G04 ================== begin FILE IDENTIFICATION RECORD ==================*
G04 Layout Name:  9127_F0T_Expander_BD_F_v02_0110_1240.brd*
G04 Film Name:    ssb*
G04 File Format:  Gerber RS274X*
G04 File Origin:  Cadence Allegro 17.2-S081*
G04 Origin Date:  Wed Jan 11 16:06:35 2023*
G04 *
G04 Layer:  DRAWING FORMAT/TITLE_BLOCK_A*
G04 Layer:  BOARD GEOMETRY/DESIGN_OUTLINE*
G04 Layer:  BOARD GEOMETRY/CUTOUT*
G04 Layer:  DRAWING FORMAT/TITLE_BLOCK*
G04 Layer:  MANUFACTURING/TP_TEXT_BOTTOM*
G04 Layer:  REF DES/SILKSCREEN_BOTTOM*
G04 Layer:  PACKAGE GEOMETRY/SILKSCREEN_BOTTOM*
G04 Layer:  MANUFACTURING/PHOTOPLOT_OUTLINE*
G04 Layer:  DRAWING FORMAT/TITLE_DATA_SSB*
G04 Layer:  BOARD GEOMETRY/SILKSCREEN_BOTTOM*
G04 *
G04 Offset:    (0.00 0.00)*
G04 Mirror:    No*
G04 Mode:      Positive*
G04 Rotation:  0*
G04 FullContactRelief:  No*
G04 UndefLineWidth:     6.00*
G04 ================== end FILE IDENTIFICATION RECORD ====================*
%FSLAX25Y25*MOIN*%
%IR0*IPPOS*OFA0.00000B0.00000*MIA0B0*SFA1.00000B1.00000*%
%ADD10C,.006*%
G75*
%LPD*%
G75*
G36*
G01X66625Y910263D02*
X64885Y908524D01*
X67341Y907896D01*
X66625Y910263D01*
G37*
G36*
G01X59347Y1737941D02*
X65347Y1740941D01*
Y1734941D01*
X59347Y1737941D01*
G37*
G36*
G01Y1783941D02*
X65347Y1786941D01*
Y1780941D01*
X59347Y1783941D01*
G37*
G36*
G01X210306Y551853D02*
X207924Y553044D01*
Y550662D01*
X210306Y551853D01*
G37*
G36*
G01X221972Y601656D02*
Y603656D01*
X224972Y602656D01*
X221972Y601656D01*
G37*
G36*
G01X226844Y632258D02*
X228579Y633125D01*
X226844Y633992D01*
Y632258D01*
G37*
G36*
G01X243306Y622635D02*
Y625095D01*
X241126Y623803D01*
X243306Y622635D01*
G37*
G36*
G01X275629Y449474D02*
X274438Y447092D01*
X276820D01*
X275629Y449474D01*
G37*
G36*
G01X305449Y1727941D02*
X299449Y1724941D01*
Y1730941D01*
X305449Y1727941D01*
G37*
G36*
G01Y1773941D02*
X299449Y1770941D01*
Y1776941D01*
X305449Y1773941D01*
G37*
G36*
G01X346111Y1761624D02*
X352111Y1764624D01*
Y1758624D01*
X346111Y1761624D01*
G37*
G36*
G01X346211Y1807624D02*
X352211Y1810624D01*
Y1804624D01*
X346211Y1807624D01*
G37*
G36*
G01X415593Y1373412D02*
X420299Y1371059D01*
Y1375765D01*
X415593Y1373412D01*
G37*
G36*
G01X428581Y1313302D02*
X433572Y1314966D01*
X430245Y1318293D01*
X428581Y1313302D01*
G37*
G36*
G01X482050Y798757D02*
Y802757D01*
X486050Y800757D01*
X482050Y798757D01*
G37*
G36*
G01X497504Y830468D02*
X494504Y831968D01*
Y828968D01*
X497504Y830468D01*
G37*
G36*
G01X496184Y844271D02*
X493184Y845771D01*
Y842771D01*
X496184Y844271D01*
G37*
G36*
G01X526886Y910713D02*
X524426D01*
X525718Y908533D01*
X526886Y910713D01*
G37*
G36*
G01X560800Y822449D02*
X559300Y819449D01*
X562300D01*
X560800Y822449D01*
G37*
G36*
G01X586060Y793348D02*
X584560Y790348D01*
X587560D01*
X586060Y793348D01*
G37*
G36*
G01X592313Y1751624D02*
X586313Y1748624D01*
Y1754624D01*
X592313Y1751624D01*
G37*
G36*
G01Y1797624D02*
X586313Y1794624D01*
Y1800624D01*
X592313Y1797624D01*
G37*
G36*
G01X632860Y1761765D02*
X638860Y1764765D01*
Y1758765D01*
X632860Y1761765D01*
G37*
G36*
G01X632474Y1808845D02*
X638474Y1811845D01*
Y1805845D01*
X632474Y1808845D01*
G37*
G36*
G01X667392Y551853D02*
X665010Y553044D01*
Y550662D01*
X667392Y551853D01*
G37*
G36*
G01X732715Y449474D02*
X731524Y447092D01*
X733906D01*
X732715Y449474D01*
G37*
G36*
G01X796484Y1009965D02*
X800484D01*
X798484Y1005965D01*
X796484Y1009965D01*
G37*
G36*
G01X878912Y1751765D02*
X872912Y1748765D01*
Y1754765D01*
X878912Y1751765D01*
G37*
G36*
G01X878526Y1798845D02*
X872526Y1795845D01*
Y1801845D01*
X878526Y1798845D01*
G37*
G36*
G01X888862Y692138D02*
X887327Y691294D01*
Y692983D01*
X888862Y692138D01*
G37*
G36*
G01X920162Y1762566D02*
X926162Y1765566D01*
Y1759566D01*
X920162Y1762566D01*
G37*
G36*
G01X920165Y1810435D02*
X926165Y1813435D01*
Y1807435D01*
X920165Y1810435D01*
G37*
G36*
G01X983972Y910713D02*
X981512D01*
X982804Y908533D01*
X983972Y910713D01*
G37*
G36*
G01X1124479Y551853D02*
X1122097Y553044D01*
Y550662D01*
X1124479Y551853D01*
G37*
G36*
G01X1159505Y766878D02*
X1161965D01*
X1160673Y769058D01*
X1159505Y766878D01*
G37*
G36*
G01X1166264Y1752566D02*
X1160264Y1749566D01*
Y1755566D01*
X1166264Y1752566D01*
G37*
G36*
G01X1166217Y1800435D02*
X1160217Y1797435D01*
Y1803435D01*
X1166217Y1800435D01*
G37*
G36*
G01X1184390Y913706D02*
X1182390Y917706D01*
X1186390D01*
X1184390Y913706D01*
G37*
G36*
G01X1189802Y449474D02*
X1188611Y447092D01*
X1190993D01*
X1189802Y449474D01*
G37*
G36*
G01X1194511Y953542D02*
X1195374Y956130D01*
X1192786Y955267D01*
X1194511Y953542D01*
G37*
G36*
G01X1441059Y910713D02*
X1438599D01*
X1439891Y908533D01*
X1441059Y910713D01*
G37*
G36*
G01X1446809Y926108D02*
Y930108D01*
X1450809Y928108D01*
X1446809Y926108D01*
G37*
G36*
G01X1462263Y957819D02*
X1459263Y959319D01*
Y956319D01*
X1462263Y957819D01*
G37*
G36*
G01X1460943Y971622D02*
X1457943Y973122D01*
Y970122D01*
X1460943Y971622D01*
G37*
G36*
G01X1518263Y878898D02*
X1521263Y877398D01*
Y880398D01*
X1518263Y878898D01*
G37*
G36*
G01X1525559Y949800D02*
X1524059Y946800D01*
X1527059D01*
X1525559Y949800D01*
G37*
G36*
G01X1581566Y551853D02*
X1579184Y553044D01*
Y550662D01*
X1581566Y551853D01*
G37*
G36*
G01X1646889Y449474D02*
X1645698Y447092D01*
X1648080D01*
X1646889Y449474D01*
G37*
G54D10*
G01X-20602Y-468335D02*
Y-543335D01*
X479398D01*
Y-468335D01*
X-20602D01*
G01X-8602Y-533335D02*
Y-538335D01*
G01X-10059Y-533335D02*
X-7145D01*
G01X-2235Y-538335D02*
X-4769D01*
Y-533335D01*
X-2235D01*
G01X-3249Y-535752D02*
X-4769D01*
G01X331Y-533335D02*
Y-538335D01*
X2865D01*
G01X6698Y-538502D02*
X6571Y-538418D01*
Y-538252D01*
X6698Y-538168D01*
X6825Y-538252D01*
Y-538418D01*
X6698Y-538502D01*
G01Y-536252D02*
X6571Y-536168D01*
Y-536002D01*
X6698Y-535918D01*
X6825Y-536002D01*
Y-536168D01*
X6698Y-536252D01*
G01X11481Y-540002D02*
X10848Y-539168D01*
X10531Y-538335D01*
Y-535002D01*
X10848Y-534168D01*
X11481Y-533335D01*
G01X16898D02*
X16391Y-533502D01*
X16011Y-533918D01*
X15758Y-534418D01*
X15568Y-535085D01*
X15505Y-535835D01*
X15568Y-536585D01*
X15758Y-537252D01*
X16011Y-537752D01*
X16391Y-538168D01*
X16898Y-538335D01*
X17405Y-538168D01*
X17785Y-537752D01*
X18038Y-537252D01*
X18228Y-536585D01*
X18291Y-535835D01*
X18228Y-535085D01*
X18038Y-534418D01*
X17785Y-533918D01*
X17405Y-533502D01*
X16898Y-533335D01*
G01X20605Y-537335D02*
X20985Y-537918D01*
X21491Y-538252D01*
X22061Y-538335D01*
X22568Y-538252D01*
X23075Y-537835D01*
X23391Y-537335D01*
X23455Y-536835D01*
X23328Y-536252D01*
X22885Y-535835D01*
X22441Y-535668D01*
X21871D01*
G01X22441D02*
X22821Y-535418D01*
X23138Y-535002D01*
X23265Y-534502D01*
X23138Y-534002D01*
X22821Y-533585D01*
X22251Y-533335D01*
X21681Y-533418D01*
X21111Y-533752D01*
G01X27415Y-540002D02*
X28048Y-539168D01*
X28365Y-538335D01*
Y-535002D01*
X28048Y-534168D01*
X27415Y-533335D01*
G01X30805Y-537335D02*
X31185Y-537918D01*
X31691Y-538252D01*
X32261Y-538335D01*
X32768Y-538252D01*
X33275Y-537835D01*
X33591Y-537335D01*
X33655Y-536835D01*
X33528Y-536252D01*
X33085Y-535835D01*
X32641Y-535668D01*
X32071D01*
G01X32641D02*
X33021Y-535418D01*
X33338Y-535002D01*
X33465Y-534502D01*
X33338Y-534002D01*
X33021Y-533585D01*
X32451Y-533335D01*
X31881Y-533418D01*
X31311Y-533752D01*
G01X36095Y-534168D02*
X36475Y-533668D01*
X36918Y-533418D01*
X37425Y-533335D01*
X38058Y-533502D01*
X38501Y-533918D01*
X38628Y-534418D01*
X38565Y-534918D01*
X38311Y-535335D01*
X37045Y-536168D01*
X36475Y-536752D01*
X36095Y-537585D01*
X35968Y-538335D01*
X38628D01*
G01X42271D02*
X42398Y-537252D01*
X42588Y-536335D01*
X42841Y-535502D01*
X43158Y-534585D01*
X43665Y-533335D01*
X41131D01*
G01X46675Y-536668D02*
X48321D01*
G01X51395Y-534168D02*
X51775Y-533668D01*
X52218Y-533418D01*
X52725Y-533335D01*
X53358Y-533502D01*
X53801Y-533918D01*
X53928Y-534418D01*
X53865Y-534918D01*
X53611Y-535335D01*
X52345Y-536168D01*
X51775Y-536752D01*
X51395Y-537585D01*
X51268Y-538335D01*
X53928D01*
G01X56305Y-537335D02*
X56685Y-537918D01*
X57191Y-538252D01*
X57761Y-538335D01*
X58268Y-538252D01*
X58775Y-537835D01*
X59091Y-537335D01*
X59155Y-536835D01*
X59028Y-536252D01*
X58585Y-535835D01*
X58141Y-535668D01*
X57571D01*
G01X58141D02*
X58521Y-535418D01*
X58838Y-535002D01*
X58965Y-534502D01*
X58838Y-534002D01*
X58521Y-533585D01*
X57951Y-533335D01*
X57381Y-533418D01*
X56811Y-533752D01*
G01X63558Y-538335D02*
Y-533335D01*
X61215Y-536918D01*
X64381D01*
G01X66505Y-537585D02*
X66885Y-538002D01*
X67328Y-538252D01*
X67898Y-538335D01*
X68468Y-538168D01*
X68911Y-537835D01*
X69228Y-537252D01*
X69291Y-536585D01*
X69165Y-535918D01*
X68848Y-535502D01*
X68405Y-535168D01*
X67961Y-535085D01*
X67518Y-535168D01*
X66948Y-535502D01*
X67138Y-533335D01*
X68848D01*
G01X76895Y-538335D02*
Y-533335D01*
X79301D01*
G01X78415Y-535752D02*
X76895D01*
G01X81615Y-538335D02*
X83198Y-533335D01*
X84781Y-538335D01*
G01X84211Y-536585D02*
X82185D01*
G01X86968Y-538335D02*
X89628Y-533335D01*
G01X86968D02*
X89628Y-538335D01*
G01X93398Y-538502D02*
X93271Y-538418D01*
Y-538252D01*
X93398Y-538168D01*
X93525Y-538252D01*
Y-538418D01*
X93398Y-538502D01*
G01Y-536252D02*
X93271Y-536168D01*
Y-536002D01*
X93398Y-535918D01*
X93525Y-536002D01*
Y-536168D01*
X93398Y-536252D01*
G01X98181Y-540002D02*
X97548Y-539168D01*
X97231Y-538335D01*
Y-535002D01*
X97548Y-534168D01*
X98181Y-533335D01*
G01X103598D02*
X103091Y-533502D01*
X102711Y-533918D01*
X102458Y-534418D01*
X102268Y-535085D01*
X102205Y-535835D01*
X102268Y-536585D01*
X102458Y-537252D01*
X102711Y-537752D01*
X103091Y-538168D01*
X103598Y-538335D01*
X104105Y-538168D01*
X104485Y-537752D01*
X104738Y-537252D01*
X104928Y-536585D01*
X104991Y-535835D01*
X104928Y-535085D01*
X104738Y-534418D01*
X104485Y-533918D01*
X104105Y-533502D01*
X103598Y-533335D01*
G01X107305Y-537335D02*
X107685Y-537918D01*
X108191Y-538252D01*
X108761Y-538335D01*
X109268Y-538252D01*
X109775Y-537835D01*
X110091Y-537335D01*
X110155Y-536835D01*
X110028Y-536252D01*
X109585Y-535835D01*
X109141Y-535668D01*
X108571D01*
G01X109141D02*
X109521Y-535418D01*
X109838Y-535002D01*
X109965Y-534502D01*
X109838Y-534002D01*
X109521Y-533585D01*
X108951Y-533335D01*
X108381Y-533418D01*
X107811Y-533752D01*
G01X114115Y-540002D02*
X114748Y-539168D01*
X115065Y-538335D01*
Y-535002D01*
X114748Y-534168D01*
X114115Y-533335D01*
G01X117505Y-537335D02*
X117885Y-537918D01*
X118391Y-538252D01*
X118961Y-538335D01*
X119468Y-538252D01*
X119975Y-537835D01*
X120291Y-537335D01*
X120355Y-536835D01*
X120228Y-536252D01*
X119785Y-535835D01*
X119341Y-535668D01*
X118771D01*
G01X119341D02*
X119721Y-535418D01*
X120038Y-535002D01*
X120165Y-534502D01*
X120038Y-534002D01*
X119721Y-533585D01*
X119151Y-533335D01*
X118581Y-533418D01*
X118011Y-533752D01*
G01X122921Y-537752D02*
X123365Y-538168D01*
X123871Y-538335D01*
X124378Y-538168D01*
X124821Y-537668D01*
X125138Y-536918D01*
X125265Y-536168D01*
Y-535252D01*
X125138Y-534502D01*
X124821Y-533835D01*
X124441Y-533502D01*
X123998Y-533335D01*
X123491Y-533502D01*
X123111Y-533835D01*
X122858Y-534335D01*
X122731Y-535002D01*
X122858Y-535585D01*
X123175Y-536168D01*
X123555Y-536502D01*
X123998Y-536585D01*
X124505Y-536418D01*
X124885Y-536002D01*
X125265Y-535252D01*
G01X128971Y-538335D02*
X129098Y-537252D01*
X129288Y-536335D01*
X129541Y-535502D01*
X129858Y-534585D01*
X130365Y-533335D01*
X127831D01*
G01X133375Y-536668D02*
X135021D01*
G01X137905Y-537335D02*
X138285Y-537918D01*
X138791Y-538252D01*
X139361Y-538335D01*
X139868Y-538252D01*
X140375Y-537835D01*
X140691Y-537335D01*
X140755Y-536835D01*
X140628Y-536252D01*
X140185Y-535835D01*
X139741Y-535668D01*
X139171D01*
G01X139741D02*
X140121Y-535418D01*
X140438Y-535002D01*
X140565Y-534502D01*
X140438Y-534002D01*
X140121Y-533585D01*
X139551Y-533335D01*
X138981Y-533418D01*
X138411Y-533752D01*
G01X143195Y-536252D02*
X143638Y-535668D01*
X144018Y-535335D01*
X144525Y-535168D01*
X144968Y-535335D01*
X145285Y-535668D01*
X145538Y-536168D01*
X145601Y-536752D01*
X145538Y-537252D01*
X145285Y-537752D01*
X144905Y-538168D01*
X144461Y-538335D01*
X143955Y-538168D01*
X143511Y-537668D01*
X143258Y-536918D01*
X143195Y-536085D01*
X143321Y-535002D01*
X143511Y-534418D01*
X143828Y-533835D01*
X144271Y-533418D01*
X144715Y-533335D01*
X145158Y-533502D01*
X145475Y-533918D01*
G01X149498Y-538335D02*
Y-533335D01*
X148738Y-534335D01*
G01Y-538335D02*
X150258D01*
G01X155358D02*
Y-533335D01*
X153015Y-536918D01*
X156181D01*
G01X795131Y1645405D02*
G03X789296Y1647992I-5835J-5287D01*
G01X7874D01*
G03X0Y1640118I0J-7874D01*
G01Y970427D01*
G03X2306Y964859I7874J0D01*
G01X12654Y954511D01*
G02X14961Y948943I-5568J-5569D01*
G01Y344836D01*
G02X12654Y339269I-7873J1D01*
G01X2306Y328920D01*
G03X0Y323353I5567J-5567D01*
G01Y7874D01*
G03X7874Y0I7874J0D01*
G01X23484D01*
G03X31358Y7874I0J7874D01*
G01Y46654D01*
G02X35295Y50591I3937J0D01*
G01X66791D01*
G02X70728Y46654I0J-3937D01*
G01Y7874D01*
G03X78602Y0I7874J0D01*
G01X125846D01*
G03X133720Y7874I0J7874D01*
G01Y46654D01*
G02X137657Y50591I3937J0D01*
G01X169154D01*
G02X173091Y46654I0J-3937D01*
G01Y7874D01*
G03X180965Y0I7874J0D01*
G01X228209D01*
G03X236083Y7874I0J7874D01*
G01Y46654D01*
G02X240020Y50591I3937J0D01*
G01X271516D01*
G02X275453Y46654I0J-3937D01*
G01Y7874D01*
G03X283327Y0I7874J0D01*
G01X330571D01*
G03X338445Y7874I0J7874D01*
G01Y46654D01*
G02X342382Y50591I3937J0D01*
G01X373878D01*
G02X377815Y46654I0J-3937D01*
G01Y7874D01*
G03X385689Y0I7874J0D01*
G01X480571D01*
G03X488445Y7874I0J7874D01*
G01Y46654D01*
G02X492382Y50591I3937J0D01*
G01X523878D01*
G02X527815Y46654I0J-3937D01*
G01Y7874D01*
G03X535689Y0I7874J0D01*
G01X582933D01*
G03X590807Y7874I0J7874D01*
G01Y46654D01*
G02X594744Y50591I3937J0D01*
G01X626240D01*
G02X630177Y46654I0J-3937D01*
G01Y7874D01*
G03X638051Y0I7874J0D01*
G01X685295D01*
G03X693169Y7874I0J7874D01*
G01Y46654D01*
G02X697106Y50591I3937J0D01*
G01X728602D01*
G02X732539Y46654I0J-3937D01*
G01Y7874D01*
G03X740413Y0I7874J0D01*
G01X787657D01*
G03X795531Y7874I0J7874D01*
G01Y46654D01*
G02X799469Y50591I3937J0D01*
G01X830965D01*
G02X834902Y46654I0J-3937D01*
G01Y7874D01*
G03X842776Y0I7874J0D01*
G01X937657D01*
G03X945531Y7874I0J7874D01*
G01Y46654D01*
G02X949469Y50591I3938J0D01*
G01X980965D01*
G02X984902Y46654I0J-3937D01*
G01Y7874D01*
G03X992776Y0I7874J0D01*
G01X1040020D01*
G03X1047894Y7874I0J7874D01*
G01Y46654D01*
G02X1051831Y50591I3937J0D01*
G01X1083327D01*
G02X1087264Y46654I0J-3937D01*
G01Y7874D01*
G03X1095138Y0I7874J0D01*
G01X1142382D01*
G03X1150256Y7874I0J7874D01*
G01Y46654D01*
G02X1154193Y50591I3937J0D01*
G01X1185689D01*
G02X1189626Y46654I0J-3937D01*
G01Y7874D01*
G03X1197500Y0I7874J0D01*
G01X1244744D01*
G03X1252618Y7874I0J7874D01*
G01Y46654D01*
G02X1256555Y50591I3937J0D01*
G01X1288051D01*
G02X1291988Y46654I0J-3937D01*
G01Y7874D01*
G03X1299862Y0I7874J0D01*
G01X1394744D01*
G03X1402618Y7874I0J7874D01*
G01Y46654D01*
G02X1406555Y50591I3937J0D01*
G01X1438051D01*
G02X1441988Y46654I0J-3937D01*
G01Y7874D01*
G03X1449862Y0I7874J0D01*
G01X1497106D01*
G03X1504980Y7874I0J7874D01*
G01Y46654D01*
G02X1508917Y50591I3937J0D01*
G01X1540413D01*
G02X1544350Y46654I0J-3937D01*
G01Y7874D01*
G03X1552224Y0I7874J0D01*
G01X1599469D01*
G03X1607343Y7874I0J7874D01*
G01Y46654D01*
G02X1611280Y50591I3937J0D01*
G01X1642776D01*
G02X1646713Y46654I0J-3937D01*
G01Y7874D01*
G03X1654587Y0I7874J0D01*
G01X1701831D01*
G03X1709705Y7874I0J7874D01*
G01Y46654D01*
G02X1713642Y50591I3937J0D01*
G01X1745138D01*
G02X1749075Y46654I0J-3937D01*
G01Y7874D01*
G03X1756949Y0I7874J0D01*
G01X1833071D01*
G03X1840945Y7874I0J7874D01*
G01Y323353D01*
G03X1838639Y328920I-7873J0D01*
G01X1828291Y339269D01*
G02X1825984Y344836I5566J5568D01*
G01Y948943D01*
G02X1828291Y954511I7875J-1D01*
G01X1838639Y964859D01*
G03X1840945Y970427I-5568J5568D01*
G01Y1640118D01*
G03X1833071Y1647992I-7874J0D01*
G01X1081727D01*
G03X1075892Y1645405I0J-7874D01*
G02X1070057Y1642819I-5834J5288D01*
G01X800966D01*
G02X795131Y1645405I-1J7874D01*
G01X7480Y1226024D02*
G02X20079I6299J0D01*
G02X7480I-6299J0D01*
G01X20472Y1573425D02*
X26772D01*
G02Y1561220I0J-6103D01*
G01X20472D01*
G02Y1573425I0J6102D01*
G01X12598Y1604724D02*
G02X34646I11024J0D01*
G02X12598I-11024J0D01*
G01X24882Y81575D02*
G02X32756I3937J0D01*
G02X24882I-3937J0D01*
G01X51181Y765197D02*
G02X73228I11023J0D01*
G02X51181I-11024J0D01*
G01X62992Y333465D02*
G02X85039I11024J0D01*
G02X62992I-11023J0D01*
G01X69370Y61614D02*
G02X77244I3937J0D01*
G02X69370I-3937J0D01*
G01X73031Y1186654D02*
G02X85630I6299J0D01*
G02X73031I-6300J0D01*
G01X91201Y70866D02*
G02X113248I11024J0D01*
G02X91201I-11023J0D01*
G01X107874Y1066535D02*
G02X125591I8859J0D01*
G02X107874I-8858J0D01*
G01Y1263386D02*
G02X125591I8859J0D01*
G02X107874I-8858J0D01*
G01X127244Y81575D02*
G02X135118I3937J0D01*
G02X127244I-3937J0D01*
G01X174398Y-468335D02*
Y-543335D01*
G01Y-518335D02*
X277398D01*
Y-493335D01*
G01X174398D02*
X277398D01*
G01X171732Y61614D02*
G02X179606I3937J0D01*
G02X171732I-3937J0D01*
G01X229606Y81575D02*
G02X237480I3937J0D01*
G02X229606I-3937J0D01*
G01X241644Y1580079D02*
G02X229144I-6250J0D01*
G02X241644I6250J0D01*
G01X241683Y1606142D02*
G02X229183I-6250J0D01*
G02X241683I6250J0D01*
G01X241644Y1626339D02*
G02X229144I-6250J0D01*
G02X241644I6250J0D01*
G01X277398Y-468335D02*
Y-543335D01*
G01X274094Y61614D02*
G02X281969I3938J0D01*
G02X274094I-3937J0D01*
G01X279398Y-468335D02*
Y-543335D01*
G01X284905Y-528335D02*
Y-523335D01*
X286171D01*
X286678Y-523585D01*
X287058Y-523918D01*
X287375Y-524418D01*
X287628Y-525002D01*
X287691Y-525835D01*
X287628Y-526668D01*
X287375Y-527252D01*
X287058Y-527752D01*
X286678Y-528085D01*
X286171Y-528335D01*
X284905D01*
G01X289815D02*
X291398Y-523335D01*
X292981Y-528335D01*
G01X292411Y-526585D02*
X290385D01*
G01X296498Y-523335D02*
Y-528335D01*
G01X295041Y-523335D02*
X297955D01*
G01X302865Y-528335D02*
X300331D01*
Y-523335D01*
X302865D01*
G01X301851Y-525752D02*
X300331D01*
G01X306698Y-528502D02*
X306571Y-528418D01*
Y-528252D01*
X306698Y-528168D01*
X306825Y-528252D01*
Y-528418D01*
X306698Y-528502D01*
G01Y-526252D02*
X306571Y-526168D01*
Y-526002D01*
X306698Y-525918D01*
X306825Y-526002D01*
Y-526168D01*
X306698Y-526252D01*
G01X279398Y-518335D02*
X479398D01*
G01X285031Y-503335D02*
Y-498335D01*
X286551D01*
X287058Y-498585D01*
X287438Y-499168D01*
X287565Y-499835D01*
X287438Y-500502D01*
X287121Y-501002D01*
X286551Y-501252D01*
X285031D01*
G01X290258Y-503502D02*
X292538Y-498335D01*
G01X295041Y-503335D02*
Y-498335D01*
X297955Y-503335D01*
Y-498335D01*
G01X301598Y-503502D02*
X301471Y-503418D01*
Y-503252D01*
X301598Y-503168D01*
X301725Y-503252D01*
Y-503418D01*
X301598Y-503502D01*
G01Y-501252D02*
X301471Y-501168D01*
Y-501002D01*
X301598Y-500918D01*
X301725Y-501002D01*
Y-501168D01*
X301598Y-501252D01*
G01X279398Y-493335D02*
X479398D01*
G01X285031Y-478335D02*
Y-473335D01*
X286551D01*
X287058Y-473585D01*
X287438Y-474168D01*
X287565Y-474835D01*
X287438Y-475502D01*
X287121Y-476002D01*
X286551Y-476252D01*
X285031D01*
G01X290131Y-478335D02*
Y-473335D01*
X291715D01*
X292221Y-473585D01*
X292538Y-473918D01*
X292665Y-474585D01*
X292538Y-475252D01*
X292158Y-475668D01*
X291715Y-475918D01*
X290131D01*
G01X291715D02*
X292665Y-478335D01*
G01X296498D02*
X295991Y-478252D01*
X295548Y-477918D01*
X295168Y-477418D01*
X294915Y-476835D01*
X294788Y-476168D01*
Y-475502D01*
X294915Y-474835D01*
X295168Y-474252D01*
X295548Y-473752D01*
X295991Y-473418D01*
X296498Y-473335D01*
X297005Y-473418D01*
X297448Y-473752D01*
X297828Y-474252D01*
X298081Y-474835D01*
X298208Y-475502D01*
Y-476168D01*
X298081Y-476835D01*
X297828Y-477418D01*
X297448Y-477918D01*
X297005Y-478252D01*
X296498Y-478335D01*
G01X300331Y-477335D02*
X300648Y-477835D01*
X301028Y-478168D01*
X301471Y-478335D01*
X301978Y-478168D01*
X302358Y-477835D01*
X302738Y-477335D01*
X302865Y-476668D01*
Y-473335D01*
G01X307965Y-478335D02*
X305431D01*
Y-473335D01*
X307965D01*
G01X306951Y-475752D02*
X305431D01*
G01X313191Y-473752D02*
X312811Y-473502D01*
X312368Y-473335D01*
X311861D01*
X311291Y-473585D01*
X310848Y-474002D01*
X310531Y-474502D01*
X310278Y-475335D01*
X310215Y-476085D01*
X310341Y-476835D01*
X310531Y-477335D01*
X310911Y-477835D01*
X311355Y-478168D01*
X311798Y-478335D01*
X312241D01*
X312685Y-478168D01*
X313065Y-477918D01*
X313381Y-477585D01*
G01X316898Y-473335D02*
Y-478335D01*
G01X315441Y-473335D02*
X318355D01*
G01X321998Y-478502D02*
X321871Y-478418D01*
Y-478252D01*
X321998Y-478168D01*
X322125Y-478252D01*
Y-478418D01*
X321998Y-478502D01*
G01Y-476252D02*
X321871Y-476168D01*
Y-476002D01*
X321998Y-475918D01*
X322125Y-476002D01*
Y-476168D01*
X321998Y-476252D01*
G01X331969Y81575D02*
G02X339843I3937J0D01*
G02X331969I-3937J0D01*
G01X344094Y1066535D02*
G02X361811I8858J0D01*
G02X344094I-8859J0D01*
G01Y1263386D02*
G02X361811I8858J0D01*
G02X344094I-8859J0D01*
G01X376457Y61614D02*
G02X384331I3937J0D01*
G02X376457I-3937J0D01*
G01X384055Y1141024D02*
G02X396654I6299J0D01*
G02X384055I-6299J0D01*
G01X394258Y-543563D02*
Y-518563D01*
G01X397031Y-520835D02*
Y-525835D01*
X399565D01*
G01X402638Y-520835D02*
X404158D01*
G01X403398D02*
Y-525835D01*
G01X402638D02*
X404158D01*
G01X409005Y-523168D02*
X409258Y-522918D01*
X409448Y-522502D01*
X409575Y-521918D01*
X409448Y-521418D01*
X409195Y-521085D01*
X408751Y-520835D01*
X407041D01*
Y-525835D01*
X409131D01*
X409575Y-525502D01*
X409828Y-525002D01*
X409955Y-524418D01*
X409828Y-523835D01*
X409448Y-523335D01*
X409005Y-523168D01*
X407041D01*
G01X413598Y-526002D02*
X413471Y-525918D01*
Y-525752D01*
X413598Y-525668D01*
X413725Y-525752D01*
Y-525918D01*
X413598Y-526002D01*
G01Y-523752D02*
X413471Y-523668D01*
Y-523502D01*
X413598Y-523418D01*
X413725Y-523502D01*
Y-523668D01*
X413598Y-523752D01*
G01X398465Y1604724D02*
G02X420512I11024J0D01*
G02X398465I-11023J0D01*
G01X422106Y70866D02*
G02X444154I11024J0D01*
G02X422106I-11024J0D01*
G01X437258Y-518563D02*
Y-543563D01*
G01X437398Y-518335D02*
Y-543335D01*
G01X441298Y-520835D02*
Y-525835D01*
G01X439841Y-520835D02*
X442755D01*
G01X446398Y-525835D02*
X446018Y-525752D01*
X445638Y-525418D01*
X445385Y-524835D01*
X445258Y-524168D01*
X445385Y-523502D01*
X445638Y-522918D01*
X446018Y-522585D01*
X446398Y-522502D01*
X446778Y-522585D01*
X447158Y-522918D01*
X447411Y-523502D01*
X447475Y-524168D01*
X447411Y-524835D01*
X447158Y-525418D01*
X446778Y-525752D01*
X446398Y-525835D01*
G01X451498D02*
X451118Y-525752D01*
X450738Y-525418D01*
X450485Y-524835D01*
X450358Y-524168D01*
X450485Y-523502D01*
X450738Y-522918D01*
X451118Y-522585D01*
X451498Y-522502D01*
X451878Y-522585D01*
X452258Y-522918D01*
X452511Y-523502D01*
X452575Y-524168D01*
X452511Y-524835D01*
X452258Y-525418D01*
X451878Y-525752D01*
X451498Y-525835D01*
G01X456598D02*
Y-520835D01*
G01X461698Y-526002D02*
X461571Y-525918D01*
Y-525752D01*
X461698Y-525668D01*
X461825Y-525752D01*
Y-525918D01*
X461698Y-526002D01*
G01Y-523752D02*
X461571Y-523668D01*
Y-523502D01*
X461698Y-523418D01*
X461825Y-523502D01*
Y-523668D01*
X461698Y-523752D01*
G01X437398Y-493335D02*
Y-518335D01*
G01X440031Y-500835D02*
Y-495835D01*
X441615D01*
X442121Y-496085D01*
X442438Y-496418D01*
X442565Y-497085D01*
X442438Y-497752D01*
X442058Y-498168D01*
X441615Y-498418D01*
X440031D01*
G01X441615D02*
X442565Y-500835D01*
G01X447665D02*
X445131D01*
Y-495835D01*
X447665D01*
G01X446651Y-498252D02*
X445131D01*
G01X449915Y-495835D02*
X451498Y-500835D01*
X453081Y-495835D01*
G01X456598Y-501002D02*
X456471Y-500918D01*
Y-500752D01*
X456598Y-500668D01*
X456725Y-500752D01*
Y-500918D01*
X456598Y-501002D01*
G01Y-498752D02*
X456471Y-498668D01*
Y-498502D01*
X456598Y-498418D01*
X456725Y-498502D01*
Y-498668D01*
X456598Y-498752D01*
G01X445411Y-546502D02*
X445518Y-546377D01*
X445598Y-546168D01*
X445651Y-545877D01*
X445598Y-545627D01*
X445491Y-545460D01*
X445305Y-545335D01*
X444585D01*
Y-547835D01*
X445465D01*
X445651Y-547668D01*
X445758Y-547418D01*
X445811Y-547127D01*
X445758Y-546835D01*
X445598Y-546585D01*
X445411Y-546502D01*
X444585D01*
G01X447878Y-547835D02*
Y-546168D01*
G01Y-546460D02*
X447771Y-546293D01*
X447611Y-546210D01*
X447425Y-546168D01*
X447238Y-546252D01*
X447078Y-546418D01*
X446971Y-546668D01*
X446918Y-547002D01*
X446971Y-547335D01*
X447078Y-547585D01*
X447238Y-547752D01*
X447425Y-547835D01*
X447611Y-547793D01*
X447771Y-547668D01*
X447878Y-547502D01*
G01X449198Y-547543D02*
X449331Y-547710D01*
X449518Y-547835D01*
X449678D01*
X449838Y-547752D01*
X449945Y-547627D01*
X449998Y-547460D01*
X449971Y-547210D01*
X449865Y-547085D01*
X449385Y-546835D01*
X449278Y-546543D01*
X449331Y-546335D01*
X449438Y-546210D01*
X449598Y-546168D01*
X449758Y-546210D01*
X449918Y-546335D01*
G01X451398Y-546710D02*
X452251D01*
X452171Y-546418D01*
X452038Y-546252D01*
X451851Y-546168D01*
X451665Y-546210D01*
X451505Y-546335D01*
X451398Y-546627D01*
X451345Y-546877D01*
Y-547127D01*
X451398Y-547377D01*
X451531Y-547627D01*
X451691Y-547793D01*
X451878Y-547835D01*
X452065Y-547752D01*
X452251Y-547502D01*
G01X453518Y-547835D02*
Y-545335D01*
G01Y-546585D02*
X453651Y-546335D01*
X453811Y-546210D01*
X453971Y-546168D01*
X454211Y-546252D01*
X454371Y-546418D01*
X454478Y-546710D01*
Y-547043D01*
X454425Y-547377D01*
X454318Y-547627D01*
X454131Y-547793D01*
X453971Y-547835D01*
X453811Y-547793D01*
X453651Y-547668D01*
X453518Y-547460D01*
G01X456198Y-547835D02*
X456038Y-547793D01*
X455878Y-547627D01*
X455771Y-547335D01*
X455718Y-547002D01*
X455771Y-546668D01*
X455878Y-546377D01*
X456038Y-546210D01*
X456198Y-546168D01*
X456358Y-546210D01*
X456518Y-546377D01*
X456625Y-546668D01*
X456651Y-547002D01*
X456625Y-547335D01*
X456518Y-547627D01*
X456358Y-547793D01*
X456198Y-547835D01*
G01X458878D02*
Y-546168D01*
G01Y-546460D02*
X458771Y-546293D01*
X458611Y-546210D01*
X458425Y-546168D01*
X458238Y-546252D01*
X458078Y-546418D01*
X457971Y-546668D01*
X457918Y-547002D01*
X457971Y-547335D01*
X458078Y-547585D01*
X458238Y-547752D01*
X458425Y-547835D01*
X458611Y-547793D01*
X458771Y-547668D01*
X458878Y-547502D01*
G01X460225Y-547835D02*
Y-546168D01*
G01Y-546502D02*
X460358Y-546335D01*
X460491Y-546210D01*
X460678Y-546168D01*
X460811Y-546210D01*
X460971Y-546335D01*
G01X463278Y-545335D02*
Y-547835D01*
G01Y-547460D02*
X463171Y-547668D01*
X463011Y-547793D01*
X462825Y-547835D01*
X462611Y-547752D01*
X462451Y-547543D01*
X462345Y-547293D01*
X462318Y-547002D01*
X462345Y-546710D01*
X462451Y-546460D01*
X462611Y-546252D01*
X462825Y-546168D01*
X463011Y-546210D01*
X463145Y-546293D01*
X463278Y-546460D01*
G01X466665Y-547835D02*
Y-545335D01*
X467331D01*
X467545Y-545460D01*
X467678Y-545627D01*
X467731Y-545960D01*
X467678Y-546293D01*
X467518Y-546502D01*
X467331Y-546627D01*
X466665D01*
G01X467331D02*
X467731Y-547835D01*
G01X468998Y-546710D02*
X469851D01*
X469771Y-546418D01*
X469638Y-546252D01*
X469451Y-546168D01*
X469265Y-546210D01*
X469105Y-546335D01*
X468998Y-546627D01*
X468945Y-546877D01*
Y-547127D01*
X468998Y-547377D01*
X469131Y-547627D01*
X469291Y-547793D01*
X469478Y-547835D01*
X469665Y-547752D01*
X469851Y-547502D01*
G01X471118Y-546168D02*
X471598Y-547835D01*
X472078Y-546168D01*
G01X473798Y-547918D02*
X473745Y-547877D01*
Y-547793D01*
X473798Y-547752D01*
X473851Y-547793D01*
Y-547877D01*
X473798Y-547918D01*
G01X475545Y-547543D02*
X475731Y-547752D01*
X475945Y-547835D01*
X476158Y-547752D01*
X476345Y-547502D01*
X476478Y-547127D01*
X476531Y-546752D01*
Y-546293D01*
X476478Y-545918D01*
X476345Y-545585D01*
X476185Y-545418D01*
X475998Y-545335D01*
X475785Y-545418D01*
X475625Y-545585D01*
X475518Y-545835D01*
X475465Y-546168D01*
X475518Y-546460D01*
X475651Y-546752D01*
X475811Y-546918D01*
X475998Y-546960D01*
X476211Y-546877D01*
X476371Y-546668D01*
X476531Y-546293D01*
G01X478411Y-546502D02*
X478518Y-546377D01*
X478598Y-546168D01*
X478651Y-545877D01*
X478598Y-545627D01*
X478491Y-545460D01*
X478305Y-545335D01*
X477585D01*
Y-547835D01*
X478465D01*
X478651Y-547668D01*
X478758Y-547418D01*
X478811Y-547127D01*
X478758Y-546835D01*
X478598Y-546585D01*
X478411Y-546502D01*
X477585D01*
G01X452362Y286220D02*
G02X474409I11023J0D01*
G02X452362I-11024J0D01*
G01Y765197D02*
G02X474409I11023J0D01*
G02X452362I-11024J0D01*
G01X481969Y81575D02*
G02X489843I3937J0D01*
G02X481969I-3937J0D01*
G01X526457Y61614D02*
G02X534331I3937J0D01*
G02X526457I-3937J0D01*
G01X530118Y1086654D02*
G02X542717I6299J0D01*
G02X530118I-6299J0D01*
G01X564961Y1066535D02*
G02X582677I8858J0D01*
G02X564961I-8858J0D01*
G01Y1263386D02*
G02X582677I8858J0D01*
G02X564961I-8858J0D01*
G01X584331Y81575D02*
G02X592205I3937J0D01*
G02X584331I-3937J0D01*
G01X588140Y1580079D02*
G02X575640I-6250J0D01*
G02X588140I6250J0D01*
G01Y1606142D02*
G02X575640I-6250J0D01*
G02X588140I6250J0D01*
G01Y1626339D02*
G02X575640I-6250J0D01*
G02X588140I6250J0D01*
G01X628819Y61614D02*
G02X636693I3937J0D01*
G02X628819I-3937J0D01*
G01X650650Y23622D02*
G02X672697I11023J0D01*
G02X650650I-11024J0D01*
G01X686693Y81575D02*
G02X694567I3937J0D01*
G02X686693I-3937J0D01*
G01X731181Y61614D02*
G02X739055I3937J0D01*
G02X731181I-3937J0D01*
G01X763780Y1490945D02*
G02X777165I6693J0D01*
G02X763780I-6692J0D01*
G01X774016Y1547638D02*
G02X796063I11024J0D01*
G02X774016I-11023J0D01*
G01X789055Y81575D02*
G02X796929I3937J0D01*
G02X789055I-3937J0D01*
G01X813386Y388583D02*
G02X826772I6693J0D01*
G02X813386I-6693J0D01*
G01X801181Y1066535D02*
G02X818898I8859J0D01*
G02X801181I-8858J0D01*
G01Y1263386D02*
G02X818898I8859J0D01*
G02X801181I-8858J0D01*
G01X833543Y61614D02*
G02X841417I3937J0D01*
G02X833543I-3937J0D01*
G01X841173Y1367717D02*
G02X857709I8268J0D01*
G02X841173I-8268J0D01*
G01X847992Y1225118D02*
G02X860591I6300J0D01*
G02X847992I-6299J0D01*
G01X879193Y23622D02*
G02X901240I11024J0D01*
G02X879193I-11023J0D01*
G01X909449Y765197D02*
G02X931496I11023J0D01*
G02X909449I-11023J0D01*
G01X939055Y81575D02*
G02X946929I3937J0D01*
G02X939055I-3937J0D01*
G01X983543Y61614D02*
G02X991417I3937J0D01*
G02X983543I-3937J0D01*
G01X987205Y1170748D02*
G02X999803I6299J0D01*
G02X987205I-6299J0D01*
G01X1014173Y388583D02*
G02X1027559I6693J0D01*
G02X1014173I-6693J0D01*
G01X1022047Y1066535D02*
G02X1039764I8859J0D01*
G02X1022047I-8858J0D01*
G01Y1263386D02*
G02X1039764I8859J0D01*
G02X1022047I-8858J0D01*
G01X1041417Y81575D02*
G02X1049291I3937J0D01*
G02X1041417I-3937J0D01*
G01X1044882Y1547638D02*
G02X1066929I11024J0D01*
G02X1044882I-11024J0D01*
G01X1063780Y1490945D02*
G02X1077165I6692J0D01*
G02X1063780I-6692J0D01*
G01X1085906Y61614D02*
G02X1093780I3937J0D01*
G02X1085906I-3937J0D01*
G01X1107736Y23622D02*
G02X1129783I11023J0D01*
G02X1107736I-11023J0D01*
G01X1143780Y81575D02*
G02X1151654I3937J0D01*
G02X1143780I-3937J0D01*
G01X1188268Y61614D02*
G02X1196142I3937J0D01*
G02X1188268I-3937J0D01*
G01X1246142Y81575D02*
G02X1254016I3937J0D01*
G02X1246142I-3937J0D01*
G01X1265305Y1580079D02*
G02X1252805I-6250J0D01*
G02X1265305I6250J0D01*
G01Y1606142D02*
G02X1252805I-6250J0D01*
G02X1265305I6250J0D01*
G01Y1626339D02*
G02X1252805I-6250J0D01*
G02X1265305I6250J0D01*
G01X1258268Y1066535D02*
G02X1275984I8858J0D01*
G02X1258268I-8858J0D01*
G01Y1263386D02*
G02X1275984I8858J0D01*
G02X1258268I-8858J0D01*
G01X1290630Y61614D02*
G02X1298504I3937J0D01*
G02X1290630I-3937J0D01*
G01X1298228Y1141024D02*
G02X1310827I6299J0D01*
G02X1298228I-6300J0D01*
G01X1336280Y70866D02*
G02X1358327I11023J0D01*
G02X1336280I-11024J0D01*
G01X1366535Y286220D02*
G02X1388583I11024J0D01*
G02X1366535I-11024J0D01*
G01Y765197D02*
G02X1388583I11024J0D01*
G02X1366535I-11024J0D01*
G01X1396142Y81575D02*
G02X1404016I3937J0D01*
G02X1396142I-3937J0D01*
G01X1420433Y1604724D02*
G02X1442480I11023J0D01*
G02X1420433I-11023J0D01*
G01X1440630Y61614D02*
G02X1448504I3937J0D01*
G02X1440630I-3937J0D01*
G01X1444291Y1086654D02*
G02X1456890I6300J0D01*
G02X1444291I-6299J0D01*
G01X1479134Y1066535D02*
G02X1496850I8858J0D01*
G02X1479134I-8858J0D01*
G01Y1263386D02*
G02X1496850I8858J0D01*
G02X1479134I-8858J0D01*
G01X1498504Y81575D02*
G02X1506378I3937J0D01*
G02X1498504I-3937J0D01*
G01X1542992Y61614D02*
G02X1550866I3937J0D01*
G02X1542992I-3937J0D01*
G01X1564823Y23622D02*
G02X1586870I11024J0D01*
G02X1564823I-11023J0D01*
G01X1600866Y81575D02*
G02X1608740I3937J0D01*
G02X1600866I-3937J0D01*
G01X1611801Y1580079D02*
G02X1599301I-6250J0D01*
G02X1611801I6250J0D01*
G01X1611762Y1606142D02*
G02X1599262I-6250J0D01*
G02X1611762I6250J0D01*
G01X1611801Y1626339D02*
G02X1599301I-6250J0D01*
G02X1611801I6250J0D01*
G01X1645354Y61614D02*
G02X1653228I3937J0D01*
G02X1645354I-3937J0D01*
G01X1703228Y81575D02*
G02X1711102I3937J0D01*
G02X1703228I-3937J0D01*
G01X1715354Y1066535D02*
G02X1733071I8859J0D01*
G02X1715354I-8858J0D01*
G01Y1263386D02*
G02X1733071I8859J0D01*
G02X1715354I-8858J0D01*
G01X1747717Y61614D02*
G02X1755591I3937J0D01*
G02X1747717I-3937J0D01*
G01X1755906Y333465D02*
G02X1777953I11023J0D01*
G02X1755906I-11023J0D01*
G01X1755315Y1215000D02*
G02X1767913I6299J0D01*
G02X1755315I-6299J0D01*
G01X1767717Y765197D02*
G02X1789764I11023J0D01*
G02X1767717I-11023J0D01*
G01X1783986Y23622D02*
G02X1806033I11023J0D01*
G02X1783986I-11023J0D01*
G01X1823425Y59843D02*
Y53543D01*
G02X1811220I-6103J0D01*
G01Y59843D01*
G02X1823425I6102J0D01*
G01X1820866Y1235630D02*
G02X1833465I6299J0D01*
G02X1820866I-6300J0D01*
G01X1811220Y1567323D02*
G02X1823425I6102J0D01*
G02X1811220I-6103J0D01*
G01X1806299Y1604724D02*
G02X1828346I11023J0D01*
G02X1806299I-11023J0D01*
G01X-1490433Y-1677216D02*
Y3837819D01*
X4496476D01*
Y-1677216D01*
X-1490433D01*
G01X-7782Y-515685D02*
X-6215D01*
Y-517575D01*
X-6685Y-518205D01*
X-7234Y-518625D01*
X-8017Y-518835D01*
X-8800Y-518625D01*
X-9349Y-518205D01*
X-9819Y-517575D01*
X-10132Y-516840D01*
X-10289Y-516000D01*
Y-515265D01*
X-10132Y-514635D01*
X-9819Y-513900D01*
X-9349Y-513270D01*
X-8879Y-512850D01*
X-8252Y-512535D01*
X-7704D01*
X-7077Y-512745D01*
X-6607Y-513165D01*
G01X-3675Y-512535D02*
Y-517050D01*
X-3362Y-517995D01*
X-2735Y-518625D01*
X-1952Y-518835D01*
X-1169Y-518625D01*
X-542Y-517995D01*
X-229Y-517050D01*
Y-512535D01*
G01X3408D02*
X5288D01*
G01X4348D02*
Y-518835D01*
G01X3408D02*
X5288D01*
G01X9003Y-517995D02*
X9630Y-518520D01*
X10335Y-518835D01*
X10961D01*
X11588Y-518520D01*
X12058Y-517995D01*
X12293Y-517260D01*
X12136Y-516525D01*
X11745Y-515895D01*
X11040Y-515475D01*
X10100Y-515265D01*
X9551Y-514845D01*
X9316Y-514110D01*
X9473Y-513375D01*
X9865Y-512850D01*
X10413Y-512535D01*
X10961D01*
X11510Y-512745D01*
X11980Y-513270D01*
G01X15303Y-518835D02*
Y-512535D01*
G01X18593D02*
Y-518835D01*
G01Y-515685D02*
X15303D01*
G01X21290Y-518835D02*
X23248Y-512535D01*
X25206Y-518835D01*
G01X24501Y-516630D02*
X21995D01*
G01X27746Y-518835D02*
Y-512535D01*
X31350Y-518835D01*
Y-512535D01*
G01X40425Y-518835D02*
Y-512535D01*
X41991D01*
X42618Y-512850D01*
X43088Y-513270D01*
X43480Y-513900D01*
X43793Y-514635D01*
X43871Y-515685D01*
X43793Y-516735D01*
X43480Y-517470D01*
X43088Y-518100D01*
X42618Y-518520D01*
X41991Y-518835D01*
X40425D01*
G01X47508Y-512535D02*
X49388D01*
G01X48448D02*
Y-518835D01*
G01X47508D02*
X49388D01*
G01X53103Y-517995D02*
X53730Y-518520D01*
X54435Y-518835D01*
X55061D01*
X55688Y-518520D01*
X56158Y-517995D01*
X56393Y-517260D01*
X56236Y-516525D01*
X55845Y-515895D01*
X55140Y-515475D01*
X54200Y-515265D01*
X53651Y-514845D01*
X53416Y-514110D01*
X53573Y-513375D01*
X53965Y-512850D01*
X54513Y-512535D01*
X55061D01*
X55610Y-512745D01*
X56080Y-513270D01*
G01X61048Y-512535D02*
Y-518835D01*
G01X59246Y-512535D02*
X62850D01*
G01X67348Y-519045D02*
X67191Y-518940D01*
Y-518730D01*
X67348Y-518625D01*
X67505Y-518730D01*
Y-518940D01*
X67348Y-519045D01*
G01X73491Y-519990D02*
X73805Y-518625D01*
G01X79948Y-512535D02*
Y-518835D01*
G01X78146Y-512535D02*
X81750D01*
G01X84290Y-518835D02*
X86248Y-512535D01*
X88206Y-518835D01*
G01X87501Y-516630D02*
X84995D01*
G01X92548Y-518835D02*
X91921Y-518730D01*
X91373Y-518310D01*
X90903Y-517680D01*
X90590Y-516945D01*
X90433Y-516105D01*
Y-515265D01*
X90590Y-514425D01*
X90903Y-513690D01*
X91373Y-513060D01*
X91921Y-512640D01*
X92548Y-512535D01*
X93175Y-512640D01*
X93723Y-513060D01*
X94193Y-513690D01*
X94506Y-514425D01*
X94663Y-515265D01*
Y-516105D01*
X94506Y-516945D01*
X94193Y-517680D01*
X93723Y-518310D01*
X93175Y-518730D01*
X92548Y-518835D01*
G01X98848D02*
Y-516000D01*
X97281Y-512535D01*
G01X100415D02*
X98848Y-516000D01*
G01X103425Y-512535D02*
Y-517050D01*
X103738Y-517995D01*
X104365Y-518625D01*
X105148Y-518835D01*
X105931Y-518625D01*
X106558Y-517995D01*
X106871Y-517050D01*
Y-512535D01*
G01X109490Y-518835D02*
X111448Y-512535D01*
X113406Y-518835D01*
G01X112701Y-516630D02*
X110195D01*
G01X115946Y-518835D02*
Y-512535D01*
X119550Y-518835D01*
Y-512535D01*
G01X-6529Y-523060D02*
X-6999Y-522745D01*
X-7547Y-522535D01*
X-8174D01*
X-8879Y-522850D01*
X-9427Y-523375D01*
X-9819Y-524005D01*
X-10132Y-525055D01*
X-10210Y-526000D01*
X-10054Y-526945D01*
X-9819Y-527575D01*
X-9349Y-528205D01*
X-8800Y-528625D01*
X-8252Y-528835D01*
X-7704D01*
X-7155Y-528625D01*
X-6685Y-528310D01*
X-6294Y-527890D01*
G01X-2892Y-522535D02*
X-1012D01*
G01X-1952D02*
Y-528835D01*
G01X-2892D02*
X-1012D01*
G01X4348Y-522535D02*
Y-528835D01*
G01X2546Y-522535D02*
X6150D01*
G01X10648Y-528835D02*
Y-526000D01*
X9081Y-522535D01*
G01X12215D02*
X10648Y-526000D01*
G01X21525Y-527575D02*
X21995Y-528310D01*
X22621Y-528730D01*
X23326Y-528835D01*
X23953Y-528730D01*
X24580Y-528205D01*
X24971Y-527575D01*
X25050Y-526945D01*
X24893Y-526210D01*
X24345Y-525685D01*
X23796Y-525475D01*
X23091D01*
G01X23796D02*
X24266Y-525160D01*
X24658Y-524635D01*
X24815Y-524005D01*
X24658Y-523375D01*
X24266Y-522850D01*
X23561Y-522535D01*
X22856Y-522640D01*
X22151Y-523060D01*
G01X27825Y-527575D02*
X28295Y-528310D01*
X28921Y-528730D01*
X29626Y-528835D01*
X30253Y-528730D01*
X30880Y-528205D01*
X31271Y-527575D01*
X31350Y-526945D01*
X31193Y-526210D01*
X30645Y-525685D01*
X30096Y-525475D01*
X29391D01*
G01X30096D02*
X30566Y-525160D01*
X30958Y-524635D01*
X31115Y-524005D01*
X30958Y-523375D01*
X30566Y-522850D01*
X29861Y-522535D01*
X29156Y-522640D01*
X28451Y-523060D01*
G01X34125Y-527575D02*
X34595Y-528310D01*
X35221Y-528730D01*
X35926Y-528835D01*
X36553Y-528730D01*
X37180Y-528205D01*
X37571Y-527575D01*
X37650Y-526945D01*
X37493Y-526210D01*
X36945Y-525685D01*
X36396Y-525475D01*
X35691D01*
G01X36396D02*
X36866Y-525160D01*
X37258Y-524635D01*
X37415Y-524005D01*
X37258Y-523375D01*
X36866Y-522850D01*
X36161Y-522535D01*
X35456Y-522640D01*
X34751Y-523060D01*
G01X41991Y-528835D02*
X42148Y-527470D01*
X42383Y-526315D01*
X42696Y-525265D01*
X43088Y-524110D01*
X43715Y-522535D01*
X40581D01*
G01X48291Y-528835D02*
X48448Y-527470D01*
X48683Y-526315D01*
X48996Y-525265D01*
X49388Y-524110D01*
X50015Y-522535D01*
X46881D01*
G01X54591Y-529990D02*
X54905Y-528625D01*
G01X61048Y-522535D02*
Y-528835D01*
G01X59246Y-522535D02*
X62850D01*
G01X65390Y-528835D02*
X67348Y-522535D01*
X69306Y-528835D01*
G01X68601Y-526630D02*
X66095D01*
G01X72708Y-522535D02*
X74588D01*
G01X73648D02*
Y-528835D01*
G01X72708D02*
X74588D01*
G01X77598Y-522535D02*
X78695Y-528835D01*
X79948Y-522535D01*
X81201Y-528835D01*
X82298Y-522535D01*
G01X84290Y-528835D02*
X86248Y-522535D01*
X88206Y-528835D01*
G01X87501Y-526630D02*
X84995D01*
G01X90746Y-528835D02*
Y-522535D01*
X94350Y-528835D01*
Y-522535D01*
G01X104756Y-530935D02*
X103973Y-529885D01*
X103581Y-528835D01*
Y-524635D01*
X103973Y-523585D01*
X104756Y-522535D01*
G01X116181Y-528835D02*
Y-522535D01*
X118140D01*
X118766Y-522850D01*
X119158Y-523270D01*
X119315Y-524110D01*
X119158Y-524950D01*
X118688Y-525475D01*
X118140Y-525790D01*
X116181D01*
G01X118140D02*
X119315Y-528835D01*
G01X124048Y-529045D02*
X123891Y-528940D01*
Y-528730D01*
X124048Y-528625D01*
X124205Y-528730D01*
Y-528940D01*
X124048Y-529045D01*
G01X130348Y-528835D02*
X129721Y-528730D01*
X129173Y-528310D01*
X128703Y-527680D01*
X128390Y-526945D01*
X128233Y-526105D01*
Y-525265D01*
X128390Y-524425D01*
X128703Y-523690D01*
X129173Y-523060D01*
X129721Y-522640D01*
X130348Y-522535D01*
X130975Y-522640D01*
X131523Y-523060D01*
X131993Y-523690D01*
X132306Y-524425D01*
X132463Y-525265D01*
Y-526105D01*
X132306Y-526945D01*
X131993Y-527680D01*
X131523Y-528310D01*
X130975Y-528730D01*
X130348Y-528835D01*
G01X136648Y-529045D02*
X136491Y-528940D01*
Y-528730D01*
X136648Y-528625D01*
X136805Y-528730D01*
Y-528940D01*
X136648Y-529045D01*
G01X144671Y-523060D02*
X144201Y-522745D01*
X143653Y-522535D01*
X143026D01*
X142321Y-522850D01*
X141773Y-523375D01*
X141381Y-524005D01*
X141068Y-525055D01*
X140990Y-526000D01*
X141146Y-526945D01*
X141381Y-527575D01*
X141851Y-528205D01*
X142400Y-528625D01*
X142948Y-528835D01*
X143496D01*
X144045Y-528625D01*
X144515Y-528310D01*
X144906Y-527890D01*
G01X149248Y-529045D02*
X149091Y-528940D01*
Y-528730D01*
X149248Y-528625D01*
X149405Y-528730D01*
Y-528940D01*
X149248Y-529045D01*
G01X155940Y-530935D02*
X156723Y-529885D01*
X157115Y-528835D01*
Y-524635D01*
X156723Y-523585D01*
X155940Y-522535D01*
G01X-10054Y-508835D02*
Y-502535D01*
X-6450Y-508835D01*
Y-502535D01*
G01X-1952Y-508835D02*
X-2579Y-508730D01*
X-3127Y-508310D01*
X-3597Y-507680D01*
X-3910Y-506945D01*
X-4067Y-506105D01*
Y-505265D01*
X-3910Y-504425D01*
X-3597Y-503690D01*
X-3127Y-503060D01*
X-2579Y-502640D01*
X-1952Y-502535D01*
X-1325Y-502640D01*
X-777Y-503060D01*
X-307Y-503690D01*
X6Y-504425D01*
X163Y-505265D01*
Y-506105D01*
X6Y-506945D01*
X-307Y-507680D01*
X-777Y-508310D01*
X-1325Y-508730D01*
X-1952Y-508835D01*
G01X4348Y-509045D02*
X4191Y-508940D01*
Y-508730D01*
X4348Y-508625D01*
X4505Y-508730D01*
Y-508940D01*
X4348Y-509045D01*
G01X9160Y-503585D02*
X9630Y-502955D01*
X10178Y-502640D01*
X10805Y-502535D01*
X11588Y-502745D01*
X12136Y-503270D01*
X12293Y-503900D01*
X12215Y-504530D01*
X11901Y-505055D01*
X10335Y-506105D01*
X9630Y-506840D01*
X9160Y-507890D01*
X9003Y-508835D01*
X12293D01*
G01X16948D02*
Y-502535D01*
X16008Y-503795D01*
G01Y-508835D02*
X17888D01*
G01X23248D02*
Y-502535D01*
X22308Y-503795D01*
G01Y-508835D02*
X24188D01*
G01X29391Y-509990D02*
X29705Y-508625D01*
G01X33498Y-502535D02*
X34595Y-508835D01*
X35848Y-502535D01*
X37101Y-508835D01*
X38198Y-502535D01*
G01X43715Y-508835D02*
X40581D01*
Y-502535D01*
X43715D01*
G01X42461Y-505580D02*
X40581D01*
G01X46646Y-508835D02*
Y-502535D01*
X50250Y-508835D01*
Y-502535D01*
G01X53103Y-508835D02*
Y-502535D01*
G01X56393D02*
Y-508835D01*
G01Y-505685D02*
X53103D01*
G01X59325Y-502535D02*
Y-507050D01*
X59638Y-507995D01*
X60265Y-508625D01*
X61048Y-508835D01*
X61831Y-508625D01*
X62458Y-507995D01*
X62771Y-507050D01*
Y-502535D01*
G01X65390Y-508835D02*
X67348Y-502535D01*
X69306Y-508835D01*
G01X68601Y-506630D02*
X66095D01*
G01X78460Y-503585D02*
X78930Y-502955D01*
X79478Y-502640D01*
X80105Y-502535D01*
X80888Y-502745D01*
X81436Y-503270D01*
X81593Y-503900D01*
X81515Y-504530D01*
X81201Y-505055D01*
X79635Y-506105D01*
X78930Y-506840D01*
X78460Y-507890D01*
X78303Y-508835D01*
X81593D01*
G01X84446D02*
Y-502535D01*
X88050Y-508835D01*
Y-502535D01*
G01X90825Y-508835D02*
Y-502535D01*
X92391D01*
X93018Y-502850D01*
X93488Y-503270D01*
X93880Y-503900D01*
X94193Y-504635D01*
X94271Y-505685D01*
X94193Y-506735D01*
X93880Y-507470D01*
X93488Y-508100D01*
X93018Y-508520D01*
X92391Y-508835D01*
X90825D01*
G01X103581D02*
Y-502535D01*
X105540D01*
X106166Y-502850D01*
X106558Y-503270D01*
X106715Y-504110D01*
X106558Y-504950D01*
X106088Y-505475D01*
X105540Y-505790D01*
X103581D01*
G01X105540D02*
X106715Y-508835D01*
G01X109725D02*
Y-502535D01*
X111291D01*
X111918Y-502850D01*
X112388Y-503270D01*
X112780Y-503900D01*
X113093Y-504635D01*
X113171Y-505685D01*
X113093Y-506735D01*
X112780Y-507470D01*
X112388Y-508100D01*
X111918Y-508520D01*
X111291Y-508835D01*
X109725D01*
G01X117748Y-509045D02*
X117591Y-508940D01*
Y-508730D01*
X117748Y-508625D01*
X117905Y-508730D01*
Y-508940D01*
X117748Y-509045D01*
G01X52739Y1373669D02*
G02I-25950J0D01*
G01X14048Y-498135D02*
X11528Y-497718D01*
X9323Y-496052D01*
X7433Y-493552D01*
X6173Y-490635D01*
X5543Y-487302D01*
Y-483968D01*
X6173Y-480635D01*
X7433Y-477718D01*
X9323Y-475219D01*
X11528Y-473552D01*
X14048Y-473135D01*
X16568Y-473552D01*
X18773Y-475219D01*
X20663Y-477718D01*
X21923Y-480635D01*
X22553Y-483968D01*
Y-487302D01*
X21923Y-490635D01*
X20663Y-493552D01*
X18773Y-496052D01*
X16568Y-497718D01*
X14048Y-498135D01*
G01X16568Y-491468D02*
X20348Y-498135D01*
G01X33893Y-481469D02*
Y-493135D01*
X35153Y-496052D01*
X37043Y-497718D01*
X39248Y-498135D01*
X41453Y-497718D01*
X43343Y-496052D01*
X44603Y-493135D01*
G01Y-498135D02*
Y-481469D01*
G01X70118Y-498135D02*
Y-481469D01*
G01Y-484385D02*
X68858Y-482719D01*
X66968Y-481885D01*
X64763Y-481469D01*
X62558Y-482302D01*
X60668Y-483968D01*
X59408Y-486469D01*
X58778Y-489802D01*
X59408Y-493135D01*
X60668Y-495636D01*
X62558Y-497302D01*
X64763Y-498135D01*
X66968Y-497718D01*
X68858Y-496469D01*
X70118Y-494802D01*
G01X84293Y-498135D02*
Y-481469D01*
G01Y-485635D02*
X85553Y-483552D01*
X87443Y-481885D01*
X89963Y-481469D01*
X92168Y-481885D01*
X94058Y-483552D01*
X95003Y-486469D01*
Y-498135D01*
G01X114848Y-473135D02*
Y-498135D01*
G01X110438Y-481469D02*
X119258D01*
G01X145718Y-498135D02*
Y-481469D01*
G01Y-484385D02*
X144458Y-482719D01*
X142568Y-481885D01*
X140363Y-481469D01*
X138158Y-482302D01*
X136268Y-483968D01*
X135008Y-486469D01*
X134378Y-489802D01*
X135008Y-493135D01*
X136268Y-495636D01*
X138158Y-497302D01*
X140363Y-498135D01*
X142568Y-497718D01*
X144458Y-496469D01*
X145718Y-494802D01*
G01X24011Y70629D02*
Y73729D01*
G01X22401D02*
Y70629D01*
G01Y72179D02*
X24011D01*
G01X20106Y70629D02*
Y73729D01*
X20566Y73109D01*
G01Y70629D02*
X19646D01*
G01X17734Y73212D02*
X17504Y73522D01*
X17236Y73677D01*
X16929Y73729D01*
X16546Y73626D01*
X16278Y73367D01*
X16201Y73057D01*
X16239Y72747D01*
X16393Y72489D01*
X17159Y71972D01*
X17504Y71611D01*
X17734Y71094D01*
X17811Y70629D01*
X16201D01*
G01X13983D02*
X13906Y71301D01*
X13791Y71869D01*
X13638Y72386D01*
X13446Y72954D01*
X13139Y73729D01*
X14673D01*
G01X13266Y1022029D02*
Y1032999D01*
G01X30968Y1022029D02*
X13266D01*
G01X11974Y1037229D02*
X32260D01*
G01X11974Y1046129D02*
Y1037229D01*
G01X13266Y1049860D02*
Y1061329D01*
G01X32260Y1046129D02*
X11974D01*
G01X17223Y1072892D02*
X7023D01*
Y1068292D01*
X17223D01*
Y1072892D01*
G01Y1067599D02*
X7023D01*
Y1062999D01*
X17223D01*
Y1067599D01*
G01X17276Y1078272D02*
X7076D01*
Y1073672D01*
X17276D01*
Y1078272D01*
G01X13266Y1061329D02*
X30968D01*
G01X17168Y1083586D02*
X6968D01*
Y1078986D01*
X17168D01*
Y1083586D01*
G01X17170Y1088827D02*
X6970D01*
Y1084227D01*
X17170D01*
Y1088827D01*
G01X17174Y1094245D02*
X6974D01*
Y1089645D01*
X17174D01*
Y1094245D01*
G01X25213Y1119633D02*
X13213D01*
G01Y1113633D02*
X25213D01*
G01X13213Y1119633D02*
Y1113633D01*
G01Y1122633D02*
X25213D01*
G01X13213Y1128633D02*
Y1122633D01*
G01X25213Y1128633D02*
X13213D01*
G01X25267Y1137705D02*
X13267D01*
G01Y1131705D02*
X25267D01*
G01X13267Y1137705D02*
Y1131705D01*
G01Y1139705D02*
X25267D01*
G01X13267Y1145705D02*
Y1139705D01*
G01X25267Y1145705D02*
X13267D01*
G01X27267Y1500569D02*
Y1506569D01*
X15267D01*
Y1500569D01*
X27267D01*
G01X7984Y1513448D02*
X14384D01*
G01X7984Y1500568D02*
X14384D01*
G01D02*
Y1513448D01*
G01X7984D02*
Y1500568D01*
G01X19637Y1510894D02*
Y1517094D01*
X16437D01*
Y1510894D01*
X19637D01*
G01X12942Y1515608D02*
X9842D01*
Y1517142D01*
G01Y1519475D02*
X12942D01*
X12322Y1519015D01*
G01X9842D02*
Y1519935D01*
G01X10307Y1521732D02*
X10049Y1521962D01*
X9894Y1522230D01*
X9842Y1522575D01*
X9945Y1522920D01*
X10152Y1523188D01*
X10514Y1523380D01*
X10927Y1523418D01*
X11340Y1523342D01*
X11599Y1523150D01*
X11805Y1522882D01*
X11857Y1522613D01*
X11805Y1522345D01*
X11599Y1522000D01*
X12942Y1522115D01*
Y1523150D01*
G01Y1525675D02*
X12839Y1525368D01*
X12580Y1525138D01*
X12270Y1524985D01*
X11857Y1524870D01*
X11392Y1524832D01*
X10927Y1524870D01*
X10514Y1524985D01*
X10204Y1525138D01*
X9945Y1525368D01*
X9842Y1525675D01*
X9945Y1525982D01*
X10204Y1526212D01*
X10514Y1526365D01*
X10927Y1526480D01*
X11392Y1526518D01*
X11857Y1526480D01*
X12270Y1526365D01*
X12580Y1526212D01*
X12839Y1525982D01*
X12942Y1525675D01*
G01X30968Y1032999D02*
Y1022029D01*
G01X52701Y1021721D02*
X34999D01*
G01D02*
Y1032999D01*
G01X32260Y1037229D02*
Y1046129D01*
G01X33707D02*
Y1037229D01*
G01D02*
X53993D01*
G01X30968Y1061329D02*
Y1049860D01*
G01X34999D02*
Y1061021D01*
G01X53993Y1046129D02*
X33707D01*
G01X34999Y1061021D02*
X52701D01*
G01X31486Y1084432D02*
X41686D01*
Y1089032D01*
X31486D01*
Y1084432D01*
G01X25213Y1113633D02*
Y1119633D01*
G01Y1122633D02*
Y1128633D01*
G01X25267Y1131705D02*
Y1137705D01*
G01Y1139705D02*
Y1145705D01*
G01X34144Y1502934D02*
Y1496734D01*
X37344D01*
Y1502934D01*
X34144D01*
G01X23137Y1510894D02*
Y1517094D01*
X19937D01*
Y1510894D01*
X23137D01*
G01X24190Y1528331D02*
X30390D01*
Y1531531D01*
X24190D01*
Y1528331D01*
G01Y1521174D02*
X30390D01*
Y1524374D01*
X24190D01*
Y1521174D01*
G01X45121Y1544820D02*
Y1541720D01*
X43587D01*
G01X41254D02*
Y1544820D01*
X41714Y1544200D01*
G01Y1541720D02*
X40794D01*
G01X38997Y1542185D02*
X38767Y1541927D01*
X38499Y1541772D01*
X38154Y1541720D01*
X37809Y1541823D01*
X37541Y1542030D01*
X37349Y1542392D01*
X37311Y1542805D01*
X37387Y1543218D01*
X37579Y1543477D01*
X37847Y1543683D01*
X38116Y1543735D01*
X38384Y1543683D01*
X38729Y1543477D01*
X38614Y1544820D01*
X37579D01*
G01X35054Y1541720D02*
Y1544820D01*
X35514Y1544200D01*
G01Y1541720D02*
X34594D01*
G01X21851Y1538823D02*
Y1532623D01*
X25051D01*
Y1538823D01*
X21851D01*
G01X47449Y846818D02*
Y840618D01*
X50649D01*
Y846818D01*
X47449D01*
G01X44937Y1062474D02*
X55137D01*
Y1067074D01*
X44937D01*
Y1062474D01*
G01X47042Y1107100D02*
X59042D01*
G01X47042Y1113100D02*
Y1107100D01*
G01X59042Y1113100D02*
X47042D01*
G01Y1116100D02*
X59042D01*
G01X47042Y1122100D02*
Y1116100D01*
G01X59042Y1122100D02*
X47042D01*
G01X47201Y1126688D02*
X59201D01*
G01X47201Y1132688D02*
Y1126688D01*
G01X59201Y1132688D02*
X47201D01*
G01Y1134688D02*
X59201D01*
G01X47201Y1140688D02*
Y1134688D01*
G01X59201Y1140688D02*
X47201D01*
G01X49846Y1503198D02*
Y1496998D01*
X53046D01*
Y1503198D01*
X49846D01*
G01X42271Y1502939D02*
Y1496739D01*
X45471D01*
Y1502939D01*
X42271D01*
G01X41079Y1526876D02*
X47079D01*
Y1538876D01*
X41079D01*
Y1526876D01*
G01X54243Y1533659D02*
X47843D01*
G01Y1546539D02*
Y1533659D01*
G01X54243Y1546539D02*
X47843D01*
G01X56348Y1722941D02*
X46348D01*
G01D02*
Y1723491D01*
G01Y1732391D02*
Y1733491D01*
G01X48893Y1747541D02*
X50503Y1744441D01*
G01X48893D02*
X50503Y1747541D01*
G01X52070Y1746249D02*
X52338Y1745888D01*
X52568Y1745681D01*
X52875Y1745578D01*
X53143Y1745681D01*
X53335Y1745888D01*
X53488Y1746198D01*
X53526Y1746559D01*
X53488Y1746869D01*
X53335Y1747179D01*
X53105Y1747438D01*
X52836Y1747541D01*
X52530Y1747438D01*
X52261Y1747128D01*
X52108Y1746663D01*
X52070Y1746146D01*
X52146Y1745474D01*
X52261Y1745113D01*
X52453Y1744751D01*
X52721Y1744493D01*
X52990Y1744441D01*
X53258Y1744544D01*
X53450Y1744803D01*
G01X55170Y1744958D02*
X55400Y1744648D01*
X55668Y1744493D01*
X55975Y1744441D01*
X56358Y1744544D01*
X56626Y1744803D01*
X56703Y1745113D01*
X56665Y1745423D01*
X56511Y1745681D01*
X55745Y1746198D01*
X55400Y1746559D01*
X55170Y1747076D01*
X55093Y1747541D01*
X56703D01*
G01X46348Y1742941D02*
X56348D01*
G01X46348Y1742391D02*
Y1742941D01*
G01X56348Y1768941D02*
X46348D01*
G01D02*
Y1769491D01*
G01Y1778391D02*
Y1779491D01*
G01Y1788941D02*
X56348D01*
G01X46348Y1788391D02*
Y1788941D01*
G01X48893Y1793541D02*
X50503Y1790441D01*
G01X48893D02*
X50503Y1793541D01*
G01X52070Y1792249D02*
X52338Y1791888D01*
X52568Y1791681D01*
X52875Y1791578D01*
X53143Y1791681D01*
X53335Y1791888D01*
X53488Y1792198D01*
X53526Y1792559D01*
X53488Y1792869D01*
X53335Y1793179D01*
X53105Y1793438D01*
X52836Y1793541D01*
X52530Y1793438D01*
X52261Y1793128D01*
X52108Y1792663D01*
X52070Y1792146D01*
X52146Y1791474D01*
X52261Y1791113D01*
X52453Y1790751D01*
X52721Y1790493D01*
X52990Y1790441D01*
X53258Y1790544D01*
X53450Y1790803D01*
G01X56358Y1793541D02*
Y1790441D01*
X54940Y1792663D01*
X56856D01*
G01X67622Y70834D02*
Y73934D01*
G01X66012D02*
Y70834D01*
G01Y72384D02*
X67622D01*
G01X63717Y70834D02*
Y73934D01*
X64177Y73314D01*
G01Y70834D02*
X63257D01*
G01X61345Y73417D02*
X61115Y73727D01*
X60847Y73882D01*
X60540Y73934D01*
X60157Y73831D01*
X59889Y73572D01*
X59812Y73262D01*
X59850Y72952D01*
X60004Y72694D01*
X60770Y72177D01*
X61115Y71816D01*
X61345Y71299D01*
X61422Y70834D01*
X59812D01*
G01X57517D02*
X57249Y70886D01*
X56942Y71041D01*
X56750Y71299D01*
X56674Y71661D01*
X56750Y72022D01*
X56980Y72332D01*
X57325Y72487D01*
X57709D01*
X57939Y72591D01*
X58130Y72849D01*
X58207Y73211D01*
X58092Y73572D01*
X57824Y73831D01*
X57517Y73934D01*
X57210Y73831D01*
X56942Y73572D01*
X56827Y73211D01*
X56904Y72849D01*
X57095Y72591D01*
X57325Y72487D01*
X57709D01*
X58054Y72332D01*
X58284Y72022D01*
X58360Y71661D01*
X58284Y71299D01*
X58092Y71041D01*
X57785Y70886D01*
X57517Y70834D01*
G01X69849Y824318D02*
X63649D01*
Y821118D01*
X69849D01*
Y824318D01*
G01X59040Y846027D02*
X65240D01*
Y849227D01*
X59040D01*
Y846027D01*
G01X67253Y875008D02*
X73453D01*
G01X67253Y878208D02*
Y875008D01*
G01X73453Y878208D02*
X67253D01*
G01X60704Y875702D02*
X57504D01*
G01X60704Y869502D02*
Y875702D01*
G01X57504Y869502D02*
X60704D01*
G01X57504Y875702D02*
Y869502D01*
G01X65345Y878542D02*
Y884742D01*
G01X62145Y878542D02*
X65345D01*
G01X62145Y884742D02*
Y878542D01*
G01X65345Y884742D02*
X62145D01*
G01X55287Y899100D02*
Y895900D01*
G01X61487D02*
Y899100D01*
G01X55287Y895900D02*
X61487D01*
G01X67978Y891833D02*
Y886833D01*
G01X70178Y894033D02*
X67978Y891833D01*
G01Y896233D02*
X70178Y894033D01*
G01X67978Y901233D02*
Y896233D01*
G01Y886833D02*
X87578Y886883D01*
G01X61487Y899100D02*
X55287D01*
G01X61487Y903900D02*
Y907100D01*
G01X55287Y903900D02*
X61487D01*
G01X55287Y907100D02*
Y903900D01*
G01X61487Y907100D02*
X55287D01*
G01X61487Y903100D02*
X55287D01*
Y899900D01*
X61487D01*
Y903100D01*
G01X87578Y901233D02*
X67978D01*
G01X52701Y1032999D02*
Y1021721D01*
G01X53993Y1037229D02*
Y1046129D01*
G01X52701Y1061021D02*
Y1049860D01*
G01X59042Y1107100D02*
Y1113100D01*
G01Y1116100D02*
Y1122100D01*
G01X59201Y1126688D02*
Y1132688D01*
G01Y1134688D02*
Y1140688D01*
G01X62381Y1210529D02*
X65581D01*
G01X62381Y1216729D02*
Y1210529D01*
G01X65581Y1216729D02*
X62381D01*
G01X65581Y1210529D02*
Y1216729D01*
G01X65607Y1217979D02*
Y1224179D01*
G01X62407Y1217979D02*
X65607D01*
G01X62407Y1224179D02*
Y1217979D01*
G01X65607Y1224179D02*
X62407D01*
G01X57393Y1510135D02*
X63593D01*
Y1513335D01*
X57393D01*
Y1510135D01*
G01X58879Y1524114D02*
X65079D01*
Y1527314D01*
X58879D01*
Y1524114D01*
G01X58903Y1516996D02*
X65103D01*
Y1520196D01*
X58903D01*
Y1516996D01*
G01X54243Y1533659D02*
Y1546539D01*
G01X58853Y1530204D02*
X65053D01*
Y1533404D01*
X58853D01*
Y1530204D01*
G01X56348Y1725441D02*
Y1722941D01*
G01Y1735441D02*
Y1730441D01*
G01Y1742941D02*
Y1740441D01*
G01Y1771441D02*
Y1768941D01*
G01Y1781441D02*
Y1776441D01*
G01Y1788941D02*
Y1786441D01*
G01X84081Y662843D02*
X90281D01*
G01X84081Y666043D02*
Y662843D01*
G01X90281Y666043D02*
X84081D01*
G01X73453Y875008D02*
Y878208D01*
G01X80565Y873259D02*
Y876459D01*
G01X74365Y873259D02*
X80565D01*
G01X74365Y876459D02*
Y873259D01*
G01X80565Y876459D02*
X74365D01*
G01X90915Y1513754D02*
X83415D01*
Y1511514D01*
X83790Y1510767D01*
X84665Y1510207D01*
X85665Y1510020D01*
X86665Y1510207D01*
X87415Y1510674D01*
X87790Y1511514D01*
Y1513754D01*
G01X90915Y1506254D02*
X83415D01*
Y1503920D01*
X83790Y1503174D01*
X84290Y1502707D01*
X85290Y1502520D01*
X86290Y1502707D01*
X86915Y1503267D01*
X87290Y1503920D01*
Y1506254D01*
G01Y1503920D02*
X90915Y1502520D01*
G01Y1495020D02*
Y1498754D01*
X83415D01*
Y1495020D01*
G01X87040Y1496514D02*
Y1498754D01*
G01X89915Y1491347D02*
X90540Y1490600D01*
X90915Y1489760D01*
Y1489014D01*
X90540Y1488267D01*
X89915Y1487707D01*
X89040Y1487427D01*
X88165Y1487614D01*
X87415Y1488080D01*
X86915Y1488920D01*
X86665Y1490040D01*
X86165Y1490694D01*
X85290Y1490974D01*
X84415Y1490787D01*
X83790Y1490320D01*
X83415Y1489667D01*
Y1489014D01*
X83665Y1488360D01*
X84290Y1487800D01*
G01X89915Y1483847D02*
X90540Y1483100D01*
X90915Y1482260D01*
Y1481514D01*
X90540Y1480767D01*
X89915Y1480207D01*
X89040Y1479927D01*
X88165Y1480114D01*
X87415Y1480580D01*
X86915Y1481420D01*
X86665Y1482540D01*
X86165Y1483194D01*
X85290Y1483474D01*
X84415Y1483287D01*
X83790Y1482820D01*
X83415Y1482167D01*
Y1481514D01*
X83665Y1480860D01*
X84290Y1480300D01*
G01X88415Y1475600D02*
Y1473174D01*
G01X90915Y1468660D02*
X83415D01*
Y1465114D01*
G01X87040Y1466420D02*
Y1468660D01*
G01X83415Y1460507D02*
Y1458267D01*
G01Y1459387D02*
X90915D01*
G01Y1460507D02*
Y1458267D01*
G01X83415Y1451887D02*
X90915D01*
G01X83415Y1454034D02*
Y1449740D01*
G01X88307Y462220D02*
Y540960D01*
G01X167047Y462220D02*
X88307D01*
G01Y540960D02*
X88479D01*
G01X88391D02*
X167047D01*
G01X90281Y662843D02*
Y666043D01*
G01X85513Y683400D02*
Y680200D01*
G01X91713Y683400D02*
X85513D01*
G01X91713Y680200D02*
Y683400D01*
G01X85513Y680200D02*
X91713D01*
G01X94189Y876794D02*
Y873594D01*
G01X100389Y876794D02*
X94189D01*
G01X100389Y873594D02*
Y876794D01*
G01X94189Y873594D02*
X100389D01*
G01X94189Y880794D02*
Y877594D01*
G01X100389D02*
Y880794D01*
G01X94189Y877594D02*
X100389D01*
G01X96562Y872914D02*
X93362D01*
G01X96562Y866714D02*
Y872914D01*
G01X93362Y866714D02*
X96562D01*
G01X93362Y872914D02*
Y866714D01*
G01X97455Y872881D02*
Y866681D01*
X100655D01*
Y872881D01*
X97455D01*
G01X100389Y880794D02*
X94189D01*
G01X96952Y895900D02*
Y902100D01*
G01X93752Y895900D02*
X96952D01*
G01X93752Y902100D02*
Y895900D01*
G01X92987D02*
Y902100D01*
G01X89787Y895900D02*
X92987D01*
G01X89787Y902100D02*
Y895900D01*
G01X98043Y888774D02*
Y894974D01*
X94843D01*
Y888774D01*
X98043D01*
G01X92008Y881942D02*
X89786D01*
X89321Y882095D01*
X89011Y882402D01*
X88908Y882785D01*
X89011Y883168D01*
X89321Y883475D01*
X89786Y883628D01*
X92008D01*
G01X90200Y885157D02*
X90561Y885425D01*
X90768Y885655D01*
X90871Y885962D01*
X90768Y886230D01*
X90561Y886422D01*
X90251Y886575D01*
X89890Y886613D01*
X89580Y886575D01*
X89270Y886422D01*
X89011Y886192D01*
X88908Y885923D01*
X89011Y885617D01*
X89321Y885348D01*
X89786Y885195D01*
X90303Y885157D01*
X90975Y885233D01*
X91336Y885348D01*
X91698Y885540D01*
X91956Y885808D01*
X92008Y886077D01*
X91905Y886345D01*
X91646Y886537D01*
G01X89373Y888142D02*
X89115Y888372D01*
X88960Y888640D01*
X88908Y888985D01*
X89011Y889330D01*
X89218Y889598D01*
X89580Y889790D01*
X89993Y889828D01*
X90406Y889752D01*
X90665Y889560D01*
X90871Y889292D01*
X90923Y889023D01*
X90871Y888755D01*
X90665Y888410D01*
X92008Y888525D01*
Y889560D01*
G01X87578Y886883D02*
Y901233D01*
G01X96952Y902100D02*
X93752D01*
G01X92987D02*
X89787D01*
G01X148227Y1066535D02*
G02I-31496J0D01*
G01X86246Y1271300D02*
G03X113923Y1232015I30484J-7915D01*
G01X102416Y1291440D02*
G03X88548Y1277445I14315J-28054D01*
G01X161886Y1425158D02*
X93150D01*
G01D02*
Y1689331D01*
G01D02*
X206142D01*
G01X113993Y894445D02*
Y891245D01*
G01X120193Y894445D02*
X113993D01*
G01Y891245D02*
X120193D01*
G01X113993Y886445D02*
Y883245D01*
G01X120193Y886445D02*
X113993D01*
G01Y883245D02*
X120193D01*
G01X113993Y887245D02*
X120193D01*
Y890445D01*
X113993D01*
Y887245D01*
G01X148059Y1266637D02*
G03X108711Y1293843I-31325J-3247D01*
G01X120193Y891245D02*
Y894445D01*
G01Y883245D02*
Y886445D01*
G01X119850Y1232044D02*
G03X137369Y1239594I-3120J31340D01*
G01X148089Y71653D02*
Y74753D01*
G01X146479D02*
Y71653D01*
G01Y73203D02*
X148089D01*
G01X144184Y71653D02*
Y74753D01*
X144644Y74133D01*
G01Y71653D02*
X143724D01*
G01X141084Y74753D02*
X141391Y74650D01*
X141621Y74391D01*
X141774Y74081D01*
X141889Y73668D01*
X141927Y73203D01*
X141889Y72738D01*
X141774Y72325D01*
X141621Y72015D01*
X141391Y71756D01*
X141084Y71653D01*
X140777Y71756D01*
X140547Y72015D01*
X140394Y72325D01*
X140279Y72738D01*
X140241Y73203D01*
X140279Y73668D01*
X140394Y74081D01*
X140547Y74391D01*
X140777Y74650D01*
X141084Y74753D01*
G01X137984Y71653D02*
X137716Y71705D01*
X137409Y71860D01*
X137217Y72118D01*
X137141Y72480D01*
X137217Y72841D01*
X137447Y73151D01*
X137792Y73306D01*
X138176D01*
X138406Y73410D01*
X138597Y73668D01*
X138674Y74030D01*
X138559Y74391D01*
X138291Y74650D01*
X137984Y74753D01*
X137677Y74650D01*
X137409Y74391D01*
X137294Y74030D01*
X137371Y73668D01*
X137562Y73410D01*
X137792Y73306D01*
X138176D01*
X138521Y73151D01*
X138751Y72841D01*
X138827Y72480D01*
X138751Y72118D01*
X138559Y71860D01*
X138252Y71705D01*
X137984Y71653D01*
G01X210801Y334492D02*
G03I-25950J0D01*
G01X164049Y1123108D02*
X174249D01*
G01X164049Y1127708D02*
Y1123108D01*
G01X174249Y1127708D02*
X164049D01*
G01X154699Y1133809D02*
X157899D01*
G01X154699Y1140009D02*
Y1133809D01*
G01X157899Y1140009D02*
X154699D01*
G01X157899Y1133809D02*
Y1140009D01*
G01X165139D02*
X161939D01*
G01X165139Y1133809D02*
Y1140009D01*
G01X161939Y1133809D02*
X165139D01*
G01X161939Y1140009D02*
Y1133809D01*
G01X158439D02*
X161639D01*
G01X158439Y1140009D02*
Y1133809D01*
G01X161639Y1140009D02*
X158439D01*
G01X161639Y1133809D02*
Y1140009D01*
G01X154605Y1150130D02*
Y1146930D01*
G01X160805Y1150130D02*
X154605D01*
G01X160805Y1146930D02*
Y1150130D01*
G01X154605Y1146930D02*
X160805D01*
G01X155064Y1166160D02*
Y1162960D01*
G01X161264Y1166160D02*
X155064D01*
G01X161264Y1162960D02*
Y1166160D01*
G01X155064Y1162960D02*
X161264D01*
G01X154849Y1162250D02*
Y1159050D01*
G01X161049Y1162250D02*
X154849D01*
G01X161049Y1159050D02*
Y1162250D01*
G01X154849Y1159050D02*
X161049D01*
G01X155064Y1170700D02*
Y1167500D01*
G01X161264Y1170700D02*
X155064D01*
G01X161264Y1167500D02*
Y1170700D01*
G01X155064Y1167500D02*
X161264D01*
G01X179211Y70834D02*
Y73934D01*
G01X177601D02*
Y70834D01*
G01Y72384D02*
X179211D01*
G01X175306Y70834D02*
Y73934D01*
X175766Y73314D01*
G01Y70834D02*
X174846D01*
G01X172206Y73934D02*
X172513Y73831D01*
X172743Y73572D01*
X172896Y73262D01*
X173011Y72849D01*
X173049Y72384D01*
X173011Y71919D01*
X172896Y71506D01*
X172743Y71196D01*
X172513Y70937D01*
X172206Y70834D01*
X171899Y70937D01*
X171669Y71196D01*
X171516Y71506D01*
X171401Y71919D01*
X171363Y72384D01*
X171401Y72849D01*
X171516Y73262D01*
X171669Y73572D01*
X171899Y73831D01*
X172206Y73934D01*
G01X169106D02*
X169413Y73831D01*
X169643Y73572D01*
X169796Y73262D01*
X169911Y72849D01*
X169949Y72384D01*
X169911Y71919D01*
X169796Y71506D01*
X169643Y71196D01*
X169413Y70937D01*
X169106Y70834D01*
X168799Y70937D01*
X168569Y71196D01*
X168416Y71506D01*
X168301Y71919D01*
X168263Y72384D01*
X168301Y72849D01*
X168416Y73262D01*
X168569Y73572D01*
X168799Y73831D01*
X169106Y73934D01*
G01X167047Y540960D02*
Y462220D01*
G01X178500Y552000D02*
Y548800D01*
G01X184700Y552000D02*
X178500D01*
G01Y548800D02*
X184700D01*
G01X178500Y556000D02*
Y552800D01*
G01D02*
X184700D01*
G01Y556000D02*
X178500D01*
G01X174249Y1123108D02*
Y1127708D01*
G01X183496Y1425158D02*
X172867D01*
G01X196798Y-509769D02*
X197598Y-510435D01*
X198498Y-510835D01*
X199298D01*
X200098Y-510435D01*
X200698Y-509769D01*
X200998Y-508835D01*
X200798Y-507902D01*
X200298Y-507102D01*
X199398Y-506568D01*
X198198Y-506302D01*
X197498Y-505768D01*
X197198Y-504835D01*
X197398Y-503902D01*
X197898Y-503235D01*
X198598Y-502835D01*
X199298D01*
X199998Y-503102D01*
X200598Y-503768D01*
G01X205698Y-502835D02*
X208098D01*
G01X206898D02*
Y-510835D01*
G01X205698D02*
X208098D01*
G01X212898Y-502835D02*
Y-510835D01*
X216898D01*
G01X220698D02*
Y-502835D01*
G01X224498D02*
X220698Y-507769D01*
G01X225098Y-510835D02*
X222398Y-505502D01*
G01X229598Y-508168D02*
X232198D01*
G01X239698Y-506568D02*
X240098Y-506168D01*
X240398Y-505502D01*
X240598Y-504568D01*
X240398Y-503768D01*
X239998Y-503235D01*
X239298Y-502835D01*
X236598D01*
Y-510835D01*
X239898D01*
X240598Y-510302D01*
X240998Y-509502D01*
X241198Y-508568D01*
X240998Y-507635D01*
X240398Y-506835D01*
X239698Y-506568D01*
X236598D01*
G01X246898Y-510835D02*
X246098Y-510702D01*
X245398Y-510168D01*
X244798Y-509368D01*
X244398Y-508435D01*
X244198Y-507368D01*
Y-506302D01*
X244398Y-505235D01*
X244798Y-504302D01*
X245398Y-503502D01*
X246098Y-502968D01*
X246898Y-502835D01*
X247698Y-502968D01*
X248398Y-503502D01*
X248998Y-504302D01*
X249398Y-505235D01*
X249598Y-506302D01*
Y-507368D01*
X249398Y-508435D01*
X248998Y-509368D01*
X248398Y-510168D01*
X247698Y-510702D01*
X246898Y-510835D01*
G01X254898Y-502835D02*
Y-510835D01*
G01X252598Y-502835D02*
X257198D01*
G01X185398Y-477835D02*
Y-485835D01*
X189398D01*
G01X197198D02*
Y-480502D01*
G01Y-481435D02*
X196798Y-480902D01*
X196198Y-480635D01*
X195498Y-480502D01*
X194798Y-480768D01*
X194198Y-481302D01*
X193798Y-482102D01*
X193598Y-483168D01*
X193798Y-484235D01*
X194198Y-485035D01*
X194798Y-485568D01*
X195498Y-485835D01*
X196198Y-485702D01*
X196798Y-485302D01*
X197198Y-484769D01*
G01X201298Y-488235D02*
X201898Y-488502D01*
X202698Y-488235D01*
X203198Y-487702D01*
X203598Y-487035D01*
X204198Y-484902D01*
X205498Y-480502D01*
G01X202298D02*
X204198Y-484902D01*
G01X209898Y-482235D02*
X213098D01*
X212798Y-481302D01*
X212298Y-480768D01*
X211598Y-480502D01*
X210898Y-480635D01*
X210298Y-481035D01*
X209898Y-481968D01*
X209698Y-482769D01*
Y-483568D01*
X209898Y-484368D01*
X210398Y-485168D01*
X210998Y-485702D01*
X211698Y-485835D01*
X212398Y-485568D01*
X213098Y-484769D01*
G01X217998Y-485835D02*
Y-480502D01*
G01Y-481568D02*
X218498Y-481035D01*
X218998Y-480635D01*
X219698Y-480502D01*
X220198Y-480635D01*
X220798Y-481035D01*
G01X195598Y254761D02*
Y333501D01*
G01X274338Y254761D02*
X195598D01*
G01Y334761D02*
X195770D01*
G01X195682Y333501D02*
X274338D01*
G01X184700Y548800D02*
Y552000D01*
G01Y552800D02*
Y556000D01*
G01X196286Y546567D02*
Y543367D01*
G01X202486Y546567D02*
X196286D01*
G01Y543367D02*
X202486D01*
G01X189286Y546567D02*
Y543367D01*
G01X195486Y546567D02*
X189286D01*
G01X195486Y543367D02*
Y546567D01*
G01X189286Y543367D02*
X195486D01*
G01X192000Y592800D02*
X198200D01*
G01X192000Y596000D02*
Y592800D01*
G01X198200Y596000D02*
X192000D01*
G01Y600800D02*
X198200D01*
G01X192000Y604000D02*
Y600800D01*
G01X198200Y604000D02*
X192000D01*
G01Y596800D02*
X198200D01*
G01X192000Y600000D02*
Y596800D01*
G01X198200Y600000D02*
X192000D01*
G01Y604800D02*
X198200D01*
G01X192000Y608000D02*
Y604800D01*
G01X198200Y608000D02*
X192000D01*
G01Y608800D02*
X198200D01*
G01X192000Y612000D02*
Y608800D01*
G01X198200Y612000D02*
X192000D01*
G01Y612800D02*
X198200D01*
G01X192000Y616000D02*
Y612800D01*
G01X198200Y616000D02*
X192000D01*
G01Y620000D02*
Y616800D01*
G01X198200Y620000D02*
X192000D01*
G01Y616800D02*
X198200D01*
G01X195298Y669567D02*
Y748307D01*
G01X274038Y669567D02*
X195298D01*
G01Y748307D02*
X195470D01*
G01X195382D02*
X274038D01*
G01X193369Y1186789D02*
Y1191389D01*
G01X183169Y1186789D02*
X193369D01*
G01X183169Y1191389D02*
Y1186789D01*
G01X193369Y1191389D02*
X183169D01*
G01X206142Y1425158D02*
X188579D01*
G01X211398Y-535835D02*
Y-532235D01*
X209398Y-527835D01*
G01X213398D02*
X211398Y-532235D01*
G01X217698Y-530502D02*
Y-534235D01*
X218098Y-535168D01*
X218698Y-535702D01*
X219398Y-535835D01*
X220098Y-535702D01*
X220698Y-535168D01*
X221098Y-534235D01*
G01Y-535835D02*
Y-530502D01*
G01X225698Y-535835D02*
Y-530502D01*
G01Y-531835D02*
X226098Y-531168D01*
X226698Y-530635D01*
X227498Y-530502D01*
X228198Y-530635D01*
X228798Y-531168D01*
X229098Y-532102D01*
Y-535835D01*
G01X237198D02*
Y-530502D01*
G01Y-531435D02*
X236798Y-530902D01*
X236198Y-530635D01*
X235498Y-530502D01*
X234798Y-530768D01*
X234198Y-531302D01*
X233798Y-532102D01*
X233598Y-533168D01*
X233798Y-534235D01*
X234198Y-535035D01*
X234798Y-535568D01*
X235498Y-535835D01*
X236198Y-535702D01*
X236798Y-535302D01*
X237198Y-534769D01*
G01X202486Y543367D02*
Y546567D01*
G01X210703Y550147D02*
Y559447D01*
G01X221303Y550147D02*
X210703D01*
G01X219261Y564083D02*
Y561861D01*
X219108Y561396D01*
X218801Y561086D01*
X218418Y560983D01*
X218035Y561086D01*
X217728Y561396D01*
X217575Y561861D01*
Y564083D01*
G01X215318Y560983D02*
X215050Y561035D01*
X214743Y561190D01*
X214551Y561448D01*
X214475Y561810D01*
X214551Y562171D01*
X214781Y562481D01*
X215126Y562636D01*
X215510D01*
X215740Y562740D01*
X215931Y562998D01*
X216008Y563360D01*
X215893Y563721D01*
X215625Y563980D01*
X215318Y564083D01*
X215011Y563980D01*
X214743Y563721D01*
X214628Y563360D01*
X214705Y562998D01*
X214896Y562740D01*
X215126Y562636D01*
X215510D01*
X215855Y562481D01*
X216085Y562171D01*
X216161Y561810D01*
X216085Y561448D01*
X215893Y561190D01*
X215586Y561035D01*
X215318Y560983D01*
G01X210703Y559547D02*
X221303D01*
G01X198200Y592800D02*
Y596000D01*
G01Y600800D02*
Y604000D01*
G01Y596800D02*
Y600000D01*
G01Y604800D02*
Y608000D01*
G01Y608800D02*
Y612000D01*
G01Y612800D02*
Y616000D01*
G01Y616800D02*
Y620000D01*
G01X206042Y1159991D02*
X216242D01*
G01X206042Y1164591D02*
Y1159991D01*
G01X216242Y1164591D02*
X206042D01*
G01X206142Y1543454D02*
Y1425158D01*
G01Y1689331D02*
Y1548722D01*
G01X229536Y90651D02*
Y93751D01*
G01X227926D02*
Y90651D01*
G01Y92201D02*
X229536D01*
G01X225631Y90651D02*
Y93751D01*
X226091Y93131D01*
G01Y90651D02*
X225171D01*
G01X222531D02*
Y93751D01*
X222991Y93131D01*
G01Y90651D02*
X222071D01*
G01X219508D02*
X219431Y91323D01*
X219316Y91891D01*
X219163Y92408D01*
X218971Y92976D01*
X218664Y93751D01*
X220198D01*
G01X218900Y534900D02*
X222100D01*
G01X218900Y541100D02*
Y534900D01*
G01X222100D02*
Y541100D01*
G01Y548600D02*
X218900D01*
G01X222100Y542400D02*
Y548600D01*
G01X218900Y542400D02*
X222100D01*
G01X218900Y548600D02*
Y542400D01*
G01X222100Y541100D02*
X218900D01*
G01X221303Y559547D02*
Y550147D01*
G01X233448Y599432D02*
Y597210D01*
X233295Y596745D01*
X232988Y596435D01*
X232605Y596332D01*
X232222Y596435D01*
X231915Y596745D01*
X231762Y597210D01*
Y599432D01*
G01X229505Y596332D02*
Y599432D01*
X229965Y598812D01*
G01Y596332D02*
X229045D01*
G01X226405Y599432D02*
X226712Y599329D01*
X226942Y599070D01*
X227095Y598760D01*
X227210Y598347D01*
X227248Y597882D01*
X227210Y597417D01*
X227095Y597004D01*
X226942Y596694D01*
X226712Y596435D01*
X226405Y596332D01*
X226098Y596435D01*
X225868Y596694D01*
X225715Y597004D01*
X225600Y597417D01*
X225562Y597882D01*
X225600Y598347D01*
X225715Y598760D01*
X225868Y599070D01*
X226098Y599329D01*
X226405Y599432D01*
G01X225724Y600983D02*
X230855D01*
G01X225724Y609447D02*
Y600983D01*
G01X238986Y609447D02*
X225724D01*
G01X224526Y613303D02*
X240726D01*
G01X224526Y626303D02*
Y613303D01*
G01X229054Y631353D02*
Y640015D01*
G01X232163Y631353D02*
X229054D01*
G01X235650Y630399D02*
Y628177D01*
X235497Y627712D01*
X235190Y627402D01*
X234807Y627299D01*
X234424Y627402D01*
X234117Y627712D01*
X233964Y628177D01*
Y630399D01*
G01X231707Y627299D02*
Y630399D01*
X232167Y629779D01*
G01Y627299D02*
X231247D01*
G01X228607D02*
Y630399D01*
X229067Y629779D01*
G01Y627299D02*
X228147D01*
G01X231126Y626303D02*
X224526D01*
G01X220825Y621798D02*
Y624998D01*
G01X214625Y621798D02*
X220825D01*
G01X214625Y624998D02*
Y621798D01*
G01X220825Y624998D02*
X214625D01*
G01X219663Y631053D02*
X222863D01*
G01X219663Y637253D02*
Y631053D01*
G01X222863D02*
Y637253D01*
G01X229054Y640015D02*
X239934D01*
G01X222863Y637253D02*
X219663D01*
G01X221003Y1159991D02*
X231203D01*
G01X221003Y1164591D02*
Y1159991D01*
G01X231203Y1164591D02*
X221003D01*
G01X216242Y1159991D02*
Y1164591D01*
G01X222352Y1212352D02*
X225552D01*
G01X222352Y1218552D02*
Y1212352D01*
G01X225552Y1218552D02*
X222352D01*
G01X225552Y1212352D02*
Y1218552D01*
G01X245609Y425429D02*
Y428629D01*
G01X239409Y425429D02*
X245609D01*
G01X239409Y428629D02*
Y425429D01*
G01X246441Y428617D02*
Y425417D01*
G01D02*
X252641D01*
G01X245609Y428629D02*
X239409D01*
G01X252641Y428617D02*
X246441D01*
G01X245609Y433429D02*
Y436629D01*
G01X239409Y433429D02*
X245609D01*
G01X239409Y436629D02*
Y433429D01*
G01X245609Y436629D02*
X239409D01*
G01X245609Y429429D02*
Y432629D01*
G01X239409Y429429D02*
X245609D01*
G01X239409Y432629D02*
Y429429D01*
G01X245609Y432629D02*
X239409D01*
G01X246409Y436629D02*
Y433429D01*
G01X252609Y436629D02*
X246409D01*
G01Y433429D02*
X252609D01*
G01X246409Y432629D02*
Y429429D01*
G01X252609Y432629D02*
X246409D01*
G01Y429429D02*
X252609D01*
G01X230855Y600983D02*
X232355Y602754D01*
G01X238986Y600983D02*
Y609447D01*
G01X233855Y600983D02*
X238986D01*
G01X232355Y602754D02*
X233855Y600983D01*
G01X245193Y597981D02*
Y604181D01*
G01X241993Y597981D02*
X245193D01*
G01X241993Y604181D02*
Y597981D01*
G01X240726Y613303D02*
Y626303D01*
G01X245193Y604181D02*
X241993D01*
G01X236825Y631353D02*
X234494Y633684D01*
G01X239934Y631353D02*
X236825D01*
G01X239934Y640015D02*
Y631353D01*
G01X234494Y633684D02*
X232163Y631353D01*
G01X232626Y623803D02*
X231126Y626303D01*
G01X234126D02*
X232626Y623803D01*
G01X240726Y626303D02*
X234126D01*
G01X245095Y631589D02*
X248295D01*
G01X245095Y637789D02*
Y631589D01*
G01X235760Y641548D02*
X236067Y641600D01*
X236335Y641806D01*
X236565Y642116D01*
X236718Y642478D01*
X236795Y642891D01*
Y643305D01*
X236718Y643718D01*
X236565Y644080D01*
X236335Y644390D01*
X236067Y644596D01*
X235760Y644648D01*
X235453Y644596D01*
X235185Y644390D01*
X234955Y644080D01*
X234802Y643718D01*
X234725Y643305D01*
Y642891D01*
X234802Y642478D01*
X234955Y642116D01*
X235185Y641806D01*
X235453Y641600D01*
X235760Y641548D01*
G01X235453Y642375D02*
X234993Y641548D01*
G01X232660D02*
Y644648D01*
X233120Y644028D01*
G01Y641548D02*
X232200D01*
G01X248295Y637789D02*
X245095D01*
G01X235244Y1121610D02*
Y1131810D01*
G01X230644Y1121610D02*
X235244D01*
G01X230644Y1131810D02*
Y1121610D01*
G01X235244Y1131810D02*
X230644D01*
G01X239704Y1159991D02*
X249904D01*
G01X239704Y1164591D02*
Y1159991D01*
G01X249904Y1164591D02*
X239704D01*
G01X231203Y1159991D02*
Y1164591D01*
G01X230616Y1197884D02*
X235216D01*
G01X230616Y1208084D02*
Y1197884D01*
G01X235216D02*
Y1208084D01*
G01D02*
X230616D01*
G01X252641Y425417D02*
Y428617D01*
G01X257044Y439923D02*
Y436723D01*
G01X263244Y439923D02*
X257044D01*
G01Y436723D02*
X263244D01*
G01X252609Y433429D02*
Y436629D01*
G01Y429429D02*
Y432629D01*
G01X259189Y463985D02*
Y461763D01*
X259036Y461298D01*
X258729Y460988D01*
X258346Y460885D01*
X257963Y460988D01*
X257656Y461298D01*
X257503Y461763D01*
Y463985D01*
G01X255246Y460885D02*
Y463985D01*
X255706Y463365D01*
G01Y460885D02*
X254786D01*
G01X252989Y461505D02*
X252759Y461143D01*
X252453Y460937D01*
X252108Y460885D01*
X251801Y460937D01*
X251494Y461195D01*
X251303Y461505D01*
X251264Y461815D01*
X251341Y462177D01*
X251609Y462435D01*
X251878Y462538D01*
X252223D01*
G01X251878D02*
X251648Y462693D01*
X251456Y462952D01*
X251379Y463262D01*
X251456Y463572D01*
X251648Y463830D01*
X251993Y463985D01*
X252338Y463933D01*
X252683Y463727D01*
G01X248295Y631589D02*
Y637789D01*
G01X249904Y1159991D02*
Y1164591D01*
G01X262764Y1507715D02*
X255264D01*
Y1505475D01*
X255639Y1504728D01*
X256514Y1504168D01*
X257514Y1503981D01*
X258514Y1504168D01*
X259264Y1504635D01*
X259639Y1505475D01*
Y1507715D01*
G01X262764Y1500215D02*
X255264D01*
Y1497881D01*
X255639Y1497135D01*
X256139Y1496668D01*
X257139Y1496481D01*
X258139Y1496668D01*
X258764Y1497228D01*
X259139Y1497881D01*
Y1500215D01*
G01Y1497881D02*
X262764Y1496481D01*
G01Y1488981D02*
Y1492715D01*
X255264D01*
Y1488981D01*
G01X258889Y1490475D02*
Y1492715D01*
G01X261764Y1485308D02*
X262389Y1484561D01*
X262764Y1483721D01*
Y1482975D01*
X262389Y1482228D01*
X261764Y1481668D01*
X260889Y1481388D01*
X260014Y1481575D01*
X259264Y1482041D01*
X258764Y1482881D01*
X258514Y1484001D01*
X258014Y1484655D01*
X257139Y1484935D01*
X256264Y1484748D01*
X255639Y1484281D01*
X255264Y1483628D01*
Y1482975D01*
X255514Y1482321D01*
X256139Y1481761D01*
G01X261764Y1477808D02*
X262389Y1477061D01*
X262764Y1476221D01*
Y1475475D01*
X262389Y1474728D01*
X261764Y1474168D01*
X260889Y1473888D01*
X260014Y1474075D01*
X259264Y1474541D01*
X258764Y1475381D01*
X258514Y1476501D01*
X258014Y1477155D01*
X257139Y1477435D01*
X256264Y1477248D01*
X255639Y1476781D01*
X255264Y1476128D01*
Y1475475D01*
X255514Y1474821D01*
X256139Y1474261D01*
G01X260264Y1469561D02*
Y1467135D01*
G01X262764Y1462621D02*
X255264D01*
Y1459075D01*
G01X258889Y1460381D02*
Y1462621D01*
G01X255264Y1454468D02*
Y1452228D01*
G01Y1453348D02*
X262764D01*
G01Y1454468D02*
Y1452228D01*
G01X255264Y1445848D02*
X262764D01*
G01X255264Y1447995D02*
Y1443701D01*
G01X274338Y333501D02*
Y254761D01*
G01X279100Y386400D02*
Y389600D01*
G01X272900Y386400D02*
X279100D01*
G01X272900Y389600D02*
Y386400D01*
G01X279100Y389600D02*
X272900D01*
G01X279100Y382900D02*
Y386100D01*
G01X272900Y382900D02*
X279100D01*
G01X272900Y386100D02*
Y382900D01*
G01X279100Y386100D02*
X272900D01*
G01X263244Y436723D02*
Y439923D01*
G01X273463Y441006D02*
Y444206D01*
G01X267263D02*
Y441006D01*
G01D02*
X273463D01*
G01Y444206D02*
X267263D01*
G01X273463Y445006D02*
Y448206D01*
G01X267263Y445006D02*
X273463D01*
G01X267263Y448206D02*
Y445006D01*
G01X273463Y448206D02*
X267263D01*
G01X277335Y449871D02*
X268035D01*
G01X277335Y460471D02*
Y449871D01*
G01X267935D02*
Y460471D01*
G01X274770Y461879D02*
Y465079D01*
G01X268570Y461879D02*
X274770D01*
G01X268570Y465079D02*
Y461879D01*
G01X274770Y465079D02*
X268570D01*
G01X277572Y468967D02*
Y465767D01*
G01X283772Y468967D02*
X277572D01*
G01Y465767D02*
X283772D01*
G01X277555Y461635D02*
X283755D01*
G01X277555Y464835D02*
Y461635D01*
G01X283755Y464835D02*
X277555D01*
G01X267935Y460471D02*
X277335D01*
G01X274038Y748307D02*
Y669567D01*
G01X266378Y1425158D02*
Y1689331D01*
G01X379370Y1425158D02*
X266378D01*
G01Y1689331D02*
X379370D01*
G01X292843Y49552D02*
Y52652D01*
G01X291233D02*
Y49552D01*
G01Y51102D02*
X292843D01*
G01X288938Y49552D02*
Y52652D01*
X289398Y52032D01*
G01Y49552D02*
X288478D01*
G01X285838D02*
Y52652D01*
X286298Y52032D01*
G01Y49552D02*
X285378D01*
G01X283466Y50844D02*
X283198Y51205D01*
X282968Y51412D01*
X282661Y51515D01*
X282393Y51412D01*
X282201Y51205D01*
X282048Y50895D01*
X282010Y50534D01*
X282048Y50224D01*
X282201Y49914D01*
X282431Y49655D01*
X282700Y49552D01*
X283006Y49655D01*
X283275Y49965D01*
X283428Y50430D01*
X283466Y50947D01*
X283390Y51619D01*
X283275Y51980D01*
X283083Y52342D01*
X282815Y52600D01*
X282546Y52652D01*
X282278Y52549D01*
X282086Y52290D01*
G01X285600Y386400D02*
Y389600D01*
G01X279400Y386400D02*
X285600D01*
G01X279400Y389600D02*
Y386400D01*
G01X285600Y389600D02*
X279400D01*
G01Y386100D02*
Y382900D01*
G01X285600Y386100D02*
X279400D01*
G01X285600Y382900D02*
Y386100D01*
G01X279400Y382900D02*
X285600D01*
G01X291571Y453552D02*
Y456752D01*
G01X285371Y453552D02*
X291571D01*
G01X285371Y456752D02*
Y453552D01*
G01X291571Y456752D02*
X285371D01*
G01X291571Y449552D02*
Y452752D01*
G01X285371Y449552D02*
X291571D01*
G01X285371Y452752D02*
Y449552D01*
G01X291571Y452752D02*
X285371D01*
G01X283772Y465767D02*
Y468967D01*
G01X283755Y461635D02*
Y464835D01*
G01X292998Y1160790D02*
X303198D01*
G01X292998Y1165390D02*
Y1160790D01*
G01X303198Y1165390D02*
X292998D01*
G01X289844Y1182431D02*
X293044D01*
G01X289844Y1188631D02*
Y1182431D01*
G01X293044Y1188631D02*
X289844D01*
G01X293044Y1182431D02*
Y1188631D01*
G01Y1181150D02*
X289844D01*
G01X293044Y1174950D02*
Y1181150D01*
G01X289844Y1174950D02*
X293044D01*
G01X289844Y1181150D02*
Y1174950D01*
G01X311998Y-529168D02*
X312598Y-528368D01*
X313298Y-527968D01*
X314098Y-527835D01*
X315098Y-528102D01*
X315798Y-528768D01*
X315998Y-529568D01*
X315898Y-530369D01*
X315498Y-531035D01*
X313498Y-532368D01*
X312598Y-533302D01*
X311998Y-534635D01*
X311798Y-535835D01*
X315998D01*
G01X321898Y-527835D02*
X321098Y-528102D01*
X320498Y-528768D01*
X320098Y-529568D01*
X319798Y-530635D01*
X319698Y-531835D01*
X319798Y-533035D01*
X320098Y-534102D01*
X320498Y-534902D01*
X321098Y-535568D01*
X321898Y-535835D01*
X322698Y-535568D01*
X323298Y-534902D01*
X323698Y-534102D01*
X323998Y-533035D01*
X324098Y-531835D01*
X323998Y-530635D01*
X323698Y-529568D01*
X323298Y-528768D01*
X322698Y-528102D01*
X321898Y-527835D01*
G01X327998Y-529168D02*
X328598Y-528368D01*
X329298Y-527968D01*
X330098Y-527835D01*
X331098Y-528102D01*
X331798Y-528768D01*
X331998Y-529568D01*
X331898Y-530369D01*
X331498Y-531035D01*
X329498Y-532368D01*
X328598Y-533302D01*
X327998Y-534635D01*
X327798Y-535835D01*
X331998D01*
G01X335698Y-534235D02*
X336298Y-535168D01*
X337098Y-535702D01*
X337998Y-535835D01*
X338798Y-535702D01*
X339598Y-535035D01*
X340098Y-534235D01*
X340198Y-533435D01*
X339998Y-532502D01*
X339298Y-531835D01*
X338598Y-531568D01*
X337698D01*
G01X338598D02*
X339198Y-531168D01*
X339698Y-530502D01*
X339898Y-529702D01*
X339698Y-528902D01*
X339198Y-528235D01*
X338298Y-527835D01*
X337398Y-527968D01*
X336498Y-528502D01*
G01X344098Y-536102D02*
X347698Y-527835D01*
G01X353898D02*
X353098Y-528102D01*
X352498Y-528768D01*
X352098Y-529568D01*
X351798Y-530635D01*
X351698Y-531835D01*
X351798Y-533035D01*
X352098Y-534102D01*
X352498Y-534902D01*
X353098Y-535568D01*
X353898Y-535835D01*
X354698Y-535568D01*
X355298Y-534902D01*
X355698Y-534102D01*
X355998Y-533035D01*
X356098Y-531835D01*
X355998Y-530635D01*
X355698Y-529568D01*
X355298Y-528768D01*
X354698Y-528102D01*
X353898Y-527835D01*
G01X361898Y-535835D02*
Y-527835D01*
X360698Y-529435D01*
G01Y-535835D02*
X363098D01*
G01X368098Y-536102D02*
X371698Y-527835D01*
G01X377898D02*
X377098Y-528102D01*
X376498Y-528768D01*
X376098Y-529568D01*
X375798Y-530635D01*
X375698Y-531835D01*
X375798Y-533035D01*
X376098Y-534102D01*
X376498Y-534902D01*
X377098Y-535568D01*
X377898Y-535835D01*
X378698Y-535568D01*
X379298Y-534902D01*
X379698Y-534102D01*
X379998Y-533035D01*
X380098Y-531835D01*
X379998Y-530635D01*
X379698Y-529568D01*
X379298Y-528768D01*
X378698Y-528102D01*
X377898Y-527835D01*
G01X384198Y-534902D02*
X384898Y-535568D01*
X385698Y-535835D01*
X386498Y-535568D01*
X387198Y-534769D01*
X387698Y-533568D01*
X387898Y-532368D01*
Y-530902D01*
X387698Y-529702D01*
X387198Y-528635D01*
X386598Y-528102D01*
X385898Y-527835D01*
X385098Y-528102D01*
X384498Y-528635D01*
X384098Y-529435D01*
X383898Y-530502D01*
X384098Y-531435D01*
X384598Y-532368D01*
X385198Y-532902D01*
X385898Y-533035D01*
X386698Y-532769D01*
X387298Y-532102D01*
X387898Y-530902D01*
G01X311698Y-510835D02*
Y-502835D01*
X313698D01*
X314498Y-503235D01*
X315098Y-503768D01*
X315598Y-504568D01*
X315998Y-505502D01*
X316098Y-506835D01*
X315998Y-508168D01*
X315598Y-509102D01*
X315098Y-509902D01*
X314498Y-510435D01*
X313698Y-510835D01*
X311698D01*
G01X319398D02*
X321898Y-502835D01*
X324398Y-510835D01*
G01X323498Y-508035D02*
X320298D01*
G01X329898Y-502835D02*
X329098Y-503102D01*
X328498Y-503768D01*
X328098Y-504568D01*
X327798Y-505635D01*
X327698Y-506835D01*
X327798Y-508035D01*
X328098Y-509102D01*
X328498Y-509902D01*
X329098Y-510568D01*
X329898Y-510835D01*
X330698Y-510568D01*
X331298Y-509902D01*
X331698Y-509102D01*
X331998Y-508035D01*
X332098Y-506835D01*
X331998Y-505635D01*
X331698Y-504568D01*
X331298Y-503768D01*
X330698Y-503102D01*
X329898Y-502835D01*
G01X335998Y-510835D02*
Y-502835D01*
X339798D01*
G01X338398Y-506702D02*
X335998D01*
G01X345898Y-502835D02*
X345098Y-503102D01*
X344498Y-503768D01*
X344098Y-504568D01*
X343798Y-505635D01*
X343698Y-506835D01*
X343798Y-508035D01*
X344098Y-509102D01*
X344498Y-509902D01*
X345098Y-510568D01*
X345898Y-510835D01*
X346698Y-510568D01*
X347298Y-509902D01*
X347698Y-509102D01*
X347998Y-508035D01*
X348098Y-506835D01*
X347998Y-505635D01*
X347698Y-504568D01*
X347298Y-503768D01*
X346698Y-503102D01*
X345898Y-502835D01*
G01X353898D02*
Y-510835D01*
G01X351598Y-502835D02*
X356198D01*
G01X363898Y-510835D02*
X359898D01*
Y-502835D01*
X363898D01*
G01X362298Y-506702D02*
X359898D01*
G01X370698Y-506568D02*
X371098Y-506168D01*
X371398Y-505502D01*
X371598Y-504568D01*
X371398Y-503768D01*
X370998Y-503235D01*
X370298Y-502835D01*
X367598D01*
Y-510835D01*
X370898D01*
X371598Y-510302D01*
X371998Y-509502D01*
X372198Y-508568D01*
X371998Y-507635D01*
X371398Y-506835D01*
X370698Y-506568D01*
X367598D01*
G01X376698Y-502835D02*
X379098D01*
G01X377898D02*
Y-510835D01*
G01X376698D02*
X379098D01*
G01X383998D02*
Y-502835D01*
X387798D01*
G01X386398Y-506702D02*
X383998D01*
G01X393898Y-502835D02*
X393098Y-503102D01*
X392498Y-503768D01*
X392098Y-504568D01*
X391798Y-505635D01*
X391698Y-506835D01*
X391798Y-508035D01*
X392098Y-509102D01*
X392498Y-509902D01*
X393098Y-510568D01*
X393898Y-510835D01*
X394698Y-510568D01*
X395298Y-509902D01*
X395698Y-509102D01*
X395998Y-508035D01*
X396098Y-506835D01*
X395998Y-505635D01*
X395698Y-504568D01*
X395298Y-503768D01*
X394698Y-503102D01*
X393898Y-502835D01*
G01X302183Y379512D02*
Y376312D01*
G01X308383D02*
Y379512D01*
G01X302183Y376312D02*
X308383D01*
G01Y379512D02*
X302183D01*
G01Y391512D02*
Y388312D01*
G01X308383Y391512D02*
X302183D01*
G01X308383Y388312D02*
Y391512D01*
G01X302183Y388312D02*
X308383D01*
G01X302183Y383512D02*
Y380312D01*
G01X308383Y383512D02*
X302183D01*
G01X308383Y380312D02*
Y383512D01*
G01X302183Y380312D02*
X308383D01*
G01X302183Y395524D02*
Y392324D01*
G01X308383D02*
Y395524D01*
G01X302183Y392324D02*
X308383D01*
G01X302183Y387512D02*
Y384312D01*
G01X308383Y387512D02*
X302183D01*
G01X308383Y384312D02*
Y387512D01*
G01X302183Y384312D02*
X308383D01*
G01Y395524D02*
X302183D01*
G01Y399512D02*
Y396312D01*
G01X308383Y399512D02*
X302183D01*
G01X308383Y396312D02*
Y399512D01*
G01X302183Y396312D02*
X308383D01*
G01X302183Y403524D02*
Y400324D01*
G01X308383Y403524D02*
X302183D01*
G01X308383Y400324D02*
Y403524D01*
G01X302183Y400324D02*
X308383D01*
G01X302183Y407524D02*
Y404324D01*
G01X308383Y407524D02*
X302183D01*
G01X308383Y404324D02*
Y407524D01*
G01X302183Y404324D02*
X308383D01*
G01X302183Y411524D02*
Y408324D01*
G01X308383D02*
Y411524D01*
G01X302183Y408324D02*
X308383D01*
G01Y411524D02*
X302183D01*
G01X304057Y453305D02*
X300857D01*
G01X304057Y447105D02*
Y453305D01*
G01X300857Y447105D02*
X304057D01*
G01X300857Y453305D02*
Y447105D01*
G01X300107Y453305D02*
X296907D01*
G01X300107Y447105D02*
Y453305D01*
G01X296907Y447105D02*
X300107D01*
G01X296907Y453305D02*
Y447105D01*
G01X302847Y462220D02*
Y540960D01*
G01X381587Y462220D02*
X302847D01*
G01Y540960D02*
X303019D01*
G01X302931D02*
X381587D01*
G01X299725Y1137549D02*
Y1143749D01*
G01X296525Y1137549D02*
X299725D01*
G01X296525Y1143749D02*
Y1137549D01*
G01X299725Y1143749D02*
X296525D01*
G01X299725Y1151229D02*
X296525D01*
G01X299725Y1145029D02*
Y1151229D01*
G01X296525Y1145029D02*
X299725D01*
G01X296525Y1151229D02*
Y1145029D01*
G01X303198Y1160790D02*
Y1165390D01*
G01X303962Y1165379D02*
Y1160779D01*
G01X314162Y1165379D02*
X303962D01*
G01Y1160779D02*
X314162D01*
G01X308093Y1721741D02*
X309703Y1718641D01*
G01X308093D02*
X309703Y1721741D01*
G01X311270Y1720449D02*
X311538Y1720088D01*
X311768Y1719881D01*
X312075Y1719778D01*
X312343Y1719881D01*
X312535Y1720088D01*
X312688Y1720398D01*
X312726Y1720759D01*
X312688Y1721069D01*
X312535Y1721379D01*
X312305Y1721638D01*
X312036Y1721741D01*
X311730Y1721638D01*
X311461Y1721328D01*
X311308Y1720863D01*
X311270Y1720346D01*
X311346Y1719674D01*
X311461Y1719313D01*
X311653Y1718951D01*
X311921Y1718693D01*
X312190Y1718641D01*
X312458Y1718744D01*
X312650Y1719003D01*
G01X314255Y1721121D02*
X314485Y1721483D01*
X314791Y1721689D01*
X315136Y1721741D01*
X315443Y1721689D01*
X315750Y1721431D01*
X315941Y1721121D01*
X315980Y1720811D01*
X315903Y1720449D01*
X315635Y1720191D01*
X315366Y1720088D01*
X315021D01*
G01X315366D02*
X315596Y1719933D01*
X315788Y1719674D01*
X315865Y1719364D01*
X315788Y1719054D01*
X315596Y1718796D01*
X315251Y1718641D01*
X314906Y1718693D01*
X314561Y1718899D01*
G01X318448Y1723491D02*
Y1722941D01*
X308448D01*
G01D02*
Y1725441D01*
G01Y1740441D02*
Y1742941D01*
X318448D01*
Y1742391D01*
G01X308448Y1730441D02*
Y1735441D01*
G01X308093Y1767741D02*
X309703Y1764641D01*
G01X308093D02*
X309703Y1767741D01*
G01X311270Y1766449D02*
X311538Y1766088D01*
X311768Y1765881D01*
X312075Y1765778D01*
X312343Y1765881D01*
X312535Y1766088D01*
X312688Y1766398D01*
X312726Y1766759D01*
X312688Y1767069D01*
X312535Y1767379D01*
X312305Y1767638D01*
X312036Y1767741D01*
X311730Y1767638D01*
X311461Y1767328D01*
X311308Y1766863D01*
X311270Y1766346D01*
X311346Y1765674D01*
X311461Y1765313D01*
X311653Y1764951D01*
X311921Y1764693D01*
X312190Y1764641D01*
X312458Y1764744D01*
X312650Y1765003D01*
G01X314255Y1767276D02*
X314485Y1767534D01*
X314753Y1767689D01*
X315098Y1767741D01*
X315443Y1767638D01*
X315711Y1767431D01*
X315903Y1767069D01*
X315941Y1766656D01*
X315865Y1766243D01*
X315673Y1765984D01*
X315405Y1765778D01*
X315136Y1765726D01*
X314868Y1765778D01*
X314523Y1765984D01*
X314638Y1764641D01*
X315673D01*
G01X318448Y1769491D02*
Y1768941D01*
X308448D01*
G01D02*
Y1771441D01*
G01Y1786441D02*
Y1788941D01*
X318448D01*
Y1788391D01*
G01X308448Y1776441D02*
Y1781441D01*
G01X329906Y91514D02*
Y94614D01*
G01X328296D02*
Y91514D01*
G01Y93064D02*
X329906D01*
G01X326001Y91514D02*
Y94614D01*
X326461Y93994D01*
G01Y91514D02*
X325541D01*
G01X322901Y94614D02*
X323208Y94511D01*
X323438Y94252D01*
X323591Y93942D01*
X323706Y93529D01*
X323744Y93064D01*
X323706Y92599D01*
X323591Y92186D01*
X323438Y91876D01*
X323208Y91617D01*
X322901Y91514D01*
X322594Y91617D01*
X322364Y91876D01*
X322211Y92186D01*
X322096Y92599D01*
X322058Y93064D01*
X322096Y93529D01*
X322211Y93942D01*
X322364Y94252D01*
X322594Y94511D01*
X322901Y94614D01*
G01X319878Y91514D02*
X319801Y92186D01*
X319686Y92754D01*
X319533Y93271D01*
X319341Y93839D01*
X319034Y94614D01*
X320568D01*
G01X321545Y1068899D02*
G03X384448Y1066535I31407J-2364D01*
G01X314162Y1160779D02*
Y1165379D01*
G01X337763Y1290977D02*
G03X321552Y1260933I15189J-27591D01*
G01X318448Y1733491D02*
Y1732391D01*
G01Y1779491D02*
Y1778391D01*
G01X329498Y-485835D02*
Y-477835D01*
X333298D01*
G01X331898Y-481702D02*
X329498D01*
G01X339398Y-477835D02*
X338598Y-478102D01*
X337998Y-478768D01*
X337598Y-479568D01*
X337298Y-480635D01*
X337198Y-481835D01*
X337298Y-483035D01*
X337598Y-484102D01*
X337998Y-484902D01*
X338598Y-485568D01*
X339398Y-485835D01*
X340198Y-485568D01*
X340798Y-484902D01*
X341198Y-484102D01*
X341498Y-483035D01*
X341598Y-481835D01*
X341498Y-480635D01*
X341198Y-479568D01*
X340798Y-478768D01*
X340198Y-478102D01*
X339398Y-477835D01*
G01X347398D02*
Y-485835D01*
G01X345098Y-477835D02*
X349698D01*
G01X352398Y-488502D02*
X358398D01*
G01X361898Y-482235D02*
X365098D01*
X364798Y-481302D01*
X364298Y-480768D01*
X363598Y-480502D01*
X362898Y-480635D01*
X362298Y-481035D01*
X361898Y-481968D01*
X361698Y-482769D01*
Y-483568D01*
X361898Y-484368D01*
X362398Y-485168D01*
X362998Y-485702D01*
X363698Y-485835D01*
X364398Y-485568D01*
X365098Y-484769D01*
G01X369898Y-480502D02*
X372898Y-485835D01*
G01Y-480502D02*
X369898Y-485835D01*
G01X377598Y-488502D02*
Y-480502D01*
G01Y-481702D02*
X378098Y-481035D01*
X378598Y-480635D01*
X379398Y-480502D01*
X380098Y-480635D01*
X380798Y-481302D01*
X381098Y-482235D01*
X381198Y-483168D01*
X381098Y-484102D01*
X380798Y-485035D01*
X380198Y-485568D01*
X379398Y-485835D01*
X378698Y-485702D01*
X377998Y-485302D01*
X377598Y-484769D01*
G01X389198Y-485835D02*
Y-480502D01*
G01Y-481435D02*
X388798Y-480902D01*
X388198Y-480635D01*
X387498Y-480502D01*
X386798Y-480768D01*
X386198Y-481302D01*
X385798Y-482102D01*
X385598Y-483168D01*
X385798Y-484235D01*
X386198Y-485035D01*
X386798Y-485568D01*
X387498Y-485835D01*
X388198Y-485702D01*
X388798Y-485302D01*
X389198Y-484769D01*
G01X393698Y-485835D02*
Y-480502D01*
G01Y-481835D02*
X394098Y-481168D01*
X394698Y-480635D01*
X395498Y-480502D01*
X396198Y-480635D01*
X396798Y-481168D01*
X397098Y-482102D01*
Y-485835D01*
G01X405198Y-477835D02*
Y-485835D01*
G01Y-484635D02*
X404798Y-485302D01*
X404198Y-485702D01*
X403498Y-485835D01*
X402698Y-485568D01*
X402098Y-484902D01*
X401698Y-484102D01*
X401598Y-483168D01*
X401698Y-482235D01*
X402098Y-481435D01*
X402698Y-480768D01*
X403498Y-480502D01*
X404198Y-480635D01*
X404698Y-480902D01*
X405198Y-481435D01*
G01X409898Y-482235D02*
X413098D01*
X412798Y-481302D01*
X412298Y-480768D01*
X411598Y-480502D01*
X410898Y-480635D01*
X410298Y-481035D01*
X409898Y-481968D01*
X409698Y-482769D01*
Y-483568D01*
X409898Y-484368D01*
X410398Y-485168D01*
X410998Y-485702D01*
X411698Y-485835D01*
X412398Y-485568D01*
X413098Y-484769D01*
G01X417998Y-485835D02*
Y-480502D01*
G01Y-481568D02*
X418498Y-481035D01*
X418998Y-480635D01*
X419698Y-480502D01*
X420198Y-480635D01*
X420798Y-481035D01*
G01X424398Y-488502D02*
X430398D01*
G01X433598Y-485835D02*
Y-477835D01*
G01Y-481835D02*
X434098Y-481035D01*
X434698Y-480635D01*
X435298Y-480502D01*
X436198Y-480768D01*
X436798Y-481302D01*
X437198Y-482235D01*
Y-483302D01*
X436998Y-484368D01*
X436598Y-485168D01*
X435898Y-485702D01*
X435298Y-485835D01*
X434698Y-485702D01*
X434098Y-485302D01*
X433598Y-484635D01*
G01X445198Y-477835D02*
Y-485835D01*
G01Y-484635D02*
X444798Y-485302D01*
X444198Y-485702D01*
X443498Y-485835D01*
X442698Y-485568D01*
X442098Y-484902D01*
X441698Y-484102D01*
X441598Y-483168D01*
X441698Y-482235D01*
X442098Y-481435D01*
X442698Y-480768D01*
X443498Y-480502D01*
X444198Y-480635D01*
X444698Y-480902D01*
X445198Y-481435D01*
G01X384448Y1066535D02*
G03X331521Y1089616I-31496J0D01*
G01X332453Y1239474D02*
G03X384448Y1263386I20499J23912D01*
G01X343112Y1749124D02*
Y1746624D01*
X333112D01*
Y1747174D01*
G01Y1756074D02*
Y1757174D01*
G01X343112Y1759124D02*
Y1754124D01*
G01X343467Y1767824D02*
X341857Y1770924D01*
G01X343467D02*
X341857Y1767824D01*
G01X340405Y1768289D02*
X340175Y1768031D01*
X339907Y1767876D01*
X339562Y1767824D01*
X339217Y1767927D01*
X338949Y1768134D01*
X338757Y1768496D01*
X338719Y1768909D01*
X338795Y1769322D01*
X338987Y1769581D01*
X339255Y1769787D01*
X339524Y1769839D01*
X339792Y1769787D01*
X340137Y1769581D01*
X340022Y1770924D01*
X338987D01*
G01X336539Y1767824D02*
X336462Y1768496D01*
X336347Y1769064D01*
X336194Y1769581D01*
X336002Y1770149D01*
X335695Y1770924D01*
X337229D01*
G01X333112Y1766074D02*
Y1766624D01*
X343112D01*
G01D02*
Y1764124D01*
G01X343212Y1795124D02*
Y1792624D01*
X333212D01*
Y1793174D01*
G01Y1802074D02*
Y1803174D01*
G01X343212Y1805124D02*
Y1800124D01*
G01X343567Y1813824D02*
X341957Y1816924D01*
G01X343567D02*
X341957Y1813824D01*
G01X340390Y1816407D02*
X340160Y1816717D01*
X339892Y1816872D01*
X339585Y1816924D01*
X339202Y1816821D01*
X338934Y1816562D01*
X338857Y1816252D01*
X338895Y1815942D01*
X339049Y1815684D01*
X339815Y1815167D01*
X340160Y1814806D01*
X340390Y1814289D01*
X340467Y1813824D01*
X338857D01*
G01X337290Y1815116D02*
X337022Y1815477D01*
X336792Y1815684D01*
X336485Y1815787D01*
X336217Y1815684D01*
X336025Y1815477D01*
X335872Y1815167D01*
X335834Y1814806D01*
X335872Y1814496D01*
X336025Y1814186D01*
X336255Y1813927D01*
X336524Y1813824D01*
X336830Y1813927D01*
X337099Y1814237D01*
X337252Y1814702D01*
X337290Y1815219D01*
X337214Y1815891D01*
X337099Y1816252D01*
X336907Y1816614D01*
X336639Y1816872D01*
X336370Y1816924D01*
X336102Y1816821D01*
X335910Y1816562D01*
G01X333212Y1812074D02*
Y1812624D01*
X343212D01*
G01D02*
Y1810124D01*
G01X360144Y1294049D02*
G03X345832Y1294066I-7192J-30663D01*
G01X384448Y1263386D02*
G03X368712Y1290655I-31495J0D01*
G01X394980Y50804D02*
Y53904D01*
G01X393370D02*
Y50804D01*
G01Y52354D02*
X394980D01*
G01X391075Y50804D02*
Y53904D01*
X391535Y53284D01*
G01Y50804D02*
X390615D01*
G01X387975D02*
Y53904D01*
X388435Y53284D01*
G01Y50804D02*
X387515D01*
G01X384875D02*
X384607Y50856D01*
X384300Y51011D01*
X384108Y51269D01*
X384032Y51631D01*
X384108Y51992D01*
X384338Y52302D01*
X384683Y52457D01*
X385067D01*
X385297Y52561D01*
X385488Y52819D01*
X385565Y53181D01*
X385450Y53542D01*
X385182Y53801D01*
X384875Y53904D01*
X384568Y53801D01*
X384300Y53542D01*
X384185Y53181D01*
X384262Y52819D01*
X384453Y52561D01*
X384683Y52457D01*
X385067D01*
X385412Y52302D01*
X385642Y51992D01*
X385718Y51631D01*
X385642Y51269D01*
X385450Y51011D01*
X385143Y50856D01*
X384875Y50804D01*
G01X381587Y540960D02*
Y462220D01*
G01X391211Y1300875D02*
Y1297675D01*
G01X397411Y1300875D02*
X391211D01*
G01Y1297675D02*
X397411D01*
G01X391211Y1304875D02*
Y1301675D01*
G01D02*
X397411D01*
G01X388991Y1318445D02*
X401871D01*
G01X388991D02*
Y1324845D01*
G01X397411Y1304875D02*
X391211D01*
G01X388055Y1312889D02*
Y1309689D01*
G01X394255Y1312889D02*
X388055D01*
G01Y1309689D02*
X394255D01*
G01X388055Y1316889D02*
Y1313689D01*
G01X394255Y1316889D02*
X388055D01*
G01Y1313689D02*
X394255D01*
G01X401871Y1324845D02*
X388991D01*
G01X390157Y1382550D02*
Y1376350D01*
X393357D01*
Y1382550D01*
X390157D01*
G01X383878Y1383122D02*
X390078D01*
Y1386322D01*
X383878D01*
Y1383122D01*
G01X396996Y1375525D02*
Y1373303D01*
X396843Y1372838D01*
X396536Y1372528D01*
X396153Y1372425D01*
X395770Y1372528D01*
X395463Y1372838D01*
X395310Y1373303D01*
Y1375525D01*
G01X392593Y1372425D02*
Y1375525D01*
X394011Y1373303D01*
X392095D01*
G01X390681Y1375008D02*
X390451Y1375318D01*
X390183Y1375473D01*
X389876Y1375525D01*
X389493Y1375422D01*
X389225Y1375163D01*
X389148Y1374853D01*
X389186Y1374543D01*
X389340Y1374285D01*
X390106Y1373768D01*
X390451Y1373407D01*
X390681Y1372890D01*
X390758Y1372425D01*
X389148D01*
G01X386393D02*
Y1375525D01*
X387811Y1373303D01*
X385895D01*
G01X397175Y1408889D02*
X391175D01*
Y1396889D01*
X397175D01*
Y1408889D01*
G01X393377Y1394191D02*
X387177D01*
Y1390991D01*
X393377D01*
Y1394191D01*
G01X383878Y1387122D02*
X390078D01*
Y1390322D01*
X383878D01*
Y1387122D01*
G01X379370Y1512913D02*
Y1425158D01*
G01X392475Y1480639D02*
Y1483839D01*
G01X386275Y1480639D02*
X392475D01*
G01X386275Y1483839D02*
Y1480639D01*
G01X386882Y1484178D02*
X393082D01*
G01X386882Y1487378D02*
Y1484178D01*
G01X393082Y1487378D02*
X386882D01*
G01X392475Y1483839D02*
X386275D01*
G01X379370Y1519035D02*
Y1516067D01*
G01Y1689331D02*
Y1525824D01*
G01X400398Y-538835D02*
Y-530835D01*
X399198Y-532435D01*
G01Y-538835D02*
X401598D01*
G01X406498Y-535502D02*
X407198Y-534568D01*
X407798Y-534035D01*
X408598Y-533768D01*
X409298Y-534035D01*
X409798Y-534568D01*
X410198Y-535368D01*
X410298Y-536302D01*
X410198Y-537102D01*
X409798Y-537902D01*
X409198Y-538568D01*
X408498Y-538835D01*
X407698Y-538568D01*
X406998Y-537769D01*
X406598Y-536568D01*
X406498Y-535235D01*
X406698Y-533502D01*
X406998Y-532568D01*
X407498Y-531635D01*
X408198Y-530968D01*
X408898Y-530835D01*
X409598Y-531102D01*
X410098Y-531768D01*
G01X416398Y-539102D02*
X416198Y-538968D01*
Y-538702D01*
X416398Y-538568D01*
X416598Y-538702D01*
Y-538968D01*
X416398Y-539102D01*
G01X422498Y-535502D02*
X423198Y-534568D01*
X423798Y-534035D01*
X424598Y-533768D01*
X425298Y-534035D01*
X425798Y-534568D01*
X426198Y-535368D01*
X426298Y-536302D01*
X426198Y-537102D01*
X425798Y-537902D01*
X425198Y-538568D01*
X424498Y-538835D01*
X423698Y-538568D01*
X422998Y-537769D01*
X422598Y-536568D01*
X422498Y-535235D01*
X422698Y-533502D01*
X422998Y-532568D01*
X423498Y-531635D01*
X424198Y-530968D01*
X424898Y-530835D01*
X425598Y-531102D01*
X426098Y-531768D01*
G01X402634Y326479D02*
Y316479D01*
G01X407234D02*
Y326479D01*
G01X407134Y316479D02*
X407234D01*
G01X402634Y326479D02*
X407234D01*
G01X402634Y316479D02*
X407234D01*
G01X407955Y327985D02*
Y315985D01*
G01X413955Y327985D02*
X407955D01*
G01Y315985D02*
X413955D01*
G01X408121Y928278D02*
Y940278D01*
G01X402121Y928278D02*
X408121D01*
G01X402121Y940278D02*
Y928278D01*
G01X400121D02*
Y940278D01*
G01X394121Y928278D02*
X400121D01*
G01X394121Y940278D02*
Y928278D01*
G01X408121Y940278D02*
X402121D01*
G01X400121D02*
X394121D01*
G01X395690Y1096068D02*
Y1090068D01*
X407690D01*
Y1096068D01*
X395690D01*
G01X395684Y1088881D02*
Y1082881D01*
X407684D01*
Y1088881D01*
X395684D01*
G01X408095Y1112397D02*
Y1100397D01*
G01D02*
X414095D01*
G01Y1112397D02*
X408095D01*
G01X408231Y1115247D02*
Y1127247D01*
G01X402231Y1115247D02*
X408231D01*
G01X402231Y1127247D02*
Y1115247D01*
G01X408231Y1127247D02*
X402231D01*
G01X394869Y1249202D02*
Y1266904D01*
G01X406456Y1249202D02*
X394869D01*
G01Y1266904D02*
X406456D01*
G01X406568Y1294261D02*
X394568D01*
G01X406568Y1288261D02*
Y1294261D01*
G01X394568Y1288261D02*
X406568D01*
G01X394568Y1294261D02*
Y1288261D01*
G01X404739Y1296365D02*
Y1299565D01*
G01X398539Y1296365D02*
X404739D01*
G01X398539Y1299565D02*
Y1296365D01*
G01X404739Y1299565D02*
X398539D01*
G01X397411Y1297675D02*
Y1300875D01*
G01Y1301675D02*
Y1304875D01*
G01X408718Y1295474D02*
Y1297377D01*
G01X410621Y1295474D02*
X408718D01*
G01X401871Y1318445D02*
Y1324845D01*
G01X399604Y1305638D02*
Y1308838D01*
G01X393404Y1305638D02*
X399604D01*
G01X393404Y1308838D02*
Y1305638D01*
G01X399604Y1308838D02*
X393404D01*
G01X406108Y1311843D02*
Y1315043D01*
G01X399908Y1311843D02*
X406108D01*
G01X399908Y1315043D02*
Y1311843D01*
G01X406108Y1315043D02*
X399908D01*
G01X394255Y1309689D02*
Y1312889D01*
G01Y1313689D02*
Y1316889D01*
G01X408718Y1315160D02*
X410621D01*
G01X408718Y1313257D02*
Y1315160D01*
G01X406923Y1325544D02*
X410123D01*
G01X406923Y1331744D02*
Y1325544D01*
G01X410123Y1331744D02*
X406923D01*
G01X403057Y1325568D02*
X406257D01*
G01X403057Y1331768D02*
Y1325568D01*
G01X406257Y1331768D02*
X403057D01*
G01X406257Y1325568D02*
Y1331768D01*
G01X406859Y1359651D02*
Y1353451D01*
X410059D01*
Y1359651D01*
X406859D01*
G01X402859D02*
Y1353451D01*
X406059D01*
Y1359651D01*
X402859D01*
G01X398359D02*
Y1353451D01*
X401559D01*
Y1359651D01*
X398359D01*
G01X397559Y1353451D02*
Y1359651D01*
X394359D01*
Y1353451D01*
X397559D01*
G01X400291Y1375053D02*
X398388D01*
Y1376956D01*
G01X402479Y1398718D02*
Y1404918D01*
X399279D01*
Y1398718D01*
X402479D01*
G01X398388Y1392836D02*
Y1394739D01*
X400291D01*
G01X411752Y1403853D02*
Y1410053D01*
X408552D01*
Y1403853D01*
X411752D01*
G01X400589Y1412246D02*
Y1406046D01*
X403789D01*
Y1412246D01*
X400589D01*
G01X404589D02*
Y1406046D01*
X407789D01*
Y1412246D01*
X404589D01*
G01X400078Y1496235D02*
Y1499435D01*
G01X393878Y1496235D02*
X400078D01*
G01X393878Y1499435D02*
Y1496235D01*
G01X393511Y1489381D02*
X396711D01*
G01X393511Y1495581D02*
Y1489381D01*
G01X396711Y1495581D02*
X393511D01*
G01X396711Y1489381D02*
Y1495581D01*
G01X393082Y1484178D02*
Y1487378D01*
G01X400078Y1499435D02*
X393878D01*
G01X395417Y1542300D02*
Y1539100D01*
G01X401617Y1542300D02*
X395417D01*
G01X401617Y1539100D02*
Y1542300D01*
G01X395417Y1539100D02*
X401617D01*
G01X408381Y1532386D02*
X411581D01*
G01X408381Y1538586D02*
Y1532386D01*
G01X411581Y1538586D02*
X408381D01*
G01X395417Y1548800D02*
Y1545600D01*
G01X401617D02*
Y1548800D01*
G01X395417Y1545600D02*
X401617D01*
G01X402557Y1532386D02*
X405757D01*
G01X402557Y1538586D02*
Y1532386D01*
G01X405757Y1538586D02*
X402557D01*
G01X405757Y1532386D02*
Y1538586D01*
G01X395417Y1536800D02*
Y1533600D01*
G01X401617Y1536800D02*
X395417D01*
G01X401617Y1533600D02*
Y1536800D01*
G01X395417Y1533600D02*
X401617D01*
G01Y1548800D02*
X395417D01*
G01X405652Y1555047D02*
X402452D01*
G01X405652Y1548847D02*
Y1555047D01*
G01X402452Y1548847D02*
X405652D01*
G01X402452Y1555047D02*
Y1548847D01*
G01X413955Y315985D02*
Y327985D01*
G01X422416Y326540D02*
X425616D01*
G01X422416Y332740D02*
Y326540D01*
G01X425616Y332740D02*
X422416D01*
G01X416049Y344605D02*
Y341405D01*
G01X422249D02*
Y344605D01*
G01X416049Y341405D02*
X422249D01*
G01X416470Y336123D02*
Y332923D01*
G01X422670Y336123D02*
X416470D01*
G01X422670Y332923D02*
Y336123D01*
G01X416470Y332923D02*
X422670D01*
G01X422249Y344605D02*
X416049D01*
G01X425504Y352084D02*
X422304D01*
G01Y345884D02*
X425504D01*
G01X422304Y352084D02*
Y345884D01*
G01X420750Y547580D02*
Y535580D01*
G01D02*
X426750D01*
G01Y547580D02*
X420750D01*
G01X416121Y928278D02*
Y940278D01*
G01X410121Y928278D02*
X416121D01*
G01X410121Y940278D02*
Y928278D01*
G01X424121D02*
Y940278D01*
G01X418121Y928278D02*
X424121D01*
G01X418121Y940278D02*
Y928278D01*
G01X416121Y940278D02*
X410121D01*
G01X424121D02*
X418121D01*
G01X414095Y1100397D02*
Y1112397D01*
G01X416231Y1115247D02*
Y1127247D01*
G01X410231Y1115247D02*
X416231D01*
G01X410231Y1127247D02*
Y1115247D01*
G01X416980Y1109626D02*
X423180D01*
Y1112826D01*
X416980D01*
Y1109626D01*
G01X423833Y1113998D02*
Y1107798D01*
X427033D01*
Y1113998D01*
X423833D01*
G01X416231Y1127247D02*
X410231D01*
G01X419564Y1137574D02*
Y1135148D01*
G01X410596Y1138272D02*
X427526D01*
G01X410596Y1174012D02*
Y1138272D01*
G01X418609Y1178837D02*
Y1176597D01*
G01X416984Y1177810D02*
X420234D01*
G01X410594Y1174012D02*
X427534Y1174015D01*
G01X410594Y1174612D02*
X427569Y1174616D01*
G01X410594Y1175212D02*
X427577Y1175206D01*
G01X410594Y1175212D02*
Y1174012D01*
G01X427526D02*
X410596D01*
G01X423934Y1189471D02*
X429934D01*
G01X423934Y1201471D02*
Y1189471D01*
G01X429934Y1201471D02*
X423934D01*
G01X416469Y1189471D02*
Y1201471D01*
G01X410469Y1189471D02*
X416469D01*
G01X410469Y1201471D02*
Y1189471D01*
G01X416469Y1201471D02*
X410469D01*
G01X415025Y1219982D02*
Y1209782D01*
X419625D01*
Y1219982D01*
X415025D01*
G01X422263D02*
Y1209782D01*
X426863D01*
Y1219982D01*
X422263D01*
G01X409516D02*
Y1209782D01*
X414116D01*
Y1219982D01*
X409516D01*
G01X434169Y1249202D02*
X422779D01*
G01X410069Y1247418D02*
X418969D01*
G01X410069Y1267704D02*
Y1247418D01*
G01X418969D02*
Y1267704D01*
G01X427373Y1263872D02*
Y1270072D01*
X424173D01*
Y1263872D01*
X427373D01*
G01X418969Y1267704D02*
X410069D01*
G01X428174Y1275011D02*
Y1285211D01*
X423574D01*
Y1275011D01*
X428174D01*
G01X412466Y1284263D02*
Y1290463D01*
G01X409266Y1284263D02*
X412466D01*
G01X409266Y1290463D02*
Y1284263D01*
G01X417135Y1280964D02*
X420335D01*
G01X417135Y1287164D02*
Y1280964D01*
G01X420335D02*
Y1287164D01*
G01X413135Y1280964D02*
X416335D01*
G01X413135Y1287164D02*
Y1280964D01*
G01X416335D02*
Y1287164D01*
G01X420907Y1290443D02*
Y1287243D01*
G01X427107Y1290443D02*
X420907D01*
G01Y1287243D02*
X427107D01*
G01X412466Y1290463D02*
X409266D01*
G01X420335Y1287164D02*
X417135D01*
G01X416335D02*
X413135D01*
G01X423225Y1328356D02*
X435225D01*
G01X423225Y1334356D02*
Y1328356D01*
G01X435225Y1334356D02*
X423225D01*
G01X423853Y1322284D02*
Y1319084D01*
G01X430053Y1322284D02*
X423853D01*
G01Y1319084D02*
X430053D01*
G01X410123Y1325544D02*
Y1331744D01*
G01X416031Y1331458D02*
X412831D01*
G01X416031Y1325258D02*
Y1331458D01*
G01X412831Y1325258D02*
X416031D01*
G01X412831Y1331458D02*
Y1325258D01*
G01X420031Y1331458D02*
X416831D01*
G01X420031Y1325258D02*
Y1331458D01*
G01X416831Y1325258D02*
X420031D01*
G01X416831Y1331458D02*
Y1325258D01*
G01X419605Y1360259D02*
Y1370459D01*
X415005D01*
Y1360259D01*
X419605D01*
G01X411179Y1369734D02*
Y1363534D01*
X414379D01*
Y1369734D01*
X411179D01*
G01X426808Y1368572D02*
X420608D01*
Y1365372D01*
X426808D01*
Y1368572D01*
G01X421917Y1380677D02*
Y1374477D01*
X425117D01*
Y1380677D01*
X421917D01*
G01X420608Y1369372D02*
X426808D01*
Y1372572D01*
X420608D01*
Y1369372D01*
G01X418074Y1376956D02*
Y1375053D01*
X416171D01*
G01X417957Y1397349D02*
Y1403549D01*
X414757D01*
Y1397349D01*
X417957D01*
G01X416171Y1394739D02*
X418074D01*
Y1392836D01*
G01X421359Y1414466D02*
X427759D01*
G01X421359Y1401586D02*
X427759D01*
G01X421359Y1414466D02*
Y1401586D01*
G01X412603Y1415402D02*
Y1409202D01*
X415803D01*
Y1415402D01*
X412603D01*
G01X416603D02*
Y1409202D01*
X419803D01*
Y1415402D01*
X416603D01*
G01X417984Y1539621D02*
Y1542821D01*
G01X411784Y1539621D02*
X417984D01*
G01X411784Y1542821D02*
Y1539621D01*
G01X417984Y1542821D02*
X411784D01*
G01X417984Y1545598D02*
Y1548798D01*
G01X411784Y1545598D02*
X417984D01*
G01X411784Y1548798D02*
Y1545598D01*
G01X411581Y1532386D02*
Y1538586D01*
G01X417984Y1548798D02*
X411784D01*
G01X417423Y1560871D02*
X414223D01*
G01X417423Y1554671D02*
Y1560871D01*
G01X414223Y1554671D02*
X417423D01*
G01X414223Y1560871D02*
Y1554671D01*
G01X429359Y326489D02*
X432559D01*
G01X429359Y332689D02*
Y326489D01*
G01X432559D02*
Y332689D01*
G01X425616Y326540D02*
Y332740D01*
G01X432559Y332689D02*
X429359D01*
G01X440434Y332307D02*
Y335507D01*
G01X434234Y332307D02*
X440434D01*
G01X434234Y335507D02*
Y332307D01*
G01X440434Y335507D02*
X434234D01*
G01X440764Y341274D02*
Y344474D01*
G01X434564Y341274D02*
X440764D01*
G01X434564Y344474D02*
Y341274D01*
G01X440764Y344474D02*
X434564D01*
G01X439652Y348075D02*
Y351275D01*
G01X433452Y348075D02*
X439652D01*
G01X433452Y351275D02*
Y348075D01*
G01X439652Y351275D02*
X433452D01*
G01X425504Y345884D02*
Y352084D01*
G01X426593Y351296D02*
Y348096D01*
G01X432793Y351296D02*
X426593D01*
G01X432793Y348096D02*
Y351296D01*
G01X426593Y348096D02*
X432793D01*
G01X432804Y547590D02*
Y535590D01*
G01X438804D02*
Y547590D01*
G01X432804Y535590D02*
X438804D01*
G01X426750Y535580D02*
Y547580D01*
G01X438804Y547590D02*
X432804D01*
G01X449244Y1090088D02*
Y1096088D01*
X437244D01*
Y1090088D01*
X449244D01*
G01X440223Y1112397D02*
Y1100397D01*
G01D02*
X446223D01*
G01X430020Y1113573D02*
Y1107373D01*
X433220D01*
Y1113573D01*
X430020D01*
G01X446223Y1112397D02*
X440223D01*
G01X440359Y1115247D02*
Y1127247D01*
G01X434359Y1115247D02*
X440359D01*
G01X434359Y1127247D02*
Y1115247D01*
G01X430385Y1120496D02*
X427185D01*
G01X430385Y1114296D02*
Y1120496D01*
G01X427185Y1114296D02*
X430385D01*
G01X427185Y1120496D02*
Y1114296D01*
G01X433422Y1121232D02*
Y1127432D01*
X430222D01*
Y1121232D01*
X433422D01*
G01X429597Y1121217D02*
Y1127417D01*
X426397D01*
Y1121217D01*
X429597D01*
G01X440359Y1127247D02*
X434359D01*
G01X438424Y1138272D02*
X455354D01*
G01X438424Y1174012D02*
Y1138272D01*
G01X427526D02*
Y1174012D01*
G01X429975Y1161539D02*
Y1149539D01*
G01X435975D02*
Y1161539D01*
G01X429975Y1149539D02*
X435975D01*
G01Y1161539D02*
X429975D01*
G01X446437Y1178837D02*
Y1176597D01*
G01X444812Y1177810D02*
X448062D01*
G01X438422Y1174012D02*
X455362Y1174015D01*
G01X438422Y1174612D02*
X455397Y1174616D01*
G01X438422Y1175212D02*
X455405Y1175206D01*
G01X438422Y1175212D02*
Y1174012D01*
G01X455354D02*
X438424D01*
G01X427527Y1175162D02*
X427523Y1173653D01*
G01X429934Y1189471D02*
Y1201471D01*
G01X437634Y1190371D02*
X442234D01*
G01X437634Y1200571D02*
Y1190371D01*
G01X442234Y1200571D02*
X437634D01*
G01X427801Y1219982D02*
Y1209782D01*
X432401D01*
Y1219982D01*
X427801D01*
G01X435705D02*
Y1209782D01*
X440305D01*
Y1219982D01*
X435705D01*
G01X441540D02*
Y1209782D01*
X446140D01*
Y1219982D01*
X441540D01*
G01X453171Y1215076D02*
X435469D01*
G01D02*
Y1227173D01*
G01X434177Y1239176D02*
Y1230276D01*
G01D02*
X454463D01*
G01X435469Y1242151D02*
Y1254376D01*
G01X434169Y1266904D02*
Y1249202D01*
G01X454463Y1239176D02*
X434177D01*
G01X435469Y1254376D02*
X453171D01*
G01X442678Y1262110D02*
Y1268310D01*
X439478D01*
Y1262110D01*
X442678D01*
G01X437925D02*
Y1268310D01*
X434725D01*
Y1262110D01*
X437925D01*
G01X433261Y1263872D02*
Y1270072D01*
X430061D01*
Y1263872D01*
X433261D01*
G01X443344Y1275032D02*
Y1285232D01*
X438744D01*
Y1275032D01*
X443344D01*
G01X438591D02*
Y1285232D01*
X433991D01*
Y1275032D01*
X438591D01*
G01X433414Y1275310D02*
Y1285510D01*
X428814D01*
Y1275310D01*
X433414D01*
G01X427107Y1287243D02*
Y1290443D01*
G01X439512Y1293873D02*
X436312D01*
G01X439512Y1287673D02*
Y1293873D01*
G01X436312Y1287673D02*
X439512D01*
G01X436312Y1293873D02*
Y1287673D01*
G01X428404Y1295474D02*
X426501D01*
G01X428404Y1297377D02*
Y1295474D01*
G01X432998Y1312091D02*
X443198D01*
G01X432998Y1316691D02*
Y1312091D01*
G01X443198Y1316691D02*
X432998D01*
G01X433723Y1311465D02*
Y1308265D01*
G01X439923Y1311465D02*
X433723D01*
G01X439923Y1308265D02*
Y1311465D01*
G01X433723Y1308265D02*
X439923D01*
G01X438085Y1317694D02*
Y1323894D01*
G01X434885Y1317694D02*
X438085D01*
G01X434885Y1323894D02*
Y1317694D01*
G01X430885D02*
X434085D01*
G01X430885Y1323894D02*
Y1317694D01*
G01X434085D02*
Y1323894D01*
G01X428404Y1315160D02*
Y1313257D01*
G01X426501Y1315160D02*
X428404D01*
G01X435225Y1328356D02*
Y1334356D01*
G01X430053Y1319084D02*
Y1322284D01*
G01X438085Y1323894D02*
X434885D01*
G01X434085D02*
X430885D01*
G01X437266Y1380953D02*
X431266D01*
Y1368953D01*
X437266D01*
Y1380953D01*
G01X434372Y1386626D02*
X428172D01*
Y1383426D01*
X434372D01*
Y1386626D01*
G01X428482Y1397200D02*
X434682D01*
Y1400400D01*
X428482D01*
Y1397200D01*
G01X428458Y1393334D02*
X434658D01*
Y1396534D01*
X428458D01*
Y1393334D01*
G01X434372Y1390626D02*
X428172D01*
Y1387426D01*
X434372D01*
Y1390626D01*
G01X432708Y1402922D02*
X429608D01*
Y1404456D01*
G01Y1406789D02*
X432708D01*
X432088Y1406329D01*
G01X429608D02*
Y1407249D01*
G01Y1410349D02*
X432708D01*
X430486Y1408931D01*
Y1410847D01*
G01X429970Y1412337D02*
X429711Y1412606D01*
X429608Y1412912D01*
X429711Y1413219D01*
X430021Y1413487D01*
X430486Y1413679D01*
X430951Y1413756D01*
X431520D01*
X431985Y1413679D01*
X432398Y1413487D01*
X432605Y1413257D01*
X432708Y1412989D01*
X432605Y1412682D01*
X432398Y1412452D01*
X432088Y1412299D01*
X431675Y1412222D01*
X431313Y1412299D01*
X430951Y1412491D01*
X430745Y1412721D01*
X430693Y1412989D01*
X430796Y1413296D01*
X431055Y1413526D01*
X431520Y1413756D01*
G01X427759Y1401586D02*
Y1414466D01*
G01X439607Y1425158D02*
Y1689331D01*
G01X552599Y1425158D02*
X439607D01*
G01X436985Y1512067D02*
X429485D01*
Y1509827D01*
X429860Y1509080D01*
X430735Y1508520D01*
X431735Y1508333D01*
X432735Y1508520D01*
X433485Y1508987D01*
X433860Y1509827D01*
Y1512067D01*
G01X436985Y1504567D02*
X429485D01*
Y1502233D01*
X429860Y1501487D01*
X430360Y1501020D01*
X431360Y1500833D01*
X432360Y1501020D01*
X432985Y1501580D01*
X433360Y1502233D01*
Y1504567D01*
G01Y1502233D02*
X436985Y1500833D01*
G01Y1493333D02*
Y1497067D01*
X429485D01*
Y1493333D01*
G01X433110Y1494827D02*
Y1497067D01*
G01X435985Y1489660D02*
X436610Y1488913D01*
X436985Y1488073D01*
Y1487327D01*
X436610Y1486580D01*
X435985Y1486020D01*
X435110Y1485740D01*
X434235Y1485927D01*
X433485Y1486393D01*
X432985Y1487233D01*
X432735Y1488353D01*
X432235Y1489007D01*
X431360Y1489287D01*
X430485Y1489100D01*
X429860Y1488633D01*
X429485Y1487980D01*
Y1487327D01*
X429735Y1486673D01*
X430360Y1486113D01*
G01X435985Y1482160D02*
X436610Y1481413D01*
X436985Y1480573D01*
Y1479827D01*
X436610Y1479080D01*
X435985Y1478520D01*
X435110Y1478240D01*
X434235Y1478427D01*
X433485Y1478893D01*
X432985Y1479733D01*
X432735Y1480853D01*
X432235Y1481507D01*
X431360Y1481787D01*
X430485Y1481600D01*
X429860Y1481133D01*
X429485Y1480480D01*
Y1479827D01*
X429735Y1479173D01*
X430360Y1478613D01*
G01X434485Y1473913D02*
Y1471487D01*
G01X436985Y1466973D02*
X429485D01*
Y1463427D01*
G01X433110Y1464733D02*
Y1466973D01*
G01X429485Y1458820D02*
Y1456580D01*
G01Y1457700D02*
X436985D01*
G01Y1458820D02*
Y1456580D01*
G01X429485Y1450200D02*
X436985D01*
G01X429485Y1452347D02*
Y1448053D01*
G01X439607Y1689331D02*
X552599D01*
G01X445398Y-538835D02*
Y-530835D01*
X444198Y-532435D01*
G01Y-538835D02*
X446598D01*
G01X453198D02*
X453398Y-537102D01*
X453698Y-535635D01*
X454098Y-534302D01*
X454598Y-532835D01*
X455398Y-530835D01*
X451398D01*
G01X461398Y-539102D02*
X461198Y-538968D01*
Y-538702D01*
X461398Y-538568D01*
X461598Y-538702D01*
Y-538968D01*
X461398Y-539102D01*
G01X467498Y-532168D02*
X468098Y-531368D01*
X468798Y-530968D01*
X469598Y-530835D01*
X470598Y-531102D01*
X471298Y-531768D01*
X471498Y-532568D01*
X471398Y-533369D01*
X470998Y-534035D01*
X468998Y-535368D01*
X468098Y-536302D01*
X467498Y-537635D01*
X467298Y-538835D01*
X471498D01*
G01X456104Y547490D02*
Y535490D01*
G01D02*
X462104D01*
G01X444614Y547580D02*
Y535580D01*
G01X450614D02*
Y547580D01*
G01X444614Y535580D02*
X450614D01*
G01X462104Y547490D02*
X456104D01*
G01X450614Y547580D02*
X444614D01*
G01X457785Y1008925D02*
Y1005725D01*
G01X463985Y1008925D02*
X457785D01*
G01Y1005725D02*
X463985D01*
G01X456191Y1005666D02*
Y1011866D01*
G01X452991Y1005666D02*
X456191D01*
G01X452991Y1011866D02*
Y1005666D01*
G01X454685Y1003780D02*
Y1000580D01*
G01X460885Y1003780D02*
X454685D01*
G01Y1000580D02*
X460885D01*
G01X452191Y1005666D02*
Y1011866D01*
X448991D01*
Y1005666D01*
X452191D01*
G01X448991Y1012666D02*
X452191D01*
G01X448991Y1018866D02*
Y1012666D01*
G01X452191Y1018866D02*
X448991D01*
G01X452191Y1012666D02*
Y1018866D01*
G01X456191Y1011866D02*
X452991D01*
G01X448691Y1018866D02*
X445491D01*
G01X448691Y1012666D02*
Y1018866D01*
G01X445491Y1012666D02*
X448691D01*
G01X445491Y1018866D02*
Y1012666D01*
G01X445191Y1018866D02*
X441991D01*
G01X445191Y1012666D02*
Y1018866D01*
G01X441991Y1012666D02*
X445191D01*
G01X441991Y1018866D02*
Y1012666D01*
G01X457977Y1022099D02*
Y1028299D01*
X454777D01*
Y1022099D01*
X457977D01*
G01X446223Y1100397D02*
Y1112397D01*
G01X448359Y1115247D02*
Y1127247D01*
G01X442359Y1115247D02*
X448359D01*
G01X442359Y1127247D02*
Y1115247D01*
G01X449001Y1109626D02*
X455201D01*
Y1112826D01*
X449001D01*
Y1109626D01*
G01X455977Y1113993D02*
Y1107793D01*
X459177D01*
Y1113993D01*
X455977D01*
G01X448359Y1127247D02*
X442359D01*
G01X447392Y1137574D02*
Y1135148D01*
G01X455354Y1138272D02*
Y1174012D01*
G01X455355Y1175162D02*
X455351Y1173653D01*
G01X442234Y1190371D02*
Y1200571D01*
G01X454098Y1195871D02*
X460298D01*
G01X454098Y1199071D02*
Y1195871D01*
G01X460298Y1199071D02*
X454098D01*
G01Y1195071D02*
Y1191871D01*
G01X460298Y1195071D02*
X454098D01*
G01Y1191871D02*
X460298D01*
G01X452770Y1219982D02*
X448170D01*
G01X452770Y1209782D02*
Y1219982D01*
G01X448170D02*
Y1209782D01*
G01D02*
X452770D01*
G01X458111Y1219982D02*
X453511D01*
G01Y1209782D02*
X458111D01*
G01X453511Y1219982D02*
Y1209782D01*
G01X453171Y1227173D02*
Y1215076D01*
G01X454463Y1230276D02*
Y1239176D01*
G01X453171Y1254376D02*
Y1242151D01*
G01X458072Y1262217D02*
Y1268417D01*
X454872D01*
Y1262217D01*
X458072D01*
G01X452977Y1262197D02*
Y1268397D01*
X449777D01*
Y1262197D01*
X452977D01*
G01X447846Y1262142D02*
Y1268342D01*
X444646D01*
Y1262142D01*
X447846D01*
G01X458738Y1275139D02*
Y1285339D01*
X454138D01*
Y1275139D01*
X458738D01*
G01X453643Y1275119D02*
Y1285319D01*
X449043D01*
Y1275119D01*
X453643D01*
G01X448512Y1275064D02*
Y1285264D01*
X443912D01*
Y1275064D01*
X448512D01*
G01X443806Y1303145D02*
Y1299945D01*
G01X450006D02*
Y1303145D01*
G01X443806Y1299945D02*
X450006D01*
G01X443806Y1298645D02*
Y1295445D01*
G01X450006Y1298645D02*
X443806D01*
G01X450006Y1295445D02*
Y1298645D01*
G01X443806Y1295445D02*
X450006D01*
G01Y1291445D02*
Y1294645D01*
G01X443806Y1291445D02*
X450006D01*
G01X443806Y1294645D02*
Y1291445D01*
G01X450006Y1294645D02*
X443806D01*
G01X443198Y1312091D02*
Y1316691D01*
G01X450006Y1303145D02*
X443806D01*
G01Y1307145D02*
Y1303945D01*
G01X450006Y1307145D02*
X443806D01*
G01X450006Y1303945D02*
Y1307145D01*
G01X443806Y1303945D02*
X450006D01*
G01X455689Y1311918D02*
Y1309696D01*
X455536Y1309231D01*
X455229Y1308921D01*
X454846Y1308818D01*
X454463Y1308921D01*
X454156Y1309231D01*
X454003Y1309696D01*
Y1311918D01*
G01X451746Y1308818D02*
Y1311918D01*
X452206Y1311298D01*
G01Y1308818D02*
X451286D01*
G01X448646D02*
Y1311918D01*
X449106Y1311298D01*
G01Y1308818D02*
X448186D01*
G01X445546D02*
X445278Y1308870D01*
X444971Y1309025D01*
X444779Y1309283D01*
X444703Y1309645D01*
X444779Y1310006D01*
X445009Y1310316D01*
X445354Y1310471D01*
X445738D01*
X445968Y1310575D01*
X446159Y1310833D01*
X446236Y1311195D01*
X446121Y1311556D01*
X445853Y1311815D01*
X445546Y1311918D01*
X445239Y1311815D01*
X444971Y1311556D01*
X444856Y1311195D01*
X444933Y1310833D01*
X445124Y1310575D01*
X445354Y1310471D01*
X445738D01*
X446083Y1310316D01*
X446313Y1310006D01*
X446389Y1309645D01*
X446313Y1309283D01*
X446121Y1309025D01*
X445814Y1308870D01*
X445546Y1308818D01*
G01X465498Y-513835D02*
Y-505835D01*
X469298D01*
G01X467898Y-509702D02*
X465498D01*
G01X476340Y88020D02*
Y91120D01*
G01X474730D02*
Y88020D01*
G01Y89570D02*
X476340D01*
G01X472435Y88020D02*
Y91120D01*
X472895Y90500D01*
G01Y88020D02*
X471975D01*
G01X469335Y91120D02*
X469642Y91017D01*
X469872Y90758D01*
X470025Y90448D01*
X470140Y90035D01*
X470178Y89570D01*
X470140Y89105D01*
X470025Y88692D01*
X469872Y88382D01*
X469642Y88123D01*
X469335Y88020D01*
X469028Y88123D01*
X468798Y88382D01*
X468645Y88692D01*
X468530Y89105D01*
X468492Y89570D01*
X468530Y90035D01*
X468645Y90448D01*
X468798Y90758D01*
X469028Y91017D01*
X469335Y91120D01*
G01X466963Y90603D02*
X466733Y90913D01*
X466465Y91068D01*
X466158Y91120D01*
X465775Y91017D01*
X465507Y90758D01*
X465430Y90448D01*
X465468Y90138D01*
X465622Y89880D01*
X466388Y89363D01*
X466733Y89002D01*
X466963Y88485D01*
X467040Y88020D01*
X465430D01*
G01X462104Y535490D02*
Y547490D01*
G01X466301Y642487D02*
Y645687D01*
G01X460101Y642487D02*
X466301D01*
G01X460101Y645687D02*
Y642487D01*
G01X466301Y645687D02*
X460101D01*
G01X463985Y1005725D02*
Y1008925D01*
G01X460885Y1000580D02*
Y1003780D01*
G01X462991Y1016166D02*
Y1012966D01*
G01X469191Y1016166D02*
X462991D01*
G01X469191Y1012966D02*
Y1016166D01*
G01X462991Y1012966D02*
X469191D01*
G01X458777Y1022099D02*
X461977D01*
G01X458777Y1028299D02*
Y1022099D01*
G01X461977D02*
Y1028299D01*
G01X465985Y1022080D02*
Y1028280D01*
X462785D01*
Y1022080D01*
X465985D01*
G01X461977Y1028299D02*
X458777D01*
G01X461277Y1096068D02*
Y1090068D01*
X473277D01*
Y1096068D01*
X461277D01*
G01X473682Y1112397D02*
Y1100397D01*
G01D02*
X479682D01*
G01X462366Y1113495D02*
Y1107295D01*
X465566D01*
Y1113495D01*
X462366D01*
G01X479682Y1112397D02*
X473682D01*
G01X473818Y1115247D02*
Y1127247D01*
G01X467818Y1115247D02*
X473818D01*
G01X467818Y1127247D02*
Y1115247D01*
G01X462513Y1120496D02*
X459313D01*
G01X462513Y1114296D02*
Y1120496D01*
G01X459313Y1114296D02*
X462513D01*
G01X459313Y1120496D02*
Y1114296D01*
G01X473818Y1127247D02*
X467818D01*
G01X466772Y1199071D02*
Y1195871D01*
G01X472972Y1199071D02*
X466772D01*
G01X472972Y1195871D02*
Y1199071D01*
G01X466772Y1195871D02*
X472972D01*
G01Y1191871D02*
Y1195071D01*
G01X466772Y1191871D02*
X472972D01*
G01X466772Y1195071D02*
Y1191871D01*
G01X472972Y1195071D02*
X466772D01*
G01X460298Y1195871D02*
Y1199071D01*
G01Y1191871D02*
Y1195071D01*
G01X473648Y1219982D02*
X469048D01*
G01X473648Y1209782D02*
Y1219982D01*
G01X469048Y1209782D02*
X473648D01*
G01X469048Y1219982D02*
Y1209782D01*
G01X468541Y1219982D02*
X463941D01*
G01X468541Y1209782D02*
Y1219982D01*
G01X463941D02*
Y1209782D01*
G01D02*
X468541D01*
G01X463314Y1219982D02*
X458714D01*
G01X463314Y1209782D02*
Y1219982D01*
G01X458714D02*
Y1209782D01*
G01D02*
X463314D01*
G01X458111D02*
Y1219982D01*
G01X474178Y1215076D02*
Y1226455D01*
G01X491880Y1215076D02*
X474178D01*
G01X472886Y1230276D02*
X493172D01*
G01X472886Y1239176D02*
Y1230276D01*
G01X474178Y1241792D02*
Y1254376D01*
G01X493172Y1239176D02*
X472886D01*
G01X474178Y1254376D02*
X491880D01*
G01X463277Y1262239D02*
Y1268439D01*
X460077D01*
Y1262239D01*
X463277D01*
G01X468575D02*
Y1268439D01*
X465375D01*
Y1262239D01*
X468575D01*
G01X474192Y1262207D02*
Y1268407D01*
X470992D01*
Y1262207D01*
X474192D01*
G01X463943Y1275161D02*
Y1285361D01*
X459343D01*
Y1275161D01*
X463943D01*
G01X469273D02*
Y1285361D01*
X464673D01*
Y1275161D01*
X469273D01*
G01X474890D02*
Y1285361D01*
X470290D01*
Y1275161D01*
X474890D01*
G01X486393Y789425D02*
X492593D01*
G01X486393Y792625D02*
Y789425D01*
G01X492593Y792625D02*
X486393D01*
G01Y796625D02*
Y793425D01*
G01X492593Y796625D02*
X486393D01*
G01Y793425D02*
X492593D01*
G01X487350Y810599D02*
Y798395D01*
G01D02*
X492825D01*
G01X503774Y810599D02*
X487350D01*
G01X477307Y1028727D02*
Y1022527D01*
X480507D01*
Y1028727D01*
X477307D01*
G01X482515Y1028569D02*
Y1022369D01*
X485715D01*
Y1028569D01*
X482515D01*
G01X479682Y1100397D02*
Y1112397D01*
G01X481818Y1115247D02*
Y1127247D01*
G01X475818Y1115247D02*
X481818D01*
G01X475818Y1127247D02*
Y1115247D01*
G01X482452Y1109577D02*
X488652D01*
Y1112777D01*
X482452D01*
Y1109577D01*
G01X489469Y1114006D02*
Y1107806D01*
X492669D01*
Y1114006D01*
X489469D01*
G01X481818Y1127247D02*
X475818D01*
G01X485151Y1137574D02*
Y1135148D01*
G01X476183Y1138272D02*
X493113D01*
G01X476183Y1174012D02*
Y1138272D01*
G01X484196Y1178837D02*
Y1176597D01*
G01X482571Y1177810D02*
X485821D01*
G01X493113Y1174012D02*
X476183D01*
G01X476181Y1175212D02*
Y1174012D01*
G01Y1175212D02*
X493164Y1175206D01*
G01X476181Y1174612D02*
X493156Y1174616D01*
G01X476181Y1174012D02*
X493121Y1174015D01*
G01X489671Y1189471D02*
Y1201471D01*
G01X483671Y1189471D02*
X489671D01*
G01X483671Y1201471D02*
Y1189471D01*
G01X489671Y1201471D02*
X483671D01*
G01X478877Y1219982D02*
X474277D01*
G01X478877Y1209782D02*
Y1219982D01*
G01X474277Y1209782D02*
X478877D01*
G01X474277Y1219982D02*
Y1209782D01*
G01X485188Y1219982D02*
X480588D01*
G01X485188Y1209782D02*
Y1219982D01*
G01X480588D02*
Y1209782D01*
G01D02*
X485188D01*
G01X486747Y1219982D02*
Y1209782D01*
X491347D01*
Y1219982D01*
X486747D01*
G01X490721Y1262207D02*
Y1268407D01*
X487521D01*
Y1262207D01*
X490721D01*
G01X479701D02*
Y1268407D01*
X476501D01*
Y1262207D01*
X479701D01*
G01X485103D02*
Y1268407D01*
X481903D01*
Y1262207D01*
X485103D01*
G01X491419Y1275161D02*
Y1285361D01*
X486819D01*
Y1275161D01*
X491419D01*
G01X480399D02*
Y1285361D01*
X475799D01*
Y1275161D01*
X480399D01*
G01X485801D02*
Y1285361D01*
X481201D01*
Y1275161D01*
X485801D01*
G01X499312Y679178D02*
X509312D01*
G01Y683778D02*
X499312D01*
G01Y679178D02*
Y683778D01*
G01X499212Y685678D02*
X509412D01*
G01X499212Y690278D02*
Y685678D01*
G01X509412Y690278D02*
X499212D01*
G01X500455Y690945D02*
X510655D01*
G01X500455Y695545D02*
Y690945D01*
G01X510655Y695545D02*
X500455D01*
G01X502541Y695805D02*
X508741D01*
G01X502541Y699005D02*
Y695805D01*
G01X508741Y699005D02*
X502541D01*
G01X501786Y711155D02*
X507986D01*
G01X501786Y714355D02*
Y711155D01*
G01X507986Y714355D02*
X501786D01*
G01X504191Y715816D02*
X507391D01*
G01X504191Y722016D02*
Y715816D01*
G01X501786Y707155D02*
X507986D01*
G01X501786Y710355D02*
Y707155D01*
G01X507986Y710355D02*
X501786D01*
G01Y706355D02*
Y703155D01*
G01X507986Y706355D02*
X501786D01*
G01Y703155D02*
X507986D01*
G01X507391Y722016D02*
X504191D01*
G01X504641Y797749D02*
Y794549D01*
G01X510841Y797749D02*
X504641D01*
G01Y794549D02*
X510841D01*
G01X492593Y789425D02*
Y792625D01*
G01Y793425D02*
Y796625D01*
G01X501707Y791875D02*
X495507D01*
G01X501707Y788675D02*
Y791875D01*
G01X495507Y788675D02*
X501707D01*
G01X495507Y791875D02*
Y788675D01*
G01X503774Y798395D02*
Y810599D01*
G01X498299Y798395D02*
X503774D01*
G01X495562Y801132D02*
X498299Y798395D01*
G01X492825D02*
X495562Y801132D01*
G01X499033Y815155D02*
Y812933D01*
X498880Y812468D01*
X498573Y812158D01*
X498190Y812055D01*
X497807Y812158D01*
X497500Y812468D01*
X497347Y812933D01*
Y815155D01*
G01X495742Y812417D02*
X495473Y812158D01*
X495167Y812055D01*
X494860Y812158D01*
X494592Y812468D01*
X494400Y812933D01*
X494323Y813398D01*
Y813967D01*
X494400Y814432D01*
X494592Y814845D01*
X494822Y815052D01*
X495090Y815155D01*
X495397Y815052D01*
X495627Y814845D01*
X495780Y814535D01*
X495857Y814122D01*
X495780Y813760D01*
X495588Y813398D01*
X495358Y813192D01*
X495090Y813140D01*
X494783Y813243D01*
X494553Y813502D01*
X494323Y813967D01*
G01X492642Y812417D02*
X492373Y812158D01*
X492067Y812055D01*
X491760Y812158D01*
X491492Y812468D01*
X491300Y812933D01*
X491223Y813398D01*
Y813967D01*
X491300Y814432D01*
X491492Y814845D01*
X491722Y815052D01*
X491990Y815155D01*
X492297Y815052D01*
X492527Y814845D01*
X492680Y814535D01*
X492757Y814122D01*
X492680Y813760D01*
X492488Y813398D01*
X492258Y813192D01*
X491990Y813140D01*
X491683Y813243D01*
X491453Y813502D01*
X491223Y813967D01*
G01X504637Y826989D02*
Y824767D01*
X504484Y824302D01*
X504177Y823992D01*
X503794Y823889D01*
X503411Y823992D01*
X503104Y824302D01*
X502951Y824767D01*
Y826989D01*
G01X500694Y823889D02*
Y826989D01*
X501154Y826369D01*
G01Y823889D02*
X500234D01*
G01X497594Y826989D02*
X497901Y826886D01*
X498131Y826627D01*
X498284Y826317D01*
X498399Y825904D01*
X498437Y825439D01*
X498399Y824974D01*
X498284Y824561D01*
X498131Y824251D01*
X497901Y823992D01*
X497594Y823889D01*
X497287Y823992D01*
X497057Y824251D01*
X496904Y824561D01*
X496789Y824974D01*
X496751Y825439D01*
X496789Y825904D01*
X496904Y826317D01*
X497057Y826627D01*
X497287Y826886D01*
X497594Y826989D01*
G01X495337Y824354D02*
X495107Y824096D01*
X494839Y823941D01*
X494494Y823889D01*
X494149Y823992D01*
X493881Y824199D01*
X493689Y824561D01*
X493651Y824974D01*
X493727Y825387D01*
X493919Y825646D01*
X494187Y825852D01*
X494456Y825904D01*
X494724Y825852D01*
X495069Y825646D01*
X494954Y826989D01*
X493919D01*
G01X504204Y828627D02*
X498404D01*
G01X512004D02*
X506204D01*
G01X498404Y837427D02*
Y828627D01*
G01X505204Y830127D02*
X504204Y828627D01*
G01X506204D02*
X505204Y830127D01*
G01X512004Y837427D02*
X498404D01*
G01X502884Y842430D02*
X497084D01*
G01X510684D02*
X504884D01*
G01X497084Y851230D02*
Y842430D01*
G01X503884Y843930D02*
X502884Y842430D01*
G01X504884D02*
X503884Y843930D01*
G01X508606Y855566D02*
Y853344D01*
X508453Y852879D01*
X508146Y852569D01*
X507763Y852466D01*
X507380Y852569D01*
X507073Y852879D01*
X506920Y853344D01*
Y855566D01*
G01X504663Y852466D02*
Y855566D01*
X505123Y854946D01*
G01Y852466D02*
X504203D01*
G01X501563Y855566D02*
X501870Y855463D01*
X502100Y855204D01*
X502253Y854894D01*
X502368Y854481D01*
X502406Y854016D01*
X502368Y853551D01*
X502253Y853138D01*
X502100Y852828D01*
X501870Y852569D01*
X501563Y852466D01*
X501256Y852569D01*
X501026Y852828D01*
X500873Y853138D01*
X500758Y853551D01*
X500720Y854016D01*
X500758Y854481D01*
X500873Y854894D01*
X501026Y855204D01*
X501256Y855463D01*
X501563Y855566D01*
G01X498540Y852466D02*
X498463Y853138D01*
X498348Y853706D01*
X498195Y854223D01*
X498003Y854791D01*
X497696Y855566D01*
X499230D01*
G01X510684Y851230D02*
X497084D01*
G01X498034Y1025765D02*
X491834D01*
Y1022565D01*
X498034D01*
Y1025765D01*
G01X498022Y1029765D02*
X491822D01*
Y1026565D01*
X498022D01*
Y1029765D01*
G01X514831Y1090088D02*
Y1096088D01*
X502831D01*
Y1090088D01*
X514831D01*
G01X514689Y1082890D02*
Y1088890D01*
X502689D01*
Y1082890D01*
X514689D01*
G01X505810Y1112397D02*
Y1100397D01*
G01D02*
X511810D01*
G01X494772Y1113496D02*
Y1107296D01*
X497972D01*
Y1113496D01*
X494772D01*
G01X511810Y1112397D02*
X505810D01*
G01X505946Y1115247D02*
Y1127247D01*
G01X499946Y1115247D02*
X505946D01*
G01X499946Y1127247D02*
Y1115247D01*
G01X495972Y1120496D02*
X492772D01*
G01X495972Y1114296D02*
Y1120496D01*
G01X492772Y1114296D02*
X495972D01*
G01X492772Y1120496D02*
Y1114296D01*
G01X498957Y1121337D02*
Y1127537D01*
X495757D01*
Y1121337D01*
X498957D01*
G01X495132Y1121312D02*
Y1127512D01*
X491932D01*
Y1121312D01*
X495132D01*
G01X505946Y1127247D02*
X499946D01*
G01X504011Y1138272D02*
X520941D01*
G01X504011Y1174012D02*
Y1138272D01*
G01X493113D02*
Y1174012D01*
G01X495562Y1161539D02*
Y1149539D01*
G01X501562D02*
Y1161539D01*
G01X495562Y1149539D02*
X501562D01*
G01Y1161539D02*
X495562D01*
G01X520941Y1174012D02*
X504011D01*
G01X504009Y1175212D02*
Y1174012D01*
G01Y1175212D02*
X520992Y1175206D01*
G01X504009Y1174612D02*
X520984Y1174616D01*
G01X504009Y1174012D02*
X520949Y1174015D01*
G01X493114Y1175162D02*
X493110Y1173653D01*
G01X503136Y1189471D02*
Y1201471D01*
G01X497136Y1189471D02*
X503136D01*
G01X497136Y1201471D02*
Y1189471D01*
G01X503136Y1201471D02*
X497136D01*
G01X494468Y1219982D02*
Y1209782D01*
X499068D01*
Y1219982D01*
X494468D01*
G01X499902D02*
Y1209782D01*
X504502D01*
Y1219982D01*
X499902D01*
G01X491880Y1226455D02*
Y1215076D01*
G01X493172Y1230276D02*
Y1239176D01*
G01X493180Y1249202D02*
Y1266904D01*
G01X505559Y1249202D02*
X493180D01*
G01X491880Y1254376D02*
Y1241792D01*
G01X496501Y1263881D02*
Y1270081D01*
X493301D01*
Y1263881D01*
X496501D01*
G01X507328D02*
Y1270081D01*
X504128D01*
Y1263881D01*
X507328D01*
G01X501902D02*
Y1270081D01*
X498702D01*
Y1263881D01*
X501902D01*
G01X497199Y1276835D02*
Y1287035D01*
X492599D01*
Y1276835D01*
X497199D01*
G01X508326D02*
Y1287035D01*
X503726D01*
Y1276835D01*
X508326D01*
G01X502600D02*
Y1287035D01*
X498000D01*
Y1276835D01*
X502600D01*
G01X509312Y683678D02*
Y683778D01*
G01Y679178D02*
Y683778D01*
G01X516981Y684286D02*
Y690486D01*
G01X513781Y684286D02*
X516981D01*
G01X513781Y690486D02*
Y684286D01*
G01X515375Y678055D02*
X512175D01*
G01X515375Y671855D02*
Y678055D01*
G01X512175Y671855D02*
X515375D01*
G01X512175Y678055D02*
Y671855D01*
G01X519375Y678055D02*
X516175D01*
G01X519375Y671855D02*
Y678055D01*
G01X516175Y671855D02*
X519375D01*
G01X516175Y678055D02*
Y671855D01*
G01X520624Y669519D02*
X526824D01*
G01X520624Y672719D02*
Y669519D01*
G01X526824Y672719D02*
X520624D01*
G01X509412Y685678D02*
Y690278D01*
G01X510655Y690945D02*
Y695545D01*
G01X516981Y690486D02*
X513781D01*
G01X508741Y695805D02*
Y699005D01*
G01X519214Y720203D02*
Y715603D01*
G01D02*
X529414D01*
G01X521429Y715181D02*
Y711981D01*
G01X527629Y715181D02*
X521429D01*
G01Y711981D02*
X527629D01*
G01X507986Y711155D02*
Y714355D01*
G01X511391Y715816D02*
Y722016D01*
G01X508191Y715816D02*
X511391D01*
G01X508191Y722016D02*
Y715816D01*
G01X507391D02*
Y722016D01*
G01X507986Y707155D02*
Y710355D01*
G01Y703155D02*
Y706355D01*
G01X522383Y721283D02*
Y725883D01*
G01X512183Y721283D02*
X522383D01*
G01X512183Y725883D02*
Y721283D01*
G01X522383Y725883D02*
X512183D01*
G01X529414Y720203D02*
X519214D01*
G01X511391Y722016D02*
X508191D01*
G01X510841Y794549D02*
Y797749D01*
G01X510836Y801573D02*
Y798373D01*
G01X517036D02*
Y801573D01*
G01X510836Y798373D02*
X517036D01*
G01X521441Y808549D02*
X526041D01*
G01X521441Y818749D02*
Y808549D01*
G01X517036Y801573D02*
X510836D01*
G01Y813573D02*
Y810373D01*
G01X517036Y813573D02*
X510836D01*
G01X517036Y810373D02*
Y813573D01*
G01X510836Y810373D02*
X517036D01*
G01X510836Y805573D02*
Y802373D01*
G01X517036Y805573D02*
X510836D01*
G01X517036Y802373D02*
Y805573D01*
G01X510836Y802373D02*
X517036D01*
G01X510836Y809573D02*
Y806373D01*
G01X517036Y809573D02*
X510836D01*
G01X517036Y806373D02*
Y809573D01*
G01X510836Y806373D02*
X517036D01*
G01X526041Y818749D02*
X521441D01*
G01X512004Y828627D02*
Y837427D01*
G01X519357Y830062D02*
Y833262D01*
G01X513157Y830062D02*
X519357D01*
G01X513157Y833262D02*
Y830062D01*
G01X520604Y832627D02*
Y829427D01*
G01D02*
X526804D01*
G01X510684Y842430D02*
Y851230D01*
G01X519357Y833262D02*
X513157D01*
G01X526804Y832627D02*
X520604D01*
G01X520641Y842249D02*
Y839049D01*
G01X526841Y842249D02*
X520641D01*
G01Y839049D02*
X526841D01*
G01X520641Y837749D02*
Y834549D01*
G01X526841Y837749D02*
X520641D01*
G01Y834549D02*
X526841D01*
G01X520284Y851430D02*
Y848230D01*
G01X526484Y851430D02*
X520284D01*
G01Y848230D02*
X526484D01*
G01X522285Y878542D02*
Y884742D01*
G01X519085Y878542D02*
X522285D01*
G01X519085Y884742D02*
Y878542D01*
G01X517644Y875702D02*
X514444D01*
G01X517644Y869502D02*
Y875702D01*
G01X514444Y869502D02*
X517644D01*
G01X514444Y875702D02*
Y869502D01*
G01X522285Y884742D02*
X519085D01*
G01X512227Y899100D02*
Y895900D01*
G01X518427D02*
Y899100D01*
G01X512227Y895900D02*
X518427D01*
G01Y899100D02*
X512227D01*
G01X518427Y899900D02*
Y903100D01*
G01X512227Y899900D02*
X518427D01*
G01X512227Y903100D02*
Y899900D01*
G01X518427Y903100D02*
X512227D01*
G01X518427Y903900D02*
Y907100D01*
G01X512227Y903900D02*
X518427D01*
G01X512227Y907100D02*
Y903900D01*
G01X518427Y907100D02*
X512227D01*
G01X511810Y1100397D02*
Y1112397D01*
G01X513946Y1115247D02*
Y1127247D01*
G01X507946Y1115247D02*
X513946D01*
G01X507946Y1127247D02*
Y1115247D01*
G01X514710Y1109672D02*
X520910D01*
Y1112872D01*
X514710D01*
Y1109672D01*
G01X521600Y1114018D02*
Y1107818D01*
X524800D01*
Y1114018D01*
X521600D01*
G01X513946Y1127247D02*
X507946D01*
G01X512979Y1137574D02*
Y1135148D01*
G01X520941Y1138272D02*
Y1174012D01*
G01X512024Y1178837D02*
Y1176597D01*
G01X510399Y1177810D02*
X513649D01*
G01X520942Y1175162D02*
X520938Y1173653D01*
G01X510836Y1190371D02*
X515436D01*
G01X510836Y1200571D02*
Y1190371D01*
G01X515436Y1200571D02*
X510836D01*
G01X515436Y1190371D02*
Y1200571D01*
G01X513163Y1219982D02*
Y1209782D01*
X517763D01*
Y1219982D01*
X513163D01*
G01X507890D02*
Y1209782D01*
X512490D01*
Y1219982D01*
X507890D01*
G01X521394D02*
Y1209782D01*
X525994D01*
Y1219982D01*
X521394D01*
G01X532480Y1249202D02*
X521792D01*
G01X507980Y1247418D02*
X516880D01*
G01X507980Y1267704D02*
Y1247418D01*
G01X516880D02*
Y1267704D01*
G01X524539Y1263966D02*
Y1270166D01*
X521339D01*
Y1263966D01*
X524539D01*
G01X520731Y1263965D02*
Y1270165D01*
X517531D01*
Y1263965D01*
X520731D01*
G01X516880Y1267704D02*
X507980D01*
G01X525065Y1275645D02*
Y1285845D01*
X520465D01*
Y1275645D01*
X525065D01*
G01X519632D02*
Y1285845D01*
X515032D01*
Y1275645D01*
X519632D01*
G01X514176D02*
Y1285845D01*
X509576D01*
Y1275645D01*
X514176D01*
G01X538342Y70015D02*
Y73115D01*
G01X536732D02*
Y70015D01*
G01Y71565D02*
X538342D01*
G01X534437Y70015D02*
Y73115D01*
X534897Y72495D01*
G01Y70015D02*
X533977D01*
G01X532065Y72598D02*
X531835Y72908D01*
X531567Y73063D01*
X531260Y73115D01*
X530877Y73012D01*
X530609Y72753D01*
X530532Y72443D01*
X530570Y72133D01*
X530724Y71875D01*
X531490Y71358D01*
X531835Y70997D01*
X532065Y70480D01*
X532142Y70015D01*
X530532D01*
G01X528889Y70377D02*
X528620Y70118D01*
X528314Y70015D01*
X528007Y70118D01*
X527739Y70428D01*
X527547Y70893D01*
X527470Y71358D01*
Y71927D01*
X527547Y72392D01*
X527739Y72805D01*
X527969Y73012D01*
X528237Y73115D01*
X528544Y73012D01*
X528774Y72805D01*
X528927Y72495D01*
X529004Y72082D01*
X528927Y71720D01*
X528735Y71358D01*
X528505Y71152D01*
X528237Y71100D01*
X527930Y71203D01*
X527700Y71462D01*
X527470Y71927D01*
G01X530583Y599190D02*
Y602390D01*
G01X524383Y599190D02*
X530583D01*
G01X524383Y602390D02*
Y599190D01*
G01X530583Y602390D02*
X524383D01*
G01X533848Y682697D02*
Y688897D01*
G01X530648Y682697D02*
X533848D01*
G01X530648Y688897D02*
Y682697D01*
G01X526824Y669519D02*
Y672719D01*
G01X533848Y688897D02*
X530648D01*
G01X529414Y715603D02*
Y720203D01*
G01X531679Y710311D02*
Y707111D01*
G01X537879Y710311D02*
X531679D01*
G01X537879Y707111D02*
Y710311D01*
G01X531679Y707111D02*
X537879D01*
G01X527629Y711981D02*
Y715181D01*
G01X535423Y713642D02*
X538623D01*
G01X535423Y719842D02*
Y713642D01*
G01X538623D02*
Y719842D01*
G01X534623Y713642D02*
Y719842D01*
G01X531423Y713642D02*
X534623D01*
G01X531423Y719842D02*
Y713642D01*
G01X538623Y719842D02*
X535423D01*
G01X534623D02*
X531423D01*
G01X530104Y795589D02*
X540304D01*
G01X530104Y800189D02*
Y795589D01*
G01X526841Y798249D02*
X523641D01*
G01X526841Y792049D02*
Y798249D01*
G01X523641Y792049D02*
X526841D01*
G01X523641Y798249D02*
Y792049D01*
G01X538841Y791049D02*
Y794249D01*
G01X532641Y791049D02*
X538841D01*
G01X532641Y794249D02*
Y791049D01*
G01X538841Y794249D02*
X532641D01*
G01X530204Y805689D02*
Y801089D01*
G01D02*
X540204D01*
G01X530204Y801189D02*
Y801089D01*
G01X540204Y805689D02*
X530204D01*
G01X540304Y800189D02*
X530104D01*
G01X526041Y808549D02*
Y818749D01*
G01X527141Y811049D02*
X530341D01*
G01X527141Y817249D02*
Y811049D01*
G01X530341D02*
Y817249D01*
G01D02*
X527141D01*
G01X535841Y827249D02*
X532641D01*
G01X535841Y821049D02*
Y827249D01*
G01X532641Y821049D02*
X535841D01*
G01X532641Y827249D02*
Y821049D01*
G01X527341Y825749D02*
X524141D01*
G01X527341Y819549D02*
Y825749D01*
G01X524141Y819549D02*
X527341D01*
G01X524141Y825749D02*
Y819549D01*
G01X527604Y832627D02*
Y829427D01*
G01X533804D02*
Y832627D01*
G01X527604Y829427D02*
X533804D01*
G01X526804D02*
Y832627D01*
G01X533804D02*
X527604D01*
G01X527641Y837749D02*
Y834549D01*
G01X533841Y837749D02*
X527641D01*
G01X533841Y834549D02*
Y837749D01*
G01X527641Y834549D02*
X533841D01*
G01X527641Y842249D02*
Y839049D01*
G01X533841Y842249D02*
X527641D01*
G01X533841Y839049D02*
Y842249D01*
G01X527641Y839049D02*
X533841D01*
G01X526841D02*
Y842249D01*
G01Y834549D02*
Y837749D01*
G01X527284Y851430D02*
Y848230D01*
G01X533484Y851430D02*
X527284D01*
G01X533484Y848230D02*
Y851430D01*
G01X527284Y848230D02*
X533484D01*
G01X526484D02*
Y851430D01*
G01X530393Y875008D02*
Y878208D01*
G01X524193Y875008D02*
X530393D01*
G01X524193Y878208D02*
Y875008D01*
G01X530393Y878208D02*
X524193D01*
G01X537505Y873259D02*
Y876459D01*
G01X531305Y873259D02*
X537505D01*
G01X531305Y876459D02*
Y873259D01*
G01X537505Y876459D02*
X531305D01*
G01X524918Y891833D02*
Y886833D01*
G01X527118Y894033D02*
X524918Y891833D01*
G01Y896233D02*
X527118Y894033D01*
G01X524918Y901233D02*
Y896233D01*
G01Y886833D02*
X544518Y886883D01*
G01Y901233D02*
X524918D01*
G01X526900Y1113496D02*
Y1107296D01*
X530100D01*
Y1113496D01*
X526900D01*
G01X528100Y1120496D02*
X524900D01*
G01X528100Y1114296D02*
Y1120496D01*
G01X524900Y1114296D02*
X528100D01*
G01X524900Y1120496D02*
Y1114296D01*
G01X532480Y1266904D02*
Y1249202D01*
G01X532053Y1264032D02*
Y1270232D01*
X528853D01*
Y1264032D01*
X532053D01*
G01X528325Y1264006D02*
Y1270206D01*
X525125D01*
Y1264006D01*
X528325D01*
G01X530436Y1275645D02*
Y1285845D01*
X525836D01*
Y1275645D01*
X530436D01*
G01X545544Y462144D02*
Y540884D01*
G01X624284Y462144D02*
X545544D01*
G01Y540884D02*
X545716D01*
G01X545628D02*
X624284D01*
G01X544739Y689436D02*
Y679436D01*
G01X549339D02*
Y689436D01*
G01X549239Y679436D02*
X549339D01*
G01X544739D02*
X549339D01*
G01X544384Y679259D02*
Y689459D01*
G01X539784Y679259D02*
X544384D01*
G01X539784Y689459D02*
Y679259D01*
G01X544739Y689436D02*
X549339D01*
G01X544384Y689459D02*
X539784D01*
G01X540304Y795589D02*
Y800189D01*
G01X550604Y797989D02*
Y794789D01*
G01X556804Y797989D02*
X550604D01*
G01Y794789D02*
X556804D01*
G01X557774Y792515D02*
X554574D01*
G01Y786315D02*
X557774D01*
G01X554574Y792515D02*
Y786315D01*
G01X544141Y797049D02*
X547341D01*
G01X544141Y803249D02*
Y797049D01*
G01X547341D02*
Y803249D01*
G01X549704Y804589D02*
X559704D01*
G01Y809189D02*
X549704D01*
G01Y804589D02*
Y809189D01*
G01X540204Y805689D02*
Y801089D01*
G01X549604Y803689D02*
Y799089D01*
G01X559804Y803689D02*
X549604D01*
G01Y799089D02*
X559804D01*
G01X547341Y803249D02*
X544141D01*
G01X552645Y824820D02*
X550423D01*
X549958Y824973D01*
X549648Y825280D01*
X549545Y825663D01*
X549648Y826046D01*
X549958Y826353D01*
X550423Y826506D01*
X552645D01*
G01X549545Y828763D02*
X552645D01*
X552025Y828303D01*
G01X549545D02*
Y829223D01*
G01X552645Y831863D02*
X552542Y831556D01*
X552283Y831326D01*
X551973Y831173D01*
X551560Y831058D01*
X551095Y831020D01*
X550630Y831058D01*
X550217Y831173D01*
X549907Y831326D01*
X549648Y831556D01*
X549545Y831863D01*
X549648Y832170D01*
X549907Y832400D01*
X550217Y832553D01*
X550630Y832668D01*
X551095Y832706D01*
X551560Y832668D01*
X551973Y832553D01*
X552283Y832400D01*
X552542Y832170D01*
X552645Y831863D01*
G01X550837Y834235D02*
X551198Y834503D01*
X551405Y834733D01*
X551508Y835040D01*
X551405Y835308D01*
X551198Y835500D01*
X550888Y835653D01*
X550527Y835691D01*
X550217Y835653D01*
X549907Y835500D01*
X549648Y835270D01*
X549545Y835001D01*
X549648Y834695D01*
X549958Y834426D01*
X550423Y834273D01*
X550940Y834235D01*
X551612Y834311D01*
X551973Y834426D01*
X552335Y834618D01*
X552593Y834886D01*
X552645Y835155D01*
X552542Y835423D01*
X552283Y835615D01*
G01X553841Y823349D02*
X562641D01*
G01X553841Y836949D02*
Y823349D01*
G01X545804Y829289D02*
Y832489D01*
G01X539604Y829289D02*
X545804D01*
G01X539604Y832489D02*
Y829289D01*
G01X562641Y836949D02*
X553841D01*
G01X545804Y832489D02*
X539604D01*
G01X545804Y833789D02*
Y836989D01*
G01X539604Y833789D02*
X545804D01*
G01X539604Y836989D02*
Y833789D01*
G01X545804Y836989D02*
X539604D01*
G01X550265Y843218D02*
Y849418D01*
G01X547065Y843218D02*
X550265D01*
G01X547065Y849418D02*
Y843218D01*
G01X551065D02*
X554265D01*
G01X551065Y849418D02*
Y843218D01*
G01X554265D02*
Y849418D01*
G01X550265D02*
X547065D01*
G01X554265D02*
X551065D01*
G01X551129Y880794D02*
Y877594D01*
G01D02*
X557329D01*
G01X551129Y876794D02*
Y873594D01*
G01X557329Y876794D02*
X551129D01*
G01Y873594D02*
X557329D01*
G01X557595Y872881D02*
X554395D01*
G01Y866681D02*
X557595D01*
G01X554395Y872881D02*
Y866681D01*
G01X553502Y872914D02*
X550302D01*
G01X553502Y866714D02*
Y872914D01*
G01X550302Y866714D02*
X553502D01*
G01X550302Y872914D02*
Y866714D01*
G01X557329Y880794D02*
X551129D01*
G01X549927Y895900D02*
Y902100D01*
G01X546727Y895900D02*
X549927D01*
G01X546727Y902100D02*
Y895900D01*
G01X551783Y888774D02*
X554983D01*
G01X551783Y894974D02*
Y888774D01*
G01X554983Y894974D02*
X551783D01*
G01X554983Y888774D02*
Y894974D01*
G01X553892Y895900D02*
Y902100D01*
G01X550692Y895900D02*
X553892D01*
G01X550692Y902100D02*
Y895900D01*
G01X549233Y882333D02*
X547011D01*
X546546Y882486D01*
X546236Y882793D01*
X546133Y883176D01*
X546236Y883559D01*
X546546Y883866D01*
X547011Y884019D01*
X549233D01*
G01X547425Y885548D02*
X547786Y885816D01*
X547993Y886046D01*
X548096Y886353D01*
X547993Y886621D01*
X547786Y886813D01*
X547476Y886966D01*
X547115Y887004D01*
X546805Y886966D01*
X546495Y886813D01*
X546236Y886583D01*
X546133Y886314D01*
X546236Y886008D01*
X546546Y885739D01*
X547011Y885586D01*
X547528Y885548D01*
X548200Y885624D01*
X548561Y885739D01*
X548923Y885931D01*
X549181Y886199D01*
X549233Y886468D01*
X549130Y886736D01*
X548871Y886928D01*
G01X547425Y888648D02*
X547786Y888916D01*
X547993Y889146D01*
X548096Y889453D01*
X547993Y889721D01*
X547786Y889913D01*
X547476Y890066D01*
X547115Y890104D01*
X546805Y890066D01*
X546495Y889913D01*
X546236Y889683D01*
X546133Y889414D01*
X546236Y889108D01*
X546546Y888839D01*
X547011Y888686D01*
X547528Y888648D01*
X548200Y888724D01*
X548561Y888839D01*
X548923Y889031D01*
X549181Y889299D01*
X549233Y889568D01*
X549130Y889836D01*
X548871Y890028D01*
G01X544518Y886883D02*
Y901233D01*
G01X549927Y902100D02*
X546727D01*
G01X553892D02*
X550692D01*
G01X542593Y1062411D02*
G03X605314Y1066535I31225J4124D01*
G01X564696Y1096681D02*
G03X550192Y1087363I9122J-30146D01*
G01X605314Y1263386D02*
G03X595532Y1240572I-31495J0D01*
G01X552599Y1689331D02*
Y1425158D01*
G01X556804Y794789D02*
Y797989D01*
G01X557774Y786315D02*
Y792515D01*
G01X559704Y809089D02*
Y809189D01*
G01Y804589D02*
Y809189D01*
G01X559804Y799089D02*
Y803689D01*
G01X568641Y801549D02*
X571841D01*
G01X568641Y807749D02*
Y801549D01*
G01X571841Y807749D02*
X568641D01*
G01X561141Y830149D02*
X562641Y829149D01*
G01Y831149D02*
X561141Y830149D01*
G01X562641Y836949D02*
Y831149D01*
G01Y829149D02*
Y823349D01*
G01X568641Y823049D02*
X571841D01*
G01X568641Y829249D02*
Y823049D01*
G01X571841Y829249D02*
X568641D01*
G01X559841Y845249D02*
X556641D01*
G01X559841Y839049D02*
Y845249D01*
G01X556641Y839049D02*
X559841D01*
G01X556641Y845249D02*
Y839049D01*
G01X560631Y843196D02*
X563831D01*
G01X560631Y849396D02*
Y843196D01*
G01X563831D02*
Y849396D01*
G01X567831Y843196D02*
Y849396D01*
G01X564631Y843196D02*
X567831D01*
G01X564631Y849396D02*
Y843196D01*
G01X563831Y849396D02*
X560631D01*
G01X567831D02*
X564631D01*
G01X557329Y877594D02*
Y880794D01*
G01Y873594D02*
Y876794D01*
G01X557595Y866681D02*
Y872881D01*
G01X570933Y890445D02*
Y887245D01*
G01X577133Y890445D02*
X570933D01*
G01Y887245D02*
X577133D01*
G01X570933Y886445D02*
Y883245D01*
G01X577133Y886445D02*
X570933D01*
G01Y883245D02*
X577133D01*
G01X570933Y894445D02*
Y891245D01*
G01X577133Y894445D02*
X570933D01*
G01Y891245D02*
X577133D01*
G01X564503Y960907D02*
Y954707D01*
X567703D01*
Y960907D01*
X564503D01*
G01X593812Y90569D02*
Y93669D01*
G01X592202D02*
Y90569D01*
G01Y92119D02*
X593812D01*
G01X589907Y90569D02*
Y93669D01*
X590367Y93049D01*
G01Y90569D02*
X589447D01*
G01X586807D02*
Y93669D01*
X587267Y93049D01*
G01Y90569D02*
X586347D01*
G01X583707Y93669D02*
X584014Y93566D01*
X584244Y93307D01*
X584397Y92997D01*
X584512Y92584D01*
X584550Y92119D01*
X584512Y91654D01*
X584397Y91241D01*
X584244Y90931D01*
X584014Y90672D01*
X583707Y90569D01*
X583400Y90672D01*
X583170Y90931D01*
X583017Y91241D01*
X582902Y91654D01*
X582864Y92119D01*
X582902Y92584D01*
X583017Y92997D01*
X583170Y93307D01*
X583400Y93566D01*
X583707Y93669D01*
G01X577967Y795210D02*
X575745D01*
X575280Y795363D01*
X574970Y795670D01*
X574867Y796053D01*
X574970Y796436D01*
X575280Y796743D01*
X575745Y796896D01*
X577967D01*
G01X574867Y799153D02*
X577967D01*
X577347Y798693D01*
G01X574867D02*
Y799613D01*
G01X577967Y802253D02*
X577864Y801946D01*
X577605Y801716D01*
X577295Y801563D01*
X576882Y801448D01*
X576417Y801410D01*
X575952Y801448D01*
X575539Y801563D01*
X575229Y801716D01*
X574970Y801946D01*
X574867Y802253D01*
X574970Y802560D01*
X575229Y802790D01*
X575539Y802943D01*
X575952Y803058D01*
X576417Y803096D01*
X576882Y803058D01*
X577295Y802943D01*
X577605Y802790D01*
X577864Y802560D01*
X577967Y802253D01*
G01X574867Y805813D02*
X577967D01*
X575745Y804395D01*
Y806311D01*
G01X579101Y794248D02*
X587901D01*
G01X579101Y807848D02*
Y794248D01*
G01X586401Y801048D02*
X587901Y800048D01*
G01Y802048D02*
X586401Y801048D01*
G01X587901Y807848D02*
X579101D01*
G01X585101Y809448D02*
Y815648D01*
G01X581901Y809448D02*
X585101D01*
G01X581901Y815648D02*
Y809448D01*
G01X571841Y801549D02*
Y807749D01*
G01X575901Y814948D02*
X579101D01*
G01X575901Y821148D02*
Y814948D01*
G01X579101D02*
Y821148D01*
G01X586401Y814948D02*
X589601D01*
G01X586401Y821148D02*
Y814948D01*
G01X585101Y815648D02*
X581901D01*
G01X571841Y823049D02*
Y829249D01*
G01X579101Y821148D02*
X575901D01*
G01X589601D02*
X586401D01*
G01X575901Y821948D02*
X579101D01*
G01X575901Y828148D02*
Y821948D01*
G01X579101Y828148D02*
X575901D01*
G01X579101Y821948D02*
Y828148D01*
G01X586401Y821948D02*
X589601D01*
G01X586401Y828148D02*
Y821948D01*
G01X589601Y828148D02*
X586401D01*
G01X577133Y887245D02*
Y890445D01*
G01Y883245D02*
Y886445D01*
G01Y891245D02*
Y894445D01*
G01X586903Y938407D02*
X580703D01*
Y935207D01*
X586903D01*
Y938407D01*
G01X576300Y960204D02*
X582500D01*
Y963404D01*
X576300D01*
Y960204D01*
G01X597680Y1087092D02*
G03X579840Y1097450I-23862J-20557D01*
G01X587901Y800048D02*
Y794248D01*
G01Y807848D02*
Y802048D01*
G01X589601Y814948D02*
Y821148D01*
G01Y821948D02*
Y828148D01*
G01X611207Y1508106D02*
X603707D01*
Y1505866D01*
X604082Y1505119D01*
X604957Y1504559D01*
X605957Y1504372D01*
X606957Y1504559D01*
X607707Y1505026D01*
X608082Y1505866D01*
Y1508106D01*
G01X611207Y1500606D02*
X603707D01*
Y1498272D01*
X604082Y1497526D01*
X604582Y1497059D01*
X605582Y1496872D01*
X606582Y1497059D01*
X607207Y1497619D01*
X607582Y1498272D01*
Y1500606D01*
G01Y1498272D02*
X611207Y1496872D01*
G01Y1489372D02*
Y1493106D01*
X603707D01*
Y1489372D01*
G01X607332Y1490866D02*
Y1493106D01*
G01X610207Y1485699D02*
X610832Y1484952D01*
X611207Y1484112D01*
Y1483366D01*
X610832Y1482619D01*
X610207Y1482059D01*
X609332Y1481779D01*
X608457Y1481966D01*
X607707Y1482432D01*
X607207Y1483272D01*
X606957Y1484392D01*
X606457Y1485046D01*
X605582Y1485326D01*
X604707Y1485139D01*
X604082Y1484672D01*
X603707Y1484019D01*
Y1483366D01*
X603957Y1482712D01*
X604582Y1482152D01*
G01X610207Y1478199D02*
X610832Y1477452D01*
X611207Y1476612D01*
Y1475866D01*
X610832Y1475119D01*
X610207Y1474559D01*
X609332Y1474279D01*
X608457Y1474466D01*
X607707Y1474932D01*
X607207Y1475772D01*
X606957Y1476892D01*
X606457Y1477546D01*
X605582Y1477826D01*
X604707Y1477639D01*
X604082Y1477172D01*
X603707Y1476519D01*
Y1475866D01*
X603957Y1475212D01*
X604582Y1474652D01*
G01X608707Y1469952D02*
Y1467526D01*
G01X611207Y1463012D02*
X603707D01*
Y1459466D01*
G01X607332Y1460772D02*
Y1463012D01*
G01X603707Y1454859D02*
Y1452619D01*
G01Y1453739D02*
X611207D01*
G01Y1454859D02*
Y1452619D01*
G01X603707Y1446239D02*
X611207D01*
G01X603707Y1448386D02*
Y1444092D01*
G01X605312Y1747174D02*
Y1746624D01*
X595312D01*
G01Y1754124D02*
Y1759124D01*
G01Y1746624D02*
Y1749124D01*
G01Y1764124D02*
Y1766624D01*
X605312D01*
Y1766074D01*
G01Y1793174D02*
Y1792624D01*
X595312D01*
G01Y1800124D02*
Y1805124D01*
G01Y1792624D02*
Y1795124D01*
G01Y1810124D02*
Y1812624D01*
X605312D01*
Y1812074D01*
G01X605314Y1066535D02*
G03X604581Y1073290I-31496J0D01*
G01X611786Y1133809D02*
X614986D01*
G01X611786Y1140009D02*
Y1133809D01*
G01X614986Y1140009D02*
X611786D01*
G01X614986Y1133809D02*
Y1140009D01*
G01X622466D02*
X619266D01*
G01Y1133809D02*
X622466D01*
G01X619266Y1140009D02*
Y1133809D01*
G01X615526D02*
X618726D01*
G01X615526Y1140009D02*
Y1133809D01*
G01X618726Y1140009D02*
X615526D01*
G01X618726Y1133809D02*
Y1140009D01*
G01X611692Y1150130D02*
Y1146930D01*
G01X617892Y1150130D02*
X611692D01*
G01X617892Y1146930D02*
Y1150130D01*
G01X611692Y1146930D02*
X617892D01*
G01X611936Y1162250D02*
Y1159050D01*
G01X618136Y1162250D02*
X611936D01*
G01X618136Y1159050D02*
Y1162250D01*
G01X611936Y1159050D02*
X618136D01*
G01X612151Y1170700D02*
Y1167500D01*
G01X618351Y1170700D02*
X612151D01*
G01X618351Y1167500D02*
Y1170700D01*
G01X612151Y1167500D02*
X618351D01*
G01X612151Y1166160D02*
Y1162960D01*
G01X618351Y1166160D02*
X612151D01*
G01X618351Y1162960D02*
Y1166160D01*
G01X612151Y1162960D02*
X618351D01*
G01X605214Y1260873D02*
G03X605314Y1263386I-31395J2508D01*
G01X612835Y1425158D02*
Y1689331D01*
G01X725827Y1425158D02*
X612835D01*
G01Y1689331D02*
X725827D01*
G01X615483Y1760261D02*
X612383Y1758651D01*
G01Y1760261D02*
X615483Y1758651D01*
G01X615018Y1757199D02*
X615276Y1756969D01*
X615431Y1756701D01*
X615483Y1756356D01*
X615380Y1756011D01*
X615173Y1755743D01*
X614811Y1755551D01*
X614398Y1755513D01*
X613985Y1755589D01*
X613726Y1755781D01*
X613520Y1756049D01*
X613468Y1756318D01*
X613520Y1756586D01*
X613726Y1756931D01*
X612383Y1756816D01*
Y1755781D01*
G01X614191Y1753984D02*
X613830Y1753716D01*
X613623Y1753486D01*
X613520Y1753179D01*
X613623Y1752911D01*
X613830Y1752719D01*
X614140Y1752566D01*
X614501Y1752528D01*
X614811Y1752566D01*
X615121Y1752719D01*
X615380Y1752949D01*
X615483Y1753218D01*
X615380Y1753524D01*
X615070Y1753793D01*
X614605Y1753946D01*
X614088Y1753984D01*
X613416Y1753908D01*
X613055Y1753793D01*
X612693Y1753601D01*
X612435Y1753333D01*
X612383Y1753064D01*
X612486Y1752796D01*
X612745Y1752604D01*
G01X605312Y1757174D02*
Y1756074D01*
G01X629861Y1749265D02*
Y1746765D01*
X619861D01*
Y1747315D01*
G01Y1756215D02*
Y1757315D01*
G01Y1766215D02*
Y1766765D01*
X629861D01*
G01X613640Y1805932D02*
X610540Y1804322D01*
G01Y1805932D02*
X613640Y1804322D01*
G01X611057Y1802755D02*
X610747Y1802525D01*
X610592Y1802257D01*
X610540Y1801950D01*
X610643Y1801567D01*
X610902Y1801299D01*
X611212Y1801222D01*
X611522Y1801260D01*
X611780Y1801414D01*
X612297Y1802180D01*
X612658Y1802525D01*
X613175Y1802755D01*
X613640Y1802832D01*
Y1801222D01*
G01Y1799004D02*
X612968Y1798927D01*
X612400Y1798812D01*
X611883Y1798659D01*
X611315Y1798467D01*
X610540Y1798160D01*
Y1799694D01*
G01X605312Y1803174D02*
Y1802074D01*
G01X629475Y1796345D02*
Y1793845D01*
X619475D01*
Y1794395D01*
G01Y1803295D02*
Y1804395D01*
G01Y1813295D02*
Y1813845D01*
X629475D01*
G01X637441Y70015D02*
Y73115D01*
G01X635831D02*
Y70015D01*
G01Y71565D02*
X637441D01*
G01X633536Y70015D02*
Y73115D01*
X633996Y72495D01*
G01Y70015D02*
X633076D01*
G01X630436Y73115D02*
X630743Y73012D01*
X630973Y72753D01*
X631126Y72443D01*
X631241Y72030D01*
X631279Y71565D01*
X631241Y71100D01*
X631126Y70687D01*
X630973Y70377D01*
X630743Y70118D01*
X630436Y70015D01*
X630129Y70118D01*
X629899Y70377D01*
X629746Y70687D01*
X629631Y71100D01*
X629593Y71565D01*
X629631Y72030D01*
X629746Y72443D01*
X629899Y72753D01*
X630129Y73012D01*
X630436Y73115D01*
G01X627988Y70377D02*
X627719Y70118D01*
X627413Y70015D01*
X627106Y70118D01*
X626838Y70428D01*
X626646Y70893D01*
X626569Y71358D01*
Y71927D01*
X626646Y72392D01*
X626838Y72805D01*
X627068Y73012D01*
X627336Y73115D01*
X627643Y73012D01*
X627873Y72805D01*
X628026Y72495D01*
X628103Y72082D01*
X628026Y71720D01*
X627834Y71358D01*
X627604Y71152D01*
X627336Y71100D01*
X627029Y71203D01*
X626799Y71462D01*
X626569Y71927D01*
G01X624284Y540884D02*
Y462144D01*
G01X635586Y552000D02*
Y548800D01*
G01X641786Y552000D02*
X635586D01*
G01Y548800D02*
X641786D01*
G01X635586Y556000D02*
Y552800D01*
G01D02*
X641786D01*
G01Y556000D02*
X635586D01*
G01X633146Y1123758D02*
Y1128358D01*
G01X622946Y1123758D02*
X633146D01*
G01X622946Y1128358D02*
Y1123758D01*
G01X633146Y1128358D02*
X622946D01*
G01X622466Y1133809D02*
Y1140009D01*
G01X629861Y1759265D02*
Y1754265D01*
G01X630216Y1767965D02*
X628606Y1771065D01*
G01X630216D02*
X628606Y1767965D01*
G01X626388D02*
X626311Y1768637D01*
X626196Y1769205D01*
X626043Y1769722D01*
X625851Y1770290D01*
X625544Y1771065D01*
X627078D01*
G01X623939Y1769257D02*
X623671Y1769618D01*
X623441Y1769825D01*
X623134Y1769928D01*
X622866Y1769825D01*
X622674Y1769618D01*
X622521Y1769308D01*
X622483Y1768947D01*
X622521Y1768637D01*
X622674Y1768327D01*
X622904Y1768068D01*
X623173Y1767965D01*
X623479Y1768068D01*
X623748Y1768378D01*
X623901Y1768843D01*
X623939Y1769360D01*
X623863Y1770032D01*
X623748Y1770393D01*
X623556Y1770755D01*
X623288Y1771013D01*
X623019Y1771065D01*
X622751Y1770962D01*
X622559Y1770703D01*
G01X629861Y1766765D02*
Y1764265D01*
G01X629475Y1806345D02*
Y1801345D01*
G01X629830Y1815045D02*
X628220Y1818145D01*
G01X629830D02*
X628220Y1815045D01*
G01X626002D02*
X625925Y1815717D01*
X625810Y1816285D01*
X625657Y1816802D01*
X625465Y1817370D01*
X625158Y1818145D01*
X626692D01*
G01X622825Y1815045D02*
X622557Y1815097D01*
X622250Y1815252D01*
X622058Y1815510D01*
X621982Y1815872D01*
X622058Y1816233D01*
X622288Y1816543D01*
X622633Y1816698D01*
X623017D01*
X623247Y1816802D01*
X623438Y1817060D01*
X623515Y1817422D01*
X623400Y1817783D01*
X623132Y1818042D01*
X622825Y1818145D01*
X622518Y1818042D01*
X622250Y1817783D01*
X622135Y1817422D01*
X622212Y1817060D01*
X622403Y1816802D01*
X622633Y1816698D01*
X623017D01*
X623362Y1816543D01*
X623592Y1816233D01*
X623668Y1815872D01*
X623592Y1815510D01*
X623400Y1815252D01*
X623093Y1815097D01*
X622825Y1815045D01*
G01X629475Y1813845D02*
Y1811345D01*
G01X652768Y254685D02*
Y333425D01*
G01X731508Y254685D02*
X652768D01*
G01Y333425D02*
X652940D01*
G01X652852D02*
X731508D01*
G01X641786Y548800D02*
Y552000D01*
G01Y552800D02*
Y556000D01*
G01X646372Y546567D02*
Y543367D01*
G01X652572Y546567D02*
X646372D01*
G01X652572Y543367D02*
Y546567D01*
G01X646372Y543367D02*
X652572D01*
G01X649086Y592800D02*
X655286D01*
G01X649086Y596000D02*
Y592800D01*
G01X655286Y596000D02*
X649086D01*
G01Y600800D02*
X655286D01*
G01X649086Y604000D02*
Y600800D01*
G01X655286Y604000D02*
X649086D01*
G01Y596800D02*
X655286D01*
G01X649086Y600000D02*
Y596800D01*
G01X655286Y600000D02*
X649086D01*
G01Y604800D02*
X655286D01*
G01X649086Y608000D02*
Y604800D01*
G01X655286Y608000D02*
X649086D01*
G01Y608800D02*
X655286D01*
G01X649086Y612000D02*
Y608800D01*
G01X655286Y612000D02*
X649086D01*
G01Y612800D02*
X655286D01*
G01X649086Y616000D02*
Y612800D01*
G01X655286Y616000D02*
X649086D01*
G01Y620000D02*
Y616800D01*
G01X655286Y620000D02*
X649086D01*
G01Y616800D02*
X655286D01*
G01X652559Y669661D02*
Y748401D01*
G01X731299Y669661D02*
X652559D01*
G01Y748401D02*
X652731D01*
G01X652643D02*
X731299D01*
G01X650456Y1186789D02*
Y1191389D01*
G01X640256Y1186789D02*
X650456D01*
G01X640256Y1191389D02*
Y1186789D01*
G01X650456Y1191389D02*
X640256D01*
G01X653372Y546567D02*
Y543367D01*
G01X659572Y546567D02*
X653372D01*
G01X659572Y543367D02*
Y546567D01*
G01X653372Y543367D02*
X659572D01*
G01X667789Y550147D02*
Y559447D01*
G01X678389Y550147D02*
X667789D01*
G01Y559547D02*
X678389D01*
G01X655286Y592800D02*
Y596000D01*
G01Y600800D02*
Y604000D01*
G01Y596800D02*
Y600000D01*
G01Y604800D02*
Y608000D01*
G01Y608800D02*
Y612000D01*
G01Y612800D02*
Y616000D01*
G01Y616800D02*
Y620000D01*
G01X663129Y1159991D02*
X673329D01*
G01X663129Y1164591D02*
Y1159991D01*
G01X673329Y1164591D02*
X663129D01*
G01X696292Y90332D02*
Y93432D01*
G01X694682D02*
Y90332D01*
G01Y91882D02*
X696292D01*
G01X692387Y90332D02*
Y93432D01*
X692847Y92812D01*
G01Y90332D02*
X691927D01*
G01X689287D02*
Y93432D01*
X689747Y92812D01*
G01Y90332D02*
X688827D01*
G01X686839Y90694D02*
X686570Y90435D01*
X686264Y90332D01*
X685957Y90435D01*
X685689Y90745D01*
X685497Y91210D01*
X685420Y91675D01*
Y92244D01*
X685497Y92709D01*
X685689Y93122D01*
X685919Y93329D01*
X686187Y93432D01*
X686494Y93329D01*
X686724Y93122D01*
X686877Y92812D01*
X686954Y92399D01*
X686877Y92037D01*
X686685Y91675D01*
X686455Y91469D01*
X686187Y91417D01*
X685880Y91520D01*
X685650Y91779D01*
X685420Y92244D01*
G01X675986Y534900D02*
X679186D01*
G01X675986Y541100D02*
Y534900D01*
G01X679186D02*
Y541100D01*
G01Y548600D02*
X675986D01*
G01X679186Y542400D02*
Y548600D01*
G01X675986Y542400D02*
X679186D01*
G01X675986Y548600D02*
Y542400D01*
G01X679186Y541100D02*
X675986D01*
G01X678389Y559547D02*
Y550147D01*
G01X678915Y563923D02*
Y561701D01*
X678762Y561236D01*
X678455Y560926D01*
X678072Y560823D01*
X677689Y560926D01*
X677382Y561236D01*
X677229Y561701D01*
Y563923D01*
G01X674972Y560823D02*
Y563923D01*
X675432Y563303D01*
G01Y560823D02*
X674512D01*
G01X671872D02*
X671604Y560875D01*
X671297Y561030D01*
X671105Y561288D01*
X671029Y561650D01*
X671105Y562011D01*
X671335Y562321D01*
X671680Y562476D01*
X672064D01*
X672294Y562580D01*
X672485Y562838D01*
X672562Y563200D01*
X672447Y563561D01*
X672179Y563820D01*
X671872Y563923D01*
X671565Y563820D01*
X671297Y563561D01*
X671182Y563200D01*
X671259Y562838D01*
X671450Y562580D01*
X671680Y562476D01*
X672064D01*
X672409Y562321D01*
X672639Y562011D01*
X672715Y561650D01*
X672639Y561288D01*
X672447Y561030D01*
X672140Y560875D01*
X671872Y560823D01*
G01X678090Y1159991D02*
X688290D01*
G01X678090Y1164591D02*
Y1159991D01*
G01X688290Y1164591D02*
X678090D01*
G01X673329Y1159991D02*
Y1164591D01*
G01X679439Y1212352D02*
X682639D01*
G01X679439Y1218552D02*
Y1212352D01*
G01X682639Y1218552D02*
X679439D01*
G01X682639Y1212352D02*
Y1218552D01*
G01X695419Y764871D02*
X701619D01*
G01X695419Y768071D02*
Y764871D01*
G01Y764571D02*
Y761371D01*
G01X701619Y764571D02*
X695419D01*
G01Y761371D02*
X701619D01*
G01X695419Y758571D02*
Y755371D01*
G01X701619Y758571D02*
X695419D01*
G01Y755371D02*
X701619D01*
G01X695419Y751871D02*
X701619D01*
G01X695419Y755071D02*
Y751871D01*
G01X701619Y755071D02*
X695419D01*
G01X701619Y768071D02*
X695419D01*
G01X695405Y782259D02*
Y779059D01*
G01X701605Y782259D02*
X695405D01*
G01Y779059D02*
X701605D01*
G01X695405Y776759D02*
Y773559D01*
G01X701605Y776759D02*
X695405D01*
G01Y773559D02*
X701605D01*
G01X695405Y769559D02*
X701605D01*
G01X695405Y772759D02*
Y769559D01*
G01X701605Y772759D02*
X695405D01*
G01Y783059D02*
X701605D01*
G01X695405Y786259D02*
Y783059D01*
G01X701605Y786259D02*
X695405D01*
G01X692331Y1121610D02*
Y1131810D01*
G01X687731Y1121610D02*
X692331D01*
G01X687731Y1131810D02*
Y1121610D01*
G01X692331Y1131810D02*
X687731D01*
G01X696791Y1159991D02*
X706991D01*
G01X696791Y1164591D02*
Y1159991D01*
G01X706991Y1164591D02*
X696791D01*
G01X688290Y1159991D02*
Y1164591D01*
G01X687703Y1197884D02*
X692303D01*
G01X687703Y1208084D02*
Y1197884D01*
G01X692303D02*
Y1208084D01*
G01D02*
X687703D01*
G01X707863Y-42093D02*
Y-45193D01*
X708629D01*
X708936Y-45038D01*
X709166Y-44831D01*
X709358Y-44521D01*
X709511Y-44160D01*
X709549Y-43643D01*
X709511Y-43126D01*
X709358Y-42765D01*
X709166Y-42455D01*
X708936Y-42248D01*
X708629Y-42093D01*
X707863D01*
G01X712573D02*
X711039D01*
Y-45193D01*
X712573D01*
G01X711959Y-43695D02*
X711039D01*
G01X714906Y-42093D02*
Y-45193D01*
X714446Y-44573D01*
G01Y-42093D02*
X715366D01*
G01X717278Y-44676D02*
X717508Y-44986D01*
X717776Y-45141D01*
X718083Y-45193D01*
X718466Y-45090D01*
X718734Y-44831D01*
X718811Y-44521D01*
X718773Y-44211D01*
X718619Y-43953D01*
X717853Y-43436D01*
X717508Y-43075D01*
X717278Y-42558D01*
X717201Y-42093D01*
X718811D01*
G01X721106Y-45193D02*
Y-42093D01*
G01X720224Y-45193D02*
X721988D01*
G01X723056Y-41060D02*
X725356D01*
G01X727306Y-42093D02*
Y-45193D01*
X726846Y-44573D01*
G01Y-42093D02*
X727766D01*
G01X726556Y-40126D02*
Y-23526D01*
X716956D01*
Y-40126D01*
X726556D01*
G01X714130Y439923D02*
Y436723D01*
G01X720330Y439923D02*
X714130D01*
G01Y436723D02*
X720330D01*
G01X717631Y455817D02*
Y453595D01*
X717478Y453130D01*
X717171Y452820D01*
X716788Y452717D01*
X716405Y452820D01*
X716098Y453130D01*
X715945Y453595D01*
Y455817D01*
G01X714416Y455300D02*
X714186Y455610D01*
X713918Y455765D01*
X713611Y455817D01*
X713228Y455714D01*
X712960Y455455D01*
X712883Y455145D01*
X712921Y454835D01*
X713075Y454577D01*
X713841Y454060D01*
X714186Y453699D01*
X714416Y453182D01*
X714493Y452717D01*
X712883D01*
G01X711431Y453337D02*
X711201Y452975D01*
X710895Y452769D01*
X710550Y452717D01*
X710243Y452769D01*
X709936Y453027D01*
X709745Y453337D01*
X709706Y453647D01*
X709783Y454009D01*
X710051Y454267D01*
X710320Y454370D01*
X710665D01*
G01X710320D02*
X710090Y454525D01*
X709898Y454784D01*
X709821Y455094D01*
X709898Y455404D01*
X710090Y455662D01*
X710435Y455817D01*
X710780Y455765D01*
X711125Y455559D01*
G01X701619Y764871D02*
Y768071D01*
G01Y761371D02*
Y764571D01*
G01Y755371D02*
Y758571D01*
G01Y751871D02*
Y755071D01*
G01X701605Y779059D02*
Y782259D01*
G01Y773559D02*
Y776759D01*
G01Y769559D02*
Y772759D01*
G01Y783059D02*
Y786259D01*
G01X706991Y1159991D02*
Y1164591D01*
G01X739202Y70015D02*
Y73115D01*
G01X737592D02*
Y70015D01*
G01Y71565D02*
X739202D01*
G01X735297Y70015D02*
Y73115D01*
X735757Y72495D01*
G01Y70015D02*
X734837D01*
G01X732197Y73115D02*
X732504Y73012D01*
X732734Y72753D01*
X732887Y72443D01*
X733002Y72030D01*
X733040Y71565D01*
X733002Y71100D01*
X732887Y70687D01*
X732734Y70377D01*
X732504Y70118D01*
X732197Y70015D01*
X731890Y70118D01*
X731660Y70377D01*
X731507Y70687D01*
X731392Y71100D01*
X731354Y71565D01*
X731392Y72030D01*
X731507Y72443D01*
X731660Y72753D01*
X731890Y73012D01*
X732197Y73115D01*
G01X729097Y70015D02*
Y73115D01*
X729557Y72495D01*
G01Y70015D02*
X728637D01*
G01X731508Y333425D02*
Y254685D01*
G01X729986Y386400D02*
X736186D01*
G01X729986Y389600D02*
Y386400D01*
G01X736186Y389600D02*
X729986D01*
G01Y382900D02*
X736186D01*
G01X729986Y386100D02*
Y382900D01*
G01X736186Y386100D02*
X729986D01*
G01X724349Y444206D02*
Y441006D01*
G01X730549D02*
Y444206D01*
G01X724349Y441006D02*
X730549D01*
G01X720330Y436723D02*
Y439923D01*
G01X730549Y444206D02*
X724349D01*
G01Y448206D02*
Y445006D01*
G01X730549Y448206D02*
X724349D01*
G01X730549Y445006D02*
Y448206D01*
G01X724349Y445006D02*
X730549D01*
G01X734421Y449871D02*
X725121D01*
G01X725021D02*
Y460471D01*
G01X731856Y461879D02*
Y465079D01*
G01X725656Y461879D02*
X731856D01*
G01X725656Y465079D02*
Y461879D01*
G01X731856Y465079D02*
X725656D01*
G01X725021Y460471D02*
X734421D01*
G01X731299Y748401D02*
Y669661D01*
G01X725827Y1689331D02*
Y1425158D01*
G01X736186Y386400D02*
Y389600D01*
G01Y382900D02*
Y386100D01*
G01X736486D02*
Y382900D01*
G01X742686Y386100D02*
X736486D01*
G01X742686Y382900D02*
Y386100D01*
G01X736486Y382900D02*
X742686D01*
G01Y386400D02*
Y389600D01*
G01X736486Y386400D02*
X742686D01*
G01X736486Y389600D02*
Y386400D01*
G01X742686Y389600D02*
X736486D01*
G01X748657Y453552D02*
Y456752D01*
G01X742457Y453552D02*
X748657D01*
G01X742457Y456752D02*
Y453552D01*
G01X748657Y456752D02*
X742457D01*
G01X748657Y449552D02*
Y452752D01*
G01X742457Y449552D02*
X748657D01*
G01X742457Y452752D02*
Y449552D01*
G01X748657Y452752D02*
X742457D01*
G01X734421Y460471D02*
Y449871D01*
G01X734658Y468967D02*
Y465767D01*
G01X740858Y468967D02*
X734658D01*
G01X740858Y465767D02*
Y468967D01*
G01X734658Y465767D02*
X740858D01*
G01X740841Y461635D02*
Y464835D01*
G01X734641Y461635D02*
X740841D01*
G01X734641Y464835D02*
Y461635D01*
G01X740841Y464835D02*
X734641D01*
G01X750085Y1160790D02*
X760285D01*
G01X750085Y1165390D02*
Y1160790D01*
G01X760285Y1165390D02*
X750085D01*
G01X746931Y1182431D02*
X750131D01*
G01X746931Y1188631D02*
Y1182431D01*
G01X750131Y1188631D02*
X746931D01*
G01X750131Y1182431D02*
Y1188631D01*
G01Y1181150D02*
X746931D01*
G01X750131Y1174950D02*
Y1181150D01*
G01X746931Y1174950D02*
X750131D01*
G01X746931Y1181150D02*
Y1174950D01*
G01X764079Y1521785D02*
G03X779869Y1460883I6387J-30842D01*
G01X759269Y379512D02*
Y376312D01*
G01X765469D02*
Y379512D01*
G01X759269Y376312D02*
X765469D01*
G01Y379512D02*
X759269D01*
G01Y391512D02*
Y388312D01*
G01X765469Y391512D02*
X759269D01*
G01X765469Y388312D02*
Y391512D01*
G01X759269Y388312D02*
X765469D01*
G01X759269Y383512D02*
Y380312D01*
G01X765469Y383512D02*
X759269D01*
G01X765469Y380312D02*
Y383512D01*
G01X759269Y380312D02*
X765469D01*
G01X759269Y395524D02*
Y392324D01*
G01X765469D02*
Y395524D01*
G01X759269Y392324D02*
X765469D01*
G01X759269Y387512D02*
Y384312D01*
G01X765469Y387512D02*
X759269D01*
G01X765469Y384312D02*
Y387512D01*
G01X759269Y384312D02*
X765469D01*
G01Y395524D02*
X759269D01*
G01Y399512D02*
Y396312D01*
G01X765469Y399512D02*
X759269D01*
G01X765469Y396312D02*
Y399512D01*
G01X759269Y396312D02*
X765469D01*
G01X759269Y403524D02*
Y400324D01*
G01X765469Y403524D02*
X759269D01*
G01X765469Y400324D02*
Y403524D01*
G01X759269Y400324D02*
X765469D01*
G01X759269Y407524D02*
Y404324D01*
G01X765469Y407524D02*
X759269D01*
G01X765469Y404324D02*
Y407524D01*
G01X759269Y404324D02*
X765469D01*
G01X759269Y411524D02*
Y408324D01*
G01X765469D02*
Y411524D01*
G01X759269Y408324D02*
X765469D01*
G01Y411524D02*
X759269D01*
G01X761143Y453305D02*
X757943D01*
G01X761143Y447105D02*
Y453305D01*
G01X757943Y447105D02*
X761143D01*
G01X757943Y453305D02*
Y447105D01*
G01X757193Y453305D02*
X753993D01*
G01X757193Y447105D02*
Y453305D01*
G01X753993Y447105D02*
X757193D01*
G01X753993Y453305D02*
Y447105D01*
G01X759687Y462144D02*
Y540884D01*
G01X838427Y462144D02*
X759687D01*
G01Y540884D02*
X759859D01*
G01X759771D02*
X838427D01*
G01X756812Y1137549D02*
Y1143749D01*
G01X753612Y1137549D02*
X756812D01*
G01X753612Y1143749D02*
Y1137549D01*
G01X756812Y1143749D02*
X753612D01*
G01X756812Y1151229D02*
X753612D01*
G01X756812Y1145029D02*
Y1151229D01*
G01X753612Y1145029D02*
X756812D01*
G01X753612Y1151229D02*
Y1145029D01*
G01X760285Y1160790D02*
Y1165390D01*
G01X761049Y1165379D02*
Y1160779D01*
G01X771249Y1165379D02*
X761049D01*
G01Y1160779D02*
X771249D01*
G01X782059Y1024012D02*
Y1017812D01*
X785259D01*
Y1024012D01*
X782059D01*
G01X778750Y1070145D02*
G03X841534Y1066535I31288J-3610D01*
G01X771249Y1160779D02*
Y1165379D01*
G01X841534Y1263386D02*
G03X778615Y1261244I-31496J0D01*
G01X778592Y1443882D02*
Y1440682D01*
G01X784792Y1443882D02*
X778592D01*
G01Y1440682D02*
X784792D01*
G01X779031Y1448560D02*
X782231D01*
G01X779031Y1454760D02*
Y1448560D01*
G01X782231D02*
Y1454760D01*
G01X778552Y1444594D02*
X784752D01*
G01X778552Y1447794D02*
Y1444594D01*
G01X784752Y1447794D02*
X778552D01*
G01X782231Y1454760D02*
X779031D01*
G01X775967Y1449490D02*
Y1455690D01*
G01X772767Y1449490D02*
X775967D01*
G01X772767Y1455690D02*
Y1449490D01*
G01X775967Y1455690D02*
X772767D01*
G01X799170Y90331D02*
Y93431D01*
G01X797560D02*
Y90331D01*
G01Y91881D02*
X799170D01*
G01X795265Y90331D02*
Y93431D01*
X795725Y92811D01*
G01Y90331D02*
X794805D01*
G01X793008Y90951D02*
X792778Y90589D01*
X792472Y90383D01*
X792127Y90331D01*
X791820Y90383D01*
X791513Y90641D01*
X791322Y90951D01*
X791283Y91261D01*
X791360Y91623D01*
X791628Y91881D01*
X791897Y91984D01*
X792242D01*
G01X791897D02*
X791667Y92139D01*
X791475Y92398D01*
X791398Y92708D01*
X791475Y93018D01*
X791667Y93276D01*
X792012Y93431D01*
X792357Y93379D01*
X792702Y93173D01*
G01X789065Y93431D02*
X789372Y93328D01*
X789602Y93069D01*
X789755Y92759D01*
X789870Y92346D01*
X789908Y91881D01*
X789870Y91416D01*
X789755Y91003D01*
X789602Y90693D01*
X789372Y90434D01*
X789065Y90331D01*
X788758Y90434D01*
X788528Y90693D01*
X788375Y91003D01*
X788260Y91416D01*
X788222Y91881D01*
X788260Y92346D01*
X788375Y92759D01*
X788528Y93069D01*
X788758Y93328D01*
X789065Y93431D01*
G01X851575Y388583D02*
G02I-31496J0D01*
G01X798467Y966128D02*
Y959928D01*
X801667D01*
Y966128D01*
X798467D01*
G01X802059Y991065D02*
X797008Y996116D01*
Y998365D01*
X828110D01*
Y983765D01*
X797008D01*
Y986014D01*
X802059Y991065D01*
G01X798031Y1024012D02*
Y1017812D01*
X801231D01*
Y1024012D01*
X798031D01*
G01X794031D02*
Y1017812D01*
X797231D01*
Y1024012D01*
X794031D01*
G01X789231Y1017812D02*
Y1024012D01*
X786031D01*
Y1017812D01*
X789231D01*
G01X793286D02*
Y1024012D01*
X790086D01*
Y1017812D01*
X793286D01*
G01X841534Y1066535D02*
G03X788513Y1089527I-31496J0D01*
G01X789045Y1239907D02*
G03X841534Y1263386I20993J23479D01*
G01X784792Y1440682D02*
Y1443882D01*
G01X784752Y1444594D02*
Y1447794D01*
G01X800868Y1437840D02*
X794668D01*
Y1434640D01*
X800868D01*
Y1437840D01*
G01X803944Y1462579D02*
X797744D01*
G01Y1459379D02*
X803944D01*
G01X797744Y1462579D02*
Y1459379D01*
G01X785374Y1463197D02*
G03X789333Y1465720I-14900J27749D01*
G01X793582Y1469546D02*
G03X801968Y1490945I-23112J21400D01*
G01D02*
G03X791373Y1514507I-31496J1D01*
G01X796693Y1576803D02*
Y1695110D01*
G01X1074331Y1576803D02*
X796693D01*
G01Y1695110D02*
X1074331D01*
G01X812294Y871212D02*
X818494D01*
Y874412D01*
X812294D01*
Y871212D01*
G01Y875005D02*
X818494D01*
Y878205D01*
X812294D01*
Y875005D01*
G01X818494Y870679D02*
X812294D01*
Y867479D01*
X818494D01*
Y870679D01*
G01X814567Y917305D02*
X808367D01*
Y914105D01*
X814567D01*
Y917305D01*
G01X820032Y921626D02*
X813832D01*
Y918426D01*
X820032D01*
Y921626D01*
G01X802073Y1024012D02*
Y1017812D01*
X805273D01*
Y1024012D01*
X802073D01*
G01X806073D02*
Y1017812D01*
X809273D01*
Y1024012D01*
X806073D01*
G01X810073D02*
Y1017812D01*
X813273D01*
Y1024012D01*
X810073D01*
G01X814073D02*
Y1017812D01*
X817273D01*
Y1024012D01*
X814073D01*
G01X807734Y1427535D02*
Y1430735D01*
G01X801534Y1427535D02*
X807734D01*
G01X801534Y1430735D02*
Y1427535D01*
G01X807734Y1430735D02*
X801534D01*
G01X801519Y1426752D02*
Y1423552D01*
G01X807719Y1426752D02*
X801519D01*
G01X807719Y1423552D02*
Y1426752D01*
G01X801519Y1423552D02*
X807719D01*
G01X801744Y1434640D02*
X807944D01*
Y1437840D01*
X801744D01*
Y1434640D01*
G01X799482Y1449466D02*
X802682D01*
G01X799482Y1455666D02*
Y1449466D01*
G01X802682Y1455666D02*
X799482D01*
G01X802682Y1449466D02*
Y1455666D01*
G01X803944Y1459379D02*
Y1462579D01*
G01X803598Y1469466D02*
Y1475666D01*
X800398D01*
Y1469466D01*
X803598D01*
G01X827863Y-81273D02*
Y-84373D01*
X828629D01*
X828936Y-84218D01*
X829166Y-84011D01*
X829358Y-83701D01*
X829511Y-83340D01*
X829549Y-82823D01*
X829511Y-82306D01*
X829358Y-81945D01*
X829166Y-81635D01*
X828936Y-81428D01*
X828629Y-81273D01*
X827863D01*
G01X832573D02*
X831039D01*
Y-84373D01*
X832573D01*
G01X831959Y-82875D02*
X831039D01*
G01X834906Y-84373D02*
X834599Y-84270D01*
X834369Y-84011D01*
X834216Y-83701D01*
X834101Y-83288D01*
X834063Y-82823D01*
X834101Y-82358D01*
X834216Y-81945D01*
X834369Y-81635D01*
X834599Y-81376D01*
X834906Y-81273D01*
X835213Y-81376D01*
X835443Y-81635D01*
X835596Y-81945D01*
X835711Y-82358D01*
X835749Y-82823D01*
X835711Y-83288D01*
X835596Y-83701D01*
X835443Y-84011D01*
X835213Y-84270D01*
X834906Y-84373D01*
G01X837278Y-83856D02*
X837508Y-84166D01*
X837776Y-84321D01*
X838083Y-84373D01*
X838466Y-84270D01*
X838734Y-84011D01*
X838811Y-83701D01*
X838773Y-83391D01*
X838619Y-83133D01*
X837853Y-82616D01*
X837508Y-82255D01*
X837278Y-81738D01*
X837201Y-81273D01*
X838811D01*
G01X840378D02*
Y-84373D01*
X841834D01*
G01X841298Y-82875D02*
X840378D01*
G01X843056Y-80240D02*
X845356D01*
G01X847306Y-81273D02*
Y-84373D01*
X846846Y-83753D01*
G01Y-81273D02*
X847766D01*
G01X826021Y847386D02*
X832221D01*
G01X826021Y850586D02*
Y847386D01*
G01X826624Y861084D02*
Y857884D01*
G01X832824Y861084D02*
X826624D01*
G01Y857884D02*
X832824D01*
G01X832221Y850586D02*
X826021D01*
G01X831678Y881990D02*
X825478D01*
Y878790D01*
X831678D01*
Y881990D01*
G01X831452Y885405D02*
Y891605D01*
X828252D01*
Y885405D01*
X831452D01*
G01X823890Y891572D02*
Y885372D01*
X827090D01*
Y891572D01*
X823890D01*
G01X823097Y895485D02*
X816897D01*
Y892285D01*
X823097D01*
Y895485D01*
G01X830658Y911149D02*
Y904949D01*
X833858D01*
Y911149D01*
X830658D01*
G01X827448Y922993D02*
X821248D01*
Y919793D01*
X827448D01*
Y922993D01*
G01X831595Y918476D02*
Y924676D01*
X828395D01*
Y918476D01*
X831595D01*
G01X831352Y941198D02*
X834552D01*
G01X831352Y947398D02*
Y941198D01*
G01X834552Y947398D02*
X831352D01*
G01X831094Y968107D02*
Y974307D01*
X827894D01*
Y968107D01*
X831094D01*
G01X823546Y974248D02*
Y968048D01*
X826746D01*
Y974248D01*
X823546D01*
G01X841794Y988229D02*
Y986007D01*
X841641Y985542D01*
X841334Y985232D01*
X840951Y985129D01*
X840568Y985232D01*
X840261Y985542D01*
X840108Y986007D01*
Y988229D01*
G01X837391Y985129D02*
Y988229D01*
X838809Y986007D01*
X836893D01*
G01X835479Y987712D02*
X835249Y988022D01*
X834981Y988177D01*
X834674Y988229D01*
X834291Y988126D01*
X834023Y987867D01*
X833946Y987557D01*
X833984Y987247D01*
X834138Y986989D01*
X834904Y986472D01*
X835249Y986111D01*
X835479Y985594D01*
X835556Y985129D01*
X833946D01*
G01X832494Y985749D02*
X832264Y985387D01*
X831958Y985181D01*
X831613Y985129D01*
X831306Y985181D01*
X830999Y985439D01*
X830808Y985749D01*
X830769Y986059D01*
X830846Y986421D01*
X831114Y986679D01*
X831383Y986782D01*
X831728D01*
G01X831383D02*
X831153Y986937D01*
X830961Y987196D01*
X830884Y987506D01*
X830961Y987816D01*
X831153Y988074D01*
X831498Y988229D01*
X831843Y988177D01*
X832188Y987971D01*
G01X818073Y1024012D02*
Y1017812D01*
X821273D01*
Y1024012D01*
X818073D01*
G01X822073D02*
Y1017812D01*
X825273D01*
Y1024012D01*
X822073D01*
G01X826073D02*
Y1017812D01*
X829273D01*
Y1024012D01*
X826073D01*
G01X830073D02*
Y1017812D01*
X833273D01*
Y1024012D01*
X830073D01*
G01X829787Y1465290D02*
Y1462090D01*
G01D02*
X835987D01*
G01Y1465290D02*
X829787D01*
G01X846556Y-79306D02*
Y-62706D01*
X836956D01*
Y-79306D01*
X846556D01*
G01X842805Y70834D02*
Y73934D01*
G01X841195D02*
Y70834D01*
G01Y72384D02*
X842805D01*
G01X838900Y70834D02*
Y73934D01*
X839360Y73314D01*
G01Y70834D02*
X838440D01*
G01X836643Y71454D02*
X836413Y71092D01*
X836107Y70886D01*
X835762Y70834D01*
X835455Y70886D01*
X835148Y71144D01*
X834957Y71454D01*
X834918Y71764D01*
X834995Y72126D01*
X835263Y72384D01*
X835532Y72487D01*
X835877D01*
G01X835532D02*
X835302Y72642D01*
X835110Y72901D01*
X835033Y73211D01*
X835110Y73521D01*
X835302Y73779D01*
X835647Y73934D01*
X835992Y73882D01*
X836337Y73676D01*
G01X832700Y70834D02*
Y73934D01*
X833160Y73314D01*
G01Y70834D02*
X832240D01*
G01X838427Y540884D02*
Y462144D01*
G01X836600Y761400D02*
Y767600D01*
G01X833400Y761400D02*
X836600D01*
G01X833400Y767600D02*
Y761400D01*
G01Y760600D02*
Y754400D01*
G01X836600Y760600D02*
X833400D01*
G01X836600Y754400D02*
Y760600D01*
G01X833400Y754400D02*
X836600D01*
G01X840600Y761400D02*
Y767600D01*
X837400D01*
Y761400D01*
X840600D01*
G01X837400Y760600D02*
Y754400D01*
X840600D01*
Y760600D01*
X837400D01*
G01X836600Y767600D02*
X833400D01*
G01X836600Y779400D02*
Y785600D01*
G01X833400Y779400D02*
X836600D01*
G01X833400Y785600D02*
Y779400D01*
G01Y772400D02*
X836600D01*
G01X833400Y778600D02*
Y772400D01*
G01X836600Y778600D02*
X833400D01*
G01X836600Y772400D02*
Y778600D01*
G01X840600Y779400D02*
Y785600D01*
X837400D01*
Y779400D01*
X840600D01*
G01X837400Y778600D02*
Y772400D01*
X840600D01*
Y778600D01*
X837400D01*
G01X836600Y785600D02*
X833400D01*
G01X836600Y797400D02*
Y803600D01*
G01X833400Y797400D02*
X836600D01*
G01X833400Y803600D02*
Y797400D01*
G01Y790400D02*
X836600D01*
G01X833400Y796600D02*
Y790400D01*
G01X836600Y796600D02*
X833400D01*
G01X836600Y790400D02*
Y796600D01*
G01X840600Y797400D02*
Y803600D01*
X837400D01*
Y797400D01*
X840600D01*
G01X837400Y796600D02*
Y790400D01*
X840600D01*
Y796600D01*
X837400D01*
G01X836600Y803600D02*
X833400D01*
G01Y808400D02*
X836600D01*
G01X833400Y814600D02*
Y808400D01*
G01X836600Y814600D02*
X833400D01*
G01X836600Y808400D02*
Y814600D01*
G01X837400D02*
Y808400D01*
X840600D01*
Y814600D01*
X837400D01*
G01X836600Y821600D02*
X833400D01*
G01X836600Y815400D02*
Y821600D01*
G01X833400Y815400D02*
X836600D01*
G01X833400Y821600D02*
Y815400D01*
G01X845248Y825819D02*
X851448D01*
G01X845248Y829019D02*
Y825819D01*
G01X851448Y829019D02*
X845248D01*
G01X840600Y815400D02*
Y821600D01*
X837400D01*
Y815400D01*
X840600D01*
G01X841209Y837059D02*
Y833859D01*
G01X847409Y837059D02*
X841209D01*
G01X847409Y833859D02*
Y837059D01*
G01X841209Y833859D02*
X847409D01*
G01X841209Y841059D02*
Y837859D01*
G01X847409Y841059D02*
X841209D01*
G01X847409Y837859D02*
Y841059D01*
G01X841209Y837859D02*
X847409D01*
G01X839164Y845090D02*
Y841890D01*
G01X845364Y845090D02*
X839164D01*
G01X845364Y841890D02*
Y845090D01*
G01X839164Y841890D02*
X845364D01*
G01X832221Y847386D02*
Y850586D01*
G01X845364Y849131D02*
X839164D01*
Y845931D01*
X845364D01*
Y849131D01*
G01X832824Y857884D02*
Y861084D01*
G01X835044Y856412D02*
X838244D01*
G01X835044Y862612D02*
Y856412D01*
G01X838244Y862612D02*
X835044D01*
G01X838244Y856412D02*
Y862612D01*
G01X844837Y861813D02*
Y865013D01*
G01X838637Y861813D02*
X844837D01*
G01X838637Y865013D02*
Y861813D01*
G01X838761Y856997D02*
Y853797D01*
G01X844961Y856997D02*
X838761D01*
G01X844961Y853797D02*
Y856997D01*
G01X838761Y853797D02*
X844961D01*
G01X841209Y853059D02*
Y849859D01*
G01X847409Y853059D02*
X841209D01*
G01X847409Y849859D02*
Y853059D01*
G01X841209Y849859D02*
X847409D01*
G01X841123Y877076D02*
Y873876D01*
G01X847323Y877076D02*
X841123D01*
G01X847323Y873876D02*
Y877076D01*
G01X841123Y873876D02*
X847323D01*
G01X844837Y865013D02*
X838637D01*
G01X838358Y881059D02*
Y877859D01*
G01X844558D02*
Y881059D01*
G01X838358Y877859D02*
X844558D01*
G01X844884Y869859D02*
Y873059D01*
G01X838684Y869859D02*
X844884D01*
G01X838684Y873059D02*
Y869859D01*
G01X844884Y873059D02*
X838684D01*
G01X844837Y865813D02*
Y869013D01*
G01X838637Y865813D02*
X844837D01*
G01X838637Y869013D02*
Y865813D01*
G01X844837Y869013D02*
X838637D01*
G01X844558Y881059D02*
X838358D01*
G01Y885059D02*
Y881859D01*
G01X844558Y885059D02*
X838358D01*
G01X844558Y881859D02*
Y885059D01*
G01X838358Y881859D02*
X844558D01*
G01X838264Y893103D02*
Y889903D01*
G01X844464Y893103D02*
X838264D01*
G01X844464Y889903D02*
Y893103D01*
G01X838264Y889903D02*
X844464D01*
G01X838265Y889090D02*
Y885890D01*
G01X844465Y889090D02*
X838265D01*
G01X844465Y885890D02*
Y889090D01*
G01X838265Y885890D02*
X844465D01*
G01X834658Y911185D02*
Y904985D01*
X837858D01*
Y911185D01*
X834658D01*
G01X841981Y918969D02*
Y925169D01*
X838781D01*
Y918969D01*
X841981D01*
G01X845981D02*
Y925169D01*
X842781D01*
Y918969D01*
X845981D01*
G01X834552Y941198D02*
Y947398D01*
G01X838552Y941198D02*
Y947398D01*
G01X835352Y941198D02*
X838552D01*
G01X835352Y947398D02*
Y941198D01*
G01X838552Y947398D02*
X835352D01*
G01X832298Y1447318D02*
X835498D01*
G01X832298Y1453518D02*
Y1447318D01*
G01X835498D02*
Y1453518D01*
G01D02*
X832298D01*
G01X845744Y1452559D02*
Y1455759D01*
G01X839544Y1452559D02*
X845744D01*
G01X839544Y1455759D02*
Y1452559D01*
G01X845744Y1455759D02*
X839544D01*
G01X835987Y1462090D02*
Y1465290D01*
G01X860291Y389845D02*
Y386645D01*
G01X866491Y389845D02*
X860291D01*
G01Y386645D02*
X866491D01*
G01X851448Y825819D02*
Y829019D01*
G01X852159Y849059D02*
Y845859D01*
G01X858359D02*
Y849059D01*
G01X852159Y845859D02*
X858359D01*
G01X852159Y837059D02*
Y833859D01*
G01X858359Y837059D02*
X852159D01*
G01X858359Y833859D02*
Y837059D01*
G01X852159Y833859D02*
X858359D01*
G01X852159Y841059D02*
Y837859D01*
G01X858359Y841059D02*
X852159D01*
G01X858359Y837859D02*
Y841059D01*
G01X852159Y837859D02*
X858359D01*
G01X852159Y845059D02*
Y841859D01*
G01X858359Y845059D02*
X852159D01*
G01X858359Y841859D02*
Y845059D01*
G01X852159Y841859D02*
X858359D01*
G01X852159Y857059D02*
Y853859D01*
G01X858359Y857059D02*
X852159D01*
G01X858359Y853859D02*
Y857059D01*
G01X852159Y853859D02*
X858359D01*
G01X852206Y853524D02*
Y850324D01*
G01X858406Y853524D02*
X852206D01*
G01X858406Y850324D02*
Y853524D01*
G01X852206Y850324D02*
X858406D01*
G01X858359Y861859D02*
Y865059D01*
G01X852159Y861859D02*
X858359D01*
G01X852159Y865059D02*
Y861859D01*
G01X858359Y857859D02*
Y861059D01*
G01X852159Y857859D02*
X858359D01*
G01X852159Y861059D02*
Y857859D01*
G01X858359Y861059D02*
X852159D01*
G01X858359Y849059D02*
X852159D01*
G01X858359Y865059D02*
X852159D01*
G01X858359Y869859D02*
Y873059D01*
G01X852159Y869859D02*
X858359D01*
G01X852159Y873059D02*
Y869859D01*
G01X858359Y873059D02*
X852159D01*
G01X858359Y877859D02*
Y881059D01*
G01X852159Y877859D02*
X858359D01*
G01X852159Y881059D02*
Y877859D01*
G01X858359Y865859D02*
Y869059D01*
G01X852159Y865859D02*
X858359D01*
G01X852159Y869059D02*
Y865859D01*
G01X858359Y869059D02*
X852159D01*
G01X858350Y877068D02*
X852150D01*
Y873868D01*
X858350D01*
Y877068D01*
G01X868930Y870742D02*
X862730D01*
Y867542D01*
X868930D01*
Y870742D01*
G01X867349Y880542D02*
X861149D01*
Y877342D01*
X867349D01*
Y880542D01*
G01X858359Y881059D02*
X852159D01*
G01X858393Y891138D02*
Y894338D01*
G01X852193Y891138D02*
X858393D01*
G01X852193Y894338D02*
Y891138D01*
G01X858393Y894338D02*
X852193D01*
G01X858390Y886107D02*
Y889307D01*
G01X852190Y886107D02*
X858390D01*
G01X852190Y889307D02*
Y886107D01*
G01X858390Y889307D02*
X852190D01*
G01X858359Y881859D02*
Y885059D01*
G01X852159Y881859D02*
X858359D01*
G01X852159Y885059D02*
Y881859D01*
G01X858359Y885059D02*
X852159D01*
G01X859956Y1031032D02*
Y1042358D01*
G01X877658Y1031032D02*
X859956D01*
G01Y1057335D02*
Y1070332D01*
G01X858664Y1046232D02*
X878950D01*
G01X858664Y1055132D02*
Y1046232D01*
G01X878950Y1055132D02*
X858664D01*
G01X862209Y1075597D02*
X852009D01*
Y1070997D01*
X862209D01*
Y1075597D01*
G01X859956Y1070332D02*
X877658D01*
G01X862052Y1091561D02*
X851852D01*
Y1086961D01*
X862052D01*
Y1091561D01*
G01X862047Y1086218D02*
X851847D01*
Y1081618D01*
X862047D01*
Y1086218D01*
G01X862189Y1080810D02*
X851989D01*
Y1076210D01*
X862189D01*
Y1080810D01*
G01X861978Y1103034D02*
X851778D01*
Y1098434D01*
X861978D01*
Y1103034D01*
G01X862027Y1097015D02*
X851827D01*
Y1092415D01*
X862027D01*
Y1097015D01*
G01X859903Y1122636D02*
X871903D01*
G01X859903Y1128636D02*
Y1122636D01*
G01X871903Y1128636D02*
X859903D01*
G01X871903Y1137636D02*
X859903D01*
G01Y1131636D02*
X871903D01*
G01X859903Y1137636D02*
Y1131636D01*
G01X872080Y1155080D02*
X860080D01*
G01Y1149080D02*
X872080D01*
G01X860080Y1155080D02*
Y1149080D01*
G01X872080Y1147080D02*
X860080D01*
G01Y1141080D02*
X872080D01*
G01X860080Y1147080D02*
Y1141080D01*
G01X866491Y386645D02*
Y389845D01*
G01X875649Y558263D02*
X880249D01*
G01X875649Y568463D02*
Y558263D01*
G01X880249Y568463D02*
X875649D01*
G01X880249Y558263D02*
Y568463D01*
G01X877749Y596423D02*
X884149D01*
G01X877749Y609303D02*
Y596423D01*
G01Y609303D02*
X884149D01*
G01X878454Y756584D02*
X881654D01*
G01X878454Y762784D02*
Y756584D01*
G01X881654Y762784D02*
X878454D01*
G01X873251Y756584D02*
X876451D01*
G01X873251Y762784D02*
Y756584D01*
G01X876451Y762784D02*
X873251D01*
G01X876451Y756584D02*
Y762784D01*
G01X881654Y765934D02*
X878454D01*
G01Y759734D02*
X881654D01*
G01X878454Y765934D02*
Y759734D01*
G01X876451Y765934D02*
X873251D01*
G01X876451Y759734D02*
Y765934D01*
G01X873251Y759734D02*
X876451D01*
G01X873251Y765934D02*
Y759734D01*
G01X876451Y778658D02*
X873251D01*
G01X876451Y772458D02*
Y778658D01*
G01X873251Y772458D02*
X876451D01*
G01X873251Y778658D02*
Y772458D01*
G01X878454Y775598D02*
X881654D01*
G01X878454Y781798D02*
Y775598D01*
G01X881654Y781798D02*
X878454D01*
G01X873251Y775608D02*
X876451D01*
G01X873251Y781808D02*
Y775608D01*
G01X876451Y781808D02*
X873251D01*
G01X876451Y775608D02*
Y781808D01*
G01X881654Y778648D02*
X878454D01*
G01Y772448D02*
X881654D01*
G01X878454Y778648D02*
Y772448D01*
G01X876695Y794376D02*
X873495D01*
G01X876695Y788176D02*
Y794376D01*
G01X873495Y788176D02*
X876695D01*
G01X873495Y794376D02*
Y788176D01*
G01X874316Y801790D02*
X877516D01*
G01X874316Y807990D02*
Y801790D01*
G01X877516Y807990D02*
X874316D01*
G01X877516Y801790D02*
Y807990D01*
G01X874316Y811940D02*
X877516D01*
G01X874316Y818140D02*
Y811940D01*
G01X877516D02*
Y818140D01*
G01X876191Y825263D02*
Y829863D01*
G01X865991Y825263D02*
X876191D01*
G01X865991Y829863D02*
Y825263D01*
G01X876191Y829863D02*
X865991D01*
G01X876191Y819876D02*
Y824476D01*
G01X865991Y819876D02*
X876191D01*
G01X865991Y824476D02*
Y819876D01*
G01X876191Y824476D02*
X865991D01*
G01X876191Y830737D02*
Y835337D01*
G01X865991Y830737D02*
X876191D01*
G01X865991Y835337D02*
Y830737D01*
G01X877516Y818140D02*
X874316D01*
G01X876191Y835337D02*
X865991D01*
G01X877686Y907237D02*
X880886D01*
G01X877686Y913437D02*
Y907237D01*
G01X873686D02*
X876886D01*
G01X873686Y913437D02*
Y907237D01*
G01X876886D02*
Y913437D01*
G01X880886D02*
X877686D01*
G01X876886D02*
X873686D01*
G01X877658Y1042358D02*
Y1031032D01*
G01Y1070332D02*
Y1057335D01*
G01X878950Y1046232D02*
Y1055132D01*
G01X879448Y1091145D02*
X889648D01*
Y1095745D01*
X879448D01*
Y1091145D01*
G01X871903Y1122636D02*
Y1128636D01*
G01Y1131636D02*
Y1137636D01*
G01X872080Y1149080D02*
Y1155080D01*
G01Y1141080D02*
Y1147080D01*
G01X892649Y551763D02*
X897249D01*
G01X892649Y561963D02*
Y551763D01*
G01X895009Y542663D02*
Y549063D01*
G01X907889D02*
X895009D01*
G01Y542663D02*
X907889D01*
G01X887649Y551763D02*
X892249D01*
G01X887649Y561963D02*
Y551763D01*
G01X892249D02*
Y561963D01*
G01X885249Y568463D02*
X880649D01*
G01X885249Y558263D02*
Y568463D01*
G01X880649Y558263D02*
X885249D01*
G01X880649Y568463D02*
Y558263D01*
G01X897249Y561963D02*
X892649D01*
G01X892249D02*
X887649D01*
G01X884951Y573132D02*
Y569932D01*
G01X891151D02*
Y573132D01*
G01X884951Y569932D02*
X891151D01*
G01Y573132D02*
X884951D01*
G01X886102Y578888D02*
Y575688D01*
G01X892302Y578888D02*
X886102D01*
G01X892302Y575688D02*
Y578888D01*
G01X886102Y575688D02*
X892302D01*
G01X886159Y587373D02*
Y584173D01*
G01X892359Y587373D02*
X886159D01*
G01X892359Y584173D02*
Y587373D01*
G01X886159Y584173D02*
X892359D01*
G01X885649Y597763D02*
X890249D01*
G01X885649Y607963D02*
Y597763D01*
G01X890249D02*
Y607963D01*
G01X884149Y596423D02*
Y609303D01*
G01X895767Y595328D02*
X892567D01*
G01X895767Y589128D02*
Y595328D01*
G01X892567Y589128D02*
X895767D01*
G01X892567Y595328D02*
Y589128D01*
G01X892849Y599263D02*
X896049D01*
G01X892849Y605463D02*
Y599263D01*
G01X896049D02*
Y605463D01*
G01X890249Y607963D02*
X885649D01*
G01X896049Y605463D02*
X892849D01*
G01X898493Y688900D02*
Y686678D01*
X898340Y686213D01*
X898033Y685903D01*
X897650Y685800D01*
X897267Y685903D01*
X896960Y686213D01*
X896807Y686678D01*
Y688900D01*
G01X894090Y685800D02*
Y688900D01*
X895508Y686678D01*
X893592D01*
G01X892293Y686265D02*
X892063Y686007D01*
X891795Y685852D01*
X891450Y685800D01*
X891105Y685903D01*
X890837Y686110D01*
X890645Y686472D01*
X890607Y686885D01*
X890683Y687298D01*
X890875Y687557D01*
X891143Y687763D01*
X891412Y687815D01*
X891680Y687763D01*
X892025Y687557D01*
X891910Y688900D01*
X890875D01*
G01X888350D02*
X888657Y688797D01*
X888887Y688538D01*
X889040Y688228D01*
X889155Y687815D01*
X889193Y687350D01*
X889155Y686885D01*
X889040Y686472D01*
X888887Y686162D01*
X888657Y685903D01*
X888350Y685800D01*
X888043Y685903D01*
X887813Y686162D01*
X887660Y686472D01*
X887545Y686885D01*
X887507Y687350D01*
X887545Y687815D01*
X887660Y688228D01*
X887813Y688538D01*
X888043Y688797D01*
X888350Y688900D01*
G01X895565Y690954D02*
X889431D01*
Y697260D01*
X895565D01*
Y690954D01*
G01X885010Y756583D02*
X888210D01*
G01X885010Y762783D02*
Y756583D01*
G01X888210Y762783D02*
X885010D01*
G01X888210Y756583D02*
Y762783D01*
G01Y765933D02*
X885010D01*
G01X888210Y759733D02*
Y765933D01*
G01X885010Y759733D02*
X888210D01*
G01X885010Y765933D02*
Y759733D01*
G01X881654Y756584D02*
Y762784D01*
G01Y759734D02*
Y765934D01*
G01X883510Y775593D02*
X886710D01*
G01X883510Y781793D02*
Y775593D01*
G01X886710Y781793D02*
X883510D01*
G01X886710Y775593D02*
Y781793D01*
G01Y778643D02*
X883510D01*
G01X886710Y772443D02*
Y778643D01*
G01X883510Y772443D02*
X886710D01*
G01X883510Y778643D02*
Y772443D01*
G01X881654Y775598D02*
Y781798D01*
G01Y772448D02*
Y778648D01*
G01X886494Y794376D02*
X883294D01*
G01X886494Y788176D02*
Y794376D01*
G01X883294Y788176D02*
X886494D01*
G01X883294Y794376D02*
Y788176D01*
G01X895716Y794376D02*
X892516D01*
G01X895716Y788176D02*
Y794376D01*
G01X892516Y788176D02*
X895716D01*
G01X892516Y794376D02*
Y788176D01*
G01X890316Y811940D02*
X893516D01*
G01X890316Y818140D02*
Y811940D01*
G01X893516D02*
Y818140D01*
G01X889516Y807990D02*
X886316D01*
G01X889516Y801790D02*
Y807990D01*
G01X886316Y801790D02*
X889516D01*
G01X886316Y807990D02*
Y801790D01*
G01X893516Y818140D02*
X890316D01*
G01X894266Y818890D02*
X897466D01*
G01X894266Y825090D02*
Y818890D01*
G01X897466Y825090D02*
X894266D01*
G01X882266Y818890D02*
X885466D01*
G01X882266Y825090D02*
Y818890D01*
G01X885466Y825090D02*
X882266D01*
G01X885466Y818890D02*
Y825090D01*
G01X886416Y818890D02*
X889616D01*
G01X886416Y825090D02*
Y818890D01*
G01X889616Y825090D02*
X886416D01*
G01X889616Y818890D02*
Y825090D01*
G01X890316Y818890D02*
X893516D01*
G01X890316Y825090D02*
Y818890D01*
G01X893516Y825090D02*
X890316D01*
G01X893516Y818890D02*
Y825090D01*
G01X896692Y860615D02*
X891242D01*
G01Y858315D02*
X896692D01*
G01X891242Y860615D02*
Y858315D01*
G01X896692Y857466D02*
X891242D01*
G01Y855166D02*
X896692D01*
G01X891242Y857466D02*
Y855166D01*
G01X896692Y863765D02*
X891242D01*
G01Y861465D02*
X896692D01*
G01X891242Y863765D02*
Y861465D01*
G01X896692Y870064D02*
X891242D01*
G01Y867764D02*
X896692D01*
G01X891242Y870064D02*
Y867764D01*
G01X881686Y907237D02*
X884886D01*
G01X881686Y913437D02*
Y907237D01*
G01X884886D02*
Y913437D01*
G01X889686Y907237D02*
X892886D01*
G01X889686Y913437D02*
Y907237D01*
G01X892886D02*
Y913437D01*
G01X885686Y907237D02*
X888886D01*
G01X885686Y913437D02*
Y907237D01*
G01X888886D02*
Y913437D01*
G01X880886Y907237D02*
Y913437D01*
G01X884886D02*
X881686D01*
G01X892886D02*
X889686D01*
G01X888886D02*
X885686D01*
G01X899391Y1030724D02*
X881689D01*
G01D02*
Y1042358D01*
G01Y1057335D02*
Y1070024D01*
G01X880397Y1055132D02*
Y1046232D01*
G01X900683Y1055132D02*
X880397D01*
G01Y1046232D02*
X900683D01*
G01X891656Y1072210D02*
X901856D01*
Y1076810D01*
X891656D01*
Y1072210D01*
G01X881689Y1070024D02*
X899391D01*
G01X893732Y1116103D02*
X905732D01*
G01X893732Y1122103D02*
Y1116103D01*
G01X905732Y1122103D02*
X893732D01*
G01Y1125103D02*
X905732D01*
G01X893732Y1131103D02*
Y1125103D01*
G01X905732Y1131103D02*
X893732D01*
G01X894201Y1138169D02*
X906201D01*
G01X894201Y1144169D02*
Y1138169D01*
G01Y1146169D02*
X906201D01*
G01X894201Y1152169D02*
Y1146169D01*
G01X906201Y1152169D02*
X894201D01*
G01X906201Y1144169D02*
X894201D01*
G01X888344Y1455259D02*
Y1458459D01*
G01X882144Y1455259D02*
X888344D01*
G01Y1458459D02*
X882144D01*
G01D02*
Y1455259D01*
G01X882131Y1462447D02*
Y1459247D01*
G01X888331Y1462447D02*
X882131D01*
G01Y1459247D02*
X888331D01*
G01D02*
Y1462447D01*
G01X881556Y1745565D02*
X883166Y1742465D01*
G01X881556D02*
X883166Y1745565D01*
G01X885384D02*
X885461Y1744893D01*
X885576Y1744325D01*
X885729Y1743808D01*
X885921Y1743240D01*
X886228Y1742465D01*
X884694D01*
G01X888484Y1745565D02*
X888561Y1744893D01*
X888676Y1744325D01*
X888829Y1743808D01*
X889021Y1743240D01*
X889328Y1742465D01*
X887794D01*
G01X891911Y1757315D02*
Y1756215D01*
G01Y1747315D02*
Y1746765D01*
X881911D01*
G01Y1754265D02*
Y1759265D01*
G01Y1746765D02*
Y1749265D01*
G01Y1764265D02*
Y1766765D01*
X891911D01*
Y1766215D01*
G01X881170Y1792645D02*
X882780Y1789545D01*
G01X881170D02*
X882780Y1792645D01*
G01X884998D02*
X885075Y1791973D01*
X885190Y1791405D01*
X885343Y1790888D01*
X885535Y1790320D01*
X885842Y1789545D01*
X884308D01*
G01X887523Y1792283D02*
X887792Y1792542D01*
X888098Y1792645D01*
X888405Y1792542D01*
X888673Y1792232D01*
X888865Y1791767D01*
X888942Y1791302D01*
Y1790733D01*
X888865Y1790268D01*
X888673Y1789855D01*
X888443Y1789648D01*
X888175Y1789545D01*
X887868Y1789648D01*
X887638Y1789855D01*
X887485Y1790165D01*
X887408Y1790578D01*
X887485Y1790940D01*
X887677Y1791302D01*
X887907Y1791508D01*
X888175Y1791560D01*
X888482Y1791457D01*
X888712Y1791198D01*
X888942Y1790733D01*
G01X891525Y1804395D02*
Y1803295D01*
G01Y1794395D02*
Y1793845D01*
X881525D01*
G01Y1801345D02*
Y1806345D01*
G01Y1793845D02*
Y1796345D01*
G01Y1811345D02*
Y1813845D01*
X891525D01*
Y1813295D01*
G01X910550Y362183D02*
Y358983D01*
G01D02*
X916750D01*
G01X914265Y358207D02*
X911065D01*
G01Y352007D02*
X914265D01*
G01X911065Y358207D02*
Y352007D01*
G01X916750Y362183D02*
X910550D01*
G01X910781Y367493D02*
Y364293D01*
G01X916981Y367493D02*
X910781D01*
G01Y364293D02*
X916981D01*
G01X908049Y549563D02*
Y554163D01*
G01X897849Y549563D02*
X908049D01*
G01X897849Y554163D02*
Y549563D01*
G01X908049Y554163D02*
X897849D01*
G01X897249Y551763D02*
Y561963D01*
G01X907889Y542663D02*
Y549063D01*
G01X905549Y554763D02*
Y557963D01*
G01X899349Y554763D02*
X905549D01*
G01X899349Y557963D02*
Y554763D01*
G01X905549Y557963D02*
X899349D01*
G01X902793Y563101D02*
X905993D01*
G01X902793Y569301D02*
Y563101D01*
G01X905993Y569301D02*
X902793D01*
G01X905993Y563101D02*
Y569301D01*
G01X906917Y563101D02*
X910117D01*
G01X906917Y569301D02*
Y563101D01*
G01X910117Y569301D02*
X906917D01*
G01X910117Y563101D02*
Y569301D01*
G01X897215Y563101D02*
X900415D01*
G01X897215Y569301D02*
Y563101D01*
G01X900415Y569301D02*
X897215D01*
G01X900415Y563101D02*
Y569301D01*
G01X909899Y576794D02*
X916099D01*
G01X909899Y579994D02*
Y576794D01*
G01X916099Y579994D02*
X909899D01*
G01X909849Y581263D02*
X916049D01*
G01X909849Y584463D02*
Y581263D01*
G01X916049Y584463D02*
X909849D01*
G01X909899Y585016D02*
X916099D01*
G01X909899Y588216D02*
Y585016D01*
G01X912649Y601763D02*
X917249D01*
G01X912649Y611963D02*
Y601763D01*
G01X899984Y595395D02*
X896784D01*
G01X899984Y589195D02*
Y595395D01*
G01X896784Y589195D02*
X899984D01*
G01X896784Y595395D02*
Y589195D01*
G01X908751Y595349D02*
X905551D01*
G01X908751Y589149D02*
Y595349D01*
G01X905551Y589149D02*
X908751D01*
G01X905551Y595349D02*
Y589149D01*
G01X916099Y588216D02*
X909899D01*
G01X917249Y611963D02*
X912649D01*
G01X907816Y811940D02*
X911016D01*
G01X907816Y818140D02*
Y811940D01*
G01X911016D02*
Y818140D01*
G01X912116Y801790D02*
X915316D01*
G01X912116Y807990D02*
Y801790D01*
G01X915316Y807990D02*
X912116D01*
G01X898316Y801790D02*
X901516D01*
G01X898316Y807990D02*
Y801790D01*
G01X901516D02*
Y807990D01*
G01D02*
X898316D01*
G01X904866Y835155D02*
Y830555D01*
G01D02*
X915066D01*
G01X911016Y818140D02*
X907816D01*
G01X905366Y825090D02*
X902166D01*
G01X905366Y818890D02*
Y825090D01*
G01X902166Y818890D02*
X905366D01*
G01X902166Y825090D02*
Y818890D01*
G01X901416Y825090D02*
X898216D01*
G01X901416Y818890D02*
Y825090D01*
G01X898216Y818890D02*
X901416D01*
G01X898216Y825090D02*
Y818890D01*
G01X912728Y820483D02*
X918928D01*
G01X912728Y823683D02*
Y820483D01*
G01X918928Y823683D02*
X912728D01*
G01X897466Y818890D02*
Y825090D01*
G01X915066Y835155D02*
X904866D01*
G01X906141Y842567D02*
Y848017D01*
G01X903841Y842567D02*
X906141D01*
G01X903841Y848017D02*
Y842567D01*
G01X910140Y845717D02*
X915590D01*
G01X910140Y848017D02*
Y845717D01*
G01X911179Y838025D02*
X905729D01*
G01X911179Y835725D02*
Y838025D01*
G01X905729Y835725D02*
X911179D01*
G01X905729Y838025D02*
Y835725D01*
G01X909290Y842567D02*
Y848017D01*
G01X906990Y842567D02*
X909290D01*
G01X906990Y848017D02*
Y842567D01*
G01X902991D02*
Y848017D01*
G01X900691Y842567D02*
X902991D01*
G01X900691Y848017D02*
Y842567D01*
G01X906141Y848017D02*
X903841D01*
G01X910140Y852016D02*
X915590D01*
G01X910140Y854316D02*
Y852016D01*
G01X915590Y854316D02*
X910140D01*
G01Y858315D02*
X915590D01*
G01X910140Y860615D02*
Y858315D01*
G01X915590Y860615D02*
X910140D01*
G01X900691Y857466D02*
Y852016D01*
G01X902991Y857466D02*
X900691D01*
G01X902991Y852016D02*
Y857466D01*
G01X900691Y852016D02*
X902991D01*
G01X896692Y858315D02*
Y860615D01*
G01X915590Y848017D02*
X910140D01*
G01X909290D02*
X906990D01*
G01X902991D02*
X900691D01*
G01X896692Y855166D02*
Y857466D01*
G01Y861465D02*
Y863765D01*
G01X910140Y864614D02*
X915590D01*
G01X910140Y866914D02*
Y864614D01*
G01X915590Y866914D02*
X910140D01*
G01X902991Y870913D02*
Y876363D01*
G01X900691Y870913D02*
X902991D01*
G01X900691Y876363D02*
Y870913D01*
G01X902991Y876363D02*
X900691D01*
G01X910140Y867764D02*
X915590D01*
G01X910140Y870064D02*
Y867764D01*
G01X915590Y870064D02*
X910140D01*
G01X906141Y870913D02*
Y876363D01*
G01X903841Y870913D02*
X906141D01*
G01X903841Y876363D02*
Y870913D01*
G01X906141Y876363D02*
X903841D01*
G01X909290Y870913D02*
Y876363D01*
G01X906990Y870913D02*
X909290D01*
G01X906990Y876363D02*
Y870913D01*
G01X909290Y876363D02*
X906990D01*
G01X896692Y867764D02*
Y870064D01*
G01X899842Y870913D02*
Y876363D01*
G01X897542Y870913D02*
X899842D01*
G01X897542Y876363D02*
Y870913D01*
G01X899842Y876363D02*
X897542D01*
G01X905267Y894055D02*
X899067D01*
Y890855D01*
X905267D01*
Y894055D01*
G01X905251Y886116D02*
X899051D01*
Y882916D01*
X905251D01*
Y886116D01*
G01X899046Y886878D02*
X905246D01*
Y890078D01*
X899046D01*
Y886878D01*
G01X909686Y907237D02*
X912886D01*
G01X909686Y913437D02*
Y907237D01*
G01X904886D02*
Y913437D01*
G01X901686Y907237D02*
X904886D01*
G01X901686Y913437D02*
Y907237D01*
G01X908886D02*
Y913437D01*
G01X905686Y907237D02*
X908886D01*
G01X905686Y913437D02*
Y907237D01*
G01X897686D02*
X900886D01*
G01X897686Y913437D02*
Y907237D01*
G01X900886D02*
Y913437D01*
G01X912886D02*
X909686D01*
G01X904886D02*
X901686D01*
G01X908886D02*
X905686D01*
G01X900886D02*
X897686D01*
G01X899391Y1042358D02*
Y1030724D01*
G01Y1070024D02*
Y1057335D01*
G01X900683Y1046232D02*
Y1055132D01*
G01X905732Y1116103D02*
Y1122103D01*
G01Y1125103D02*
Y1131103D01*
G01X906201Y1138169D02*
Y1144169D01*
G01Y1146169D02*
Y1152169D01*
G01X966729Y1579737D02*
Y1587237D01*
X964489D01*
X963742Y1586862D01*
X963182Y1585987D01*
X962995Y1584987D01*
X963182Y1583987D01*
X963649Y1583237D01*
X964489Y1582862D01*
X966729D01*
G01X959229Y1579737D02*
Y1587237D01*
X956895D01*
X956149Y1586862D01*
X955682Y1586362D01*
X955495Y1585362D01*
X955682Y1584362D01*
X956242Y1583737D01*
X956895Y1583362D01*
X959229D01*
G01X956895D02*
X955495Y1579737D01*
G01X947995D02*
X951729D01*
Y1587237D01*
X947995D01*
G01X949489Y1583612D02*
X951729D01*
G01X944322Y1580737D02*
X943575Y1580112D01*
X942735Y1579737D01*
X941989D01*
X941242Y1580112D01*
X940682Y1580737D01*
X940402Y1581612D01*
X940589Y1582487D01*
X941055Y1583237D01*
X941895Y1583737D01*
X943015Y1583987D01*
X943669Y1584487D01*
X943949Y1585362D01*
X943762Y1586237D01*
X943295Y1586862D01*
X942642Y1587237D01*
X941989D01*
X941335Y1586987D01*
X940775Y1586362D01*
G01X936822Y1580737D02*
X936075Y1580112D01*
X935235Y1579737D01*
X934489D01*
X933742Y1580112D01*
X933182Y1580737D01*
X932902Y1581612D01*
X933089Y1582487D01*
X933555Y1583237D01*
X934395Y1583737D01*
X935515Y1583987D01*
X936169Y1584487D01*
X936449Y1585362D01*
X936262Y1586237D01*
X935795Y1586862D01*
X935142Y1587237D01*
X934489D01*
X933835Y1586987D01*
X933275Y1586362D01*
G01X928575Y1582237D02*
X926149D01*
G01X921635Y1579737D02*
Y1587237D01*
X918089D01*
G01X919395Y1583612D02*
X921635D01*
G01X913482Y1587237D02*
X911242D01*
G01X912362D02*
Y1579737D01*
G01X913482D02*
X911242D01*
G01X904862Y1587237D02*
Y1579737D01*
G01X907009Y1587237D02*
X902715D01*
G01X917163Y1750066D02*
Y1747566D01*
X907163D01*
Y1748116D01*
G01Y1757016D02*
Y1758116D01*
G01X917518Y1768766D02*
X915908Y1771866D01*
G01X917518D02*
X915908Y1768766D01*
G01X913613D02*
X913345Y1768818D01*
X913038Y1768973D01*
X912846Y1769231D01*
X912770Y1769593D01*
X912846Y1769954D01*
X913076Y1770264D01*
X913421Y1770419D01*
X913805D01*
X914035Y1770523D01*
X914226Y1770781D01*
X914303Y1771143D01*
X914188Y1771504D01*
X913920Y1771763D01*
X913613Y1771866D01*
X913306Y1771763D01*
X913038Y1771504D01*
X912923Y1771143D01*
X913000Y1770781D01*
X913191Y1770523D01*
X913421Y1770419D01*
X913805D01*
X914150Y1770264D01*
X914380Y1769954D01*
X914456Y1769593D01*
X914380Y1769231D01*
X914188Y1768973D01*
X913881Y1768818D01*
X913613Y1768766D01*
G01X910513Y1771866D02*
X910820Y1771763D01*
X911050Y1771504D01*
X911203Y1771194D01*
X911318Y1770781D01*
X911356Y1770316D01*
X911318Y1769851D01*
X911203Y1769438D01*
X911050Y1769128D01*
X910820Y1768869D01*
X910513Y1768766D01*
X910206Y1768869D01*
X909976Y1769128D01*
X909823Y1769438D01*
X909708Y1769851D01*
X909670Y1770316D01*
X909708Y1770781D01*
X909823Y1771194D01*
X909976Y1771504D01*
X910206Y1771763D01*
X910513Y1771866D01*
G01X907163Y1767016D02*
Y1767566D01*
X917163D01*
G01X917166Y1797935D02*
Y1795435D01*
X907166D01*
Y1795985D01*
G01Y1804885D02*
Y1805985D01*
G01X917521Y1816635D02*
X915911Y1819735D01*
G01X917521D02*
X915911Y1816635D01*
G01X913693D02*
X913616Y1817307D01*
X913501Y1817875D01*
X913348Y1818392D01*
X913156Y1818960D01*
X912849Y1819735D01*
X914383D01*
G01X911359Y1817100D02*
X911129Y1816842D01*
X910861Y1816687D01*
X910516Y1816635D01*
X910171Y1816738D01*
X909903Y1816945D01*
X909711Y1817307D01*
X909673Y1817720D01*
X909749Y1818133D01*
X909941Y1818392D01*
X910209Y1818598D01*
X910478Y1818650D01*
X910746Y1818598D01*
X911091Y1818392D01*
X910976Y1819735D01*
X909941D01*
G01X907166Y1814885D02*
Y1815435D01*
X917166D01*
G01X915373Y313828D02*
Y310628D01*
G01X921573D02*
Y313828D01*
G01X915373Y310628D02*
X921573D01*
G01Y313828D02*
X915373D01*
G01X926096Y358529D02*
X932296D01*
G01X926096Y361729D02*
Y358529D01*
G01X922543Y353291D02*
X925743D01*
G01X922543Y359491D02*
Y353291D01*
G01X925743Y359491D02*
X922543D01*
G01X925743Y353291D02*
Y359491D01*
G01X917348Y353220D02*
X920548D01*
G01X917348Y359420D02*
Y353220D01*
G01X920548Y359420D02*
X917348D01*
G01X920548Y353220D02*
Y359420D01*
G01X916750Y358983D02*
Y362183D01*
G01X914265Y352007D02*
Y358207D01*
G01X932296Y361729D02*
X926096D01*
G01X920419Y373471D02*
X917219D01*
G01X920419Y367271D02*
Y373471D01*
G01X917219Y367271D02*
X920419D01*
G01X917219Y373471D02*
Y367271D01*
G01X925724Y365017D02*
X931924D01*
G01X925724Y368217D02*
Y365017D01*
G01X931924Y368217D02*
X925724D01*
G01X916981Y364293D02*
Y367493D01*
G01X927880Y370139D02*
Y373339D01*
G01X921680Y370139D02*
X927880D01*
G01X921680Y373339D02*
Y370139D01*
G01X927880Y373339D02*
X921680D01*
G01X918249Y564263D02*
Y574463D01*
G01X913649Y564263D02*
X918249D01*
G01X913649Y574463D02*
Y564263D01*
G01X919349Y570563D02*
X929549D01*
G01X919349Y575163D02*
Y570563D01*
G01X918249Y574463D02*
X913649D01*
G01X929549Y575163D02*
X919349D01*
G01X916099Y576794D02*
Y579994D01*
G01X916049Y581263D02*
Y584463D01*
G01X916099Y585016D02*
Y588216D01*
G01X917249Y601763D02*
Y611963D01*
G01X918249Y613303D02*
Y600423D01*
G01X924649D02*
Y613303D01*
G01X918249Y600423D02*
X924649D01*
G01X918249Y613303D02*
X924649D01*
G01X920190Y811940D02*
X923390D01*
G01X920190Y818140D02*
Y811940D01*
G01X923390D02*
Y818140D01*
G01X915316Y801790D02*
Y807990D01*
G01X915066Y830555D02*
Y835155D01*
G01X923390Y818140D02*
X920190D01*
G01X919028Y816382D02*
Y819582D01*
G01X912828Y816382D02*
X919028D01*
G01X912828Y819582D02*
Y816382D01*
G01X919028Y819582D02*
X912828D01*
G01X918928Y820483D02*
Y823683D01*
G01X927355Y839056D02*
X924155D01*
G01X927355Y832856D02*
Y839056D01*
G01X924155Y832856D02*
X927355D01*
G01X924155Y839056D02*
Y832856D01*
G01X921889Y845717D02*
Y848017D01*
G01X916439Y845717D02*
X921889D01*
G01X916439Y848017D02*
Y845717D01*
G01X915590D02*
Y848017D01*
G01X921889D02*
X916439D01*
G01X926288Y857466D02*
Y852016D01*
G01X928588Y857466D02*
X926288D01*
G01X928588Y852016D02*
Y857466D01*
G01X926288Y852016D02*
X928588D01*
G01X921889Y854316D02*
X916439D01*
G01X921889Y852016D02*
Y854316D01*
G01X916439Y852016D02*
X921889D01*
G01X916439Y854316D02*
Y852016D01*
G01X922738Y857466D02*
Y852016D01*
G01X925038Y857466D02*
X922738D01*
G01X925038Y852016D02*
Y857466D01*
G01X922738Y852016D02*
X925038D01*
G01X919589Y863765D02*
Y858315D01*
G01X921889Y863765D02*
X919589D01*
G01X921889Y858315D02*
Y863765D01*
G01X919589Y858315D02*
X921889D01*
G01X915590Y852016D02*
Y854316D01*
G01Y858315D02*
Y860615D01*
G01Y864614D02*
Y866914D01*
G01Y867764D02*
Y870064D01*
G01X925686Y907237D02*
X928886D01*
G01X925686Y913437D02*
Y907237D01*
G01X928886D02*
Y913437D01*
G01X921686Y907237D02*
X924886D01*
G01X921686Y913437D02*
Y907237D01*
G01X924886D02*
Y913437D01*
G01X917686Y907237D02*
X920886D01*
G01X917686Y913437D02*
Y907237D01*
G01X920886D02*
Y913437D01*
G01X912886Y907237D02*
Y913437D01*
G01X913686Y907237D02*
X916886D01*
G01X913686Y913437D02*
Y907237D01*
G01X916886D02*
Y913437D01*
G01X928886D02*
X925686D01*
G01X924886D02*
X921686D01*
G01X920886D02*
X917686D01*
G01X918228Y927226D02*
X915028D01*
G01X918228Y921026D02*
Y927226D01*
G01X915028Y921026D02*
X918228D01*
G01X915028Y927226D02*
Y921026D01*
G01X922228Y927226D02*
X919028D01*
G01X922228Y921026D02*
Y927226D01*
G01X919028Y921026D02*
X922228D01*
G01X919028Y927226D02*
Y921026D01*
G01X926228Y927226D02*
X923028D01*
G01X926228Y921026D02*
Y927226D01*
G01X923028Y921026D02*
X926228D01*
G01X923028Y927226D02*
Y921026D01*
G01X930228Y927226D02*
X927028D01*
G01Y921026D02*
X930228D01*
G01X927028Y927226D02*
Y921026D01*
G01X916886Y913437D02*
X913686D01*
G01X923933Y1031032D02*
Y1042537D01*
G01X941635Y1031032D02*
X923933D01*
G01Y1058143D02*
Y1070332D01*
G01X922641Y1046232D02*
X942927D01*
G01X922641Y1055132D02*
Y1046232D01*
G01X942927Y1055132D02*
X922641D01*
G01X929214Y1076667D02*
X919014D01*
Y1072067D01*
X929214D01*
Y1076667D01*
G01X923933Y1070332D02*
X941635D01*
G01X929295Y1087468D02*
X919095D01*
Y1082868D01*
X929295D01*
Y1087468D01*
G01X929187Y1082121D02*
X918987D01*
Y1077521D01*
X929187D01*
Y1082121D01*
G01X927414Y1092909D02*
Y1103109D01*
X922814D01*
Y1092909D01*
X927414D01*
G01X932467Y1092926D02*
Y1103126D01*
X927867D01*
Y1092926D01*
X932467D01*
G01X923880Y1122636D02*
X935880D01*
G01X923880Y1128636D02*
Y1122636D01*
G01X935880Y1128636D02*
X923880D01*
G01X935880Y1137636D02*
X923880D01*
G01Y1131636D02*
X935880D01*
G01X923880Y1137636D02*
Y1131636D01*
G01X936058Y1146708D02*
X924058D01*
G01Y1140708D02*
X936058D01*
G01X924058Y1146708D02*
Y1140708D01*
G01X936058Y1154708D02*
X924058D01*
G01Y1148708D02*
X936058D01*
G01X924058Y1154708D02*
Y1148708D01*
G01X922018Y1377811D02*
X928218D01*
Y1381011D01*
X922018D01*
Y1377811D01*
G01X922045Y1381664D02*
X928245D01*
Y1384864D01*
X922045D01*
Y1381664D01*
G01X922071Y1385439D02*
X928271D01*
Y1388639D01*
X922071D01*
Y1385439D01*
G01X922099Y1389241D02*
X928299D01*
Y1392441D01*
X922099D01*
Y1389241D01*
G01X917163Y1760066D02*
Y1755066D01*
G01Y1767566D02*
Y1765066D01*
G01X917166Y1807935D02*
Y1802935D01*
G01Y1815435D02*
Y1812935D01*
G01X963493Y-46200D02*
Y-43100D01*
X962727D01*
X962420Y-43255D01*
X962190Y-43462D01*
X961998Y-43772D01*
X961845Y-44133D01*
X961807Y-44650D01*
X961845Y-45167D01*
X961998Y-45528D01*
X962190Y-45838D01*
X962420Y-46045D01*
X962727Y-46200D01*
X963493D01*
G01X958783D02*
X960317D01*
Y-43100D01*
X958783D01*
G01X959397Y-44598D02*
X960317D01*
G01X956450Y-46200D02*
Y-43100D01*
X956910Y-43720D01*
G01Y-46200D02*
X955990D01*
G01X954078Y-43617D02*
X953848Y-43307D01*
X953580Y-43152D01*
X953273Y-43100D01*
X952890Y-43203D01*
X952622Y-43462D01*
X952545Y-43772D01*
X952583Y-44082D01*
X952737Y-44340D01*
X953503Y-44857D01*
X953848Y-45218D01*
X954078Y-45735D01*
X954155Y-46200D01*
X952545D01*
G01X950250Y-43100D02*
Y-46200D01*
G01X951132Y-43100D02*
X949368D01*
G01X948300Y-47233D02*
X946000D01*
G01X944778Y-43617D02*
X944548Y-43307D01*
X944280Y-43152D01*
X943973Y-43100D01*
X943590Y-43203D01*
X943322Y-43462D01*
X943245Y-43772D01*
X943283Y-44082D01*
X943437Y-44340D01*
X944203Y-44857D01*
X944548Y-45218D01*
X944778Y-45735D01*
X944855Y-46200D01*
X943245D01*
G01X949237Y90373D02*
Y93473D01*
G01X947627D02*
Y90373D01*
G01Y91923D02*
X949237D01*
G01X945332Y90373D02*
Y93473D01*
X945792Y92853D01*
G01Y90373D02*
X944872D01*
G01X942960Y92956D02*
X942730Y93266D01*
X942462Y93421D01*
X942155Y93473D01*
X941772Y93370D01*
X941504Y93111D01*
X941427Y92801D01*
X941465Y92491D01*
X941619Y92233D01*
X942385Y91716D01*
X942730Y91355D01*
X942960Y90838D01*
X943037Y90373D01*
X941427D01*
G01X938672D02*
Y93473D01*
X940090Y91251D01*
X938174D01*
G01X939028Y209823D02*
X935828D01*
G01X939028Y203623D02*
Y209823D01*
G01X935828Y203623D02*
X939028D01*
G01X935828Y209823D02*
Y203623D01*
G01X932296Y358529D02*
Y361729D01*
G01X931924Y365017D02*
Y368217D01*
G01X929549Y570563D02*
Y575163D01*
G01X937135Y817388D02*
X941735D01*
G01X937135Y827388D02*
X941735D01*
G01Y817388D02*
Y827388D01*
G01X941635Y817388D02*
X941735D01*
G01X937135Y827388D02*
Y817388D01*
G01X944129Y841650D02*
Y846250D01*
G01X934129Y841650D02*
Y846250D01*
G01X944129D02*
X934129D01*
G01X944129Y846150D02*
Y846250D01*
G01X934129Y841650D02*
X944129D01*
G01X934033Y851673D02*
Y847073D01*
G01X944033Y851673D02*
Y847073D01*
G01X934033D02*
X944033D01*
G01X934033Y847173D02*
Y847073D01*
G01X932724Y839056D02*
X929524D01*
G01X932724Y832856D02*
Y839056D01*
G01X929524Y832856D02*
X932724D01*
G01X929524Y839056D02*
Y832856D01*
G01X933524D02*
X936724D01*
G01X933524Y839056D02*
Y832856D01*
G01X936724Y839056D02*
X933524D01*
G01X936724Y832856D02*
Y839056D01*
G01X944033Y851673D02*
X934033D01*
G01X940387Y852532D02*
X943587D01*
G01X940387Y858732D02*
Y852532D01*
G01X943587Y858732D02*
X940387D01*
G01X943587Y852532D02*
Y858732D01*
G01X929618Y857466D02*
Y852016D01*
G01X931918Y857466D02*
X929618D01*
G01X931918Y852016D02*
Y857466D01*
G01X929618Y852016D02*
X931918D01*
G01X942918Y863753D02*
Y869203D01*
G01X940618Y863753D02*
X942918D01*
G01X940618Y869203D02*
Y863753D01*
G01X943880Y863571D02*
X949330D01*
G01X943880Y865871D02*
Y863571D01*
G01X933118Y857466D02*
Y852016D01*
G01X935418Y857466D02*
X933118D01*
G01X935418Y852016D02*
Y857466D01*
G01X933118Y852016D02*
X935418D01*
G01X949422Y861821D02*
X943972D01*
G01Y859521D02*
X949422D01*
G01X943972Y861821D02*
Y859521D01*
G01X945096Y870168D02*
Y880168D01*
G01X940496D02*
Y870168D01*
G01X940596Y880168D02*
X940496D01*
G01X945096Y870168D02*
X940496D01*
G01X945096Y880168D02*
X940496D01*
G01X929661Y885227D02*
Y879027D01*
X932861D01*
Y885227D01*
X929661D01*
G01X942918Y869203D02*
X940618D01*
G01X949330Y865871D02*
X943880D01*
G01X949447Y869318D02*
X943997D01*
G01Y867018D02*
X949447D01*
G01X943997Y869318D02*
Y867018D01*
G01X936544Y880461D02*
Y886661D01*
X933344D01*
Y880461D01*
X936544D01*
G01X937152Y886661D02*
Y880461D01*
X940352D01*
Y886661D01*
X937152D01*
G01X929686Y907237D02*
X932886D01*
G01X929686Y913437D02*
Y907237D01*
G01X932886D02*
Y913437D01*
G01X933686Y907237D02*
X936886D01*
G01X933686Y913437D02*
Y907237D01*
G01X936886D02*
Y913437D01*
G01X934228Y927226D02*
X931028D01*
G01X934228Y921026D02*
Y927226D01*
G01X931028Y921026D02*
X934228D01*
G01X931028Y927226D02*
Y921026D01*
G01X938228Y927226D02*
X935028D01*
G01X938228Y921026D02*
Y927226D01*
G01X935028Y921026D02*
X938228D01*
G01X935028Y927226D02*
Y921026D01*
G01X932886Y913437D02*
X929686D01*
G01X930228Y921026D02*
Y927226D01*
G01X936886Y913437D02*
X933686D01*
G01X941635Y1042537D02*
Y1031032D01*
G01Y1070332D02*
Y1058143D01*
G01X944374Y1055132D02*
Y1046232D01*
G01X964660Y1055132D02*
X944374D01*
G01Y1046232D02*
X964660D01*
G01X942927D02*
Y1055132D01*
G01X948189Y1092816D02*
Y1103016D01*
X943589D01*
Y1092816D01*
X948189D01*
G01X943001Y1092823D02*
Y1103023D01*
X938401D01*
Y1092823D01*
X943001D01*
G01X937730Y1092920D02*
Y1103120D01*
X933130D01*
Y1092920D01*
X937730D01*
G01X935880Y1122636D02*
Y1128636D01*
G01Y1131636D02*
Y1137636D01*
G01X936058Y1140708D02*
Y1146708D01*
G01Y1148708D02*
Y1154708D01*
G01X932371Y1370351D02*
X938571D01*
Y1373551D01*
X932371D01*
Y1370351D01*
G01X932445Y1374278D02*
X938645D01*
Y1377478D01*
X932445D01*
Y1374278D01*
G01X938659Y1396227D02*
X932459D01*
Y1393027D01*
X938659D01*
Y1396227D01*
G01Y1400027D02*
X932459D01*
Y1396827D01*
X938659D01*
Y1400027D01*
G01Y1403827D02*
X932459D01*
Y1400627D01*
X938659D01*
Y1403827D01*
G01Y1407627D02*
X932459D01*
Y1404427D01*
X938659D01*
Y1407627D01*
G01X937413Y1442301D02*
X943613D01*
Y1445501D01*
X937413D01*
Y1442301D01*
G01X948392Y-23498D02*
Y-40098D01*
X957992D01*
Y-23498D01*
X948392D01*
G01X952850Y810155D02*
Y805555D01*
G01X963050Y810155D02*
X952850D01*
G01Y805555D02*
X963050D01*
G01X952850Y815642D02*
Y811042D01*
G01D02*
X963050D01*
G01Y815642D02*
X952850D01*
G01Y821129D02*
Y816529D01*
G01X963050Y821129D02*
X952850D01*
G01Y816529D02*
X963050D01*
G01X949330Y863571D02*
Y865871D01*
G01X949422Y859521D02*
Y861821D01*
G01X949447Y867018D02*
Y869318D01*
G01X954557Y918382D02*
Y924582D01*
X951357D01*
Y918382D01*
X954557D01*
G01X962033Y924716D02*
X955833D01*
Y921516D01*
X962033D01*
Y924716D01*
G01X947458Y924561D02*
Y918361D01*
X950658D01*
Y924561D01*
X947458D01*
G01X963368Y1030724D02*
X945666D01*
G01D02*
Y1042537D01*
G01Y1058143D02*
Y1070024D01*
G01D02*
X963368D01*
G01X957709Y1116103D02*
X969709D01*
G01X957709Y1122103D02*
Y1116103D01*
G01X969709Y1122103D02*
X957709D01*
G01X958178Y1138169D02*
X970178D01*
G01X958178Y1144169D02*
Y1138169D01*
G01X957709Y1125103D02*
X969709D01*
G01X957709Y1131103D02*
Y1125103D01*
G01X969709Y1131103D02*
X957709D01*
G01X970178Y1144169D02*
X958178D01*
G01Y1146169D02*
X970178D01*
G01X958178Y1152169D02*
Y1146169D01*
G01X970178Y1152169D02*
X958178D01*
G01X988693Y-85000D02*
Y-81900D01*
X987927D01*
X987620Y-82055D01*
X987390Y-82262D01*
X987198Y-82572D01*
X987045Y-82933D01*
X987007Y-83450D01*
X987045Y-83967D01*
X987198Y-84328D01*
X987390Y-84638D01*
X987620Y-84845D01*
X987927Y-85000D01*
X988693D01*
G01X983983D02*
X985517D01*
Y-81900D01*
X983983D01*
G01X984597Y-83398D02*
X985517D01*
G01X981650Y-81900D02*
X981957Y-82003D01*
X982187Y-82262D01*
X982340Y-82572D01*
X982455Y-82985D01*
X982493Y-83450D01*
X982455Y-83915D01*
X982340Y-84328D01*
X982187Y-84638D01*
X981957Y-84897D01*
X981650Y-85000D01*
X981343Y-84897D01*
X981113Y-84638D01*
X980960Y-84328D01*
X980845Y-83915D01*
X980807Y-83450D01*
X980845Y-82985D01*
X980960Y-82572D01*
X981113Y-82262D01*
X981343Y-82003D01*
X981650Y-81900D01*
G01X979278Y-82417D02*
X979048Y-82107D01*
X978780Y-81952D01*
X978473Y-81900D01*
X978090Y-82003D01*
X977822Y-82262D01*
X977745Y-82572D01*
X977783Y-82882D01*
X977937Y-83140D01*
X978703Y-83657D01*
X979048Y-84018D01*
X979278Y-84535D01*
X979355Y-85000D01*
X977745D01*
G01X976178D02*
Y-81900D01*
X974722D01*
G01X975258Y-83398D02*
X976178D01*
G01X973500Y-86033D02*
X971200D01*
G01X969978Y-82417D02*
X969748Y-82107D01*
X969480Y-81952D01*
X969173Y-81900D01*
X968790Y-82003D01*
X968522Y-82262D01*
X968445Y-82572D01*
X968483Y-82882D01*
X968637Y-83140D01*
X969403Y-83657D01*
X969748Y-84018D01*
X969978Y-84535D01*
X970055Y-85000D01*
X968445D01*
G01X973236Y-62678D02*
Y-79278D01*
X982836D01*
Y-62678D01*
X973236D01*
G01X963050Y805555D02*
Y810155D01*
G01Y811042D02*
Y815642D01*
G01Y816529D02*
Y821129D01*
G01X974730Y875702D02*
X971530D01*
G01X974730Y869502D02*
Y875702D01*
G01X971530Y869502D02*
X974730D01*
G01X971530Y875702D02*
Y869502D01*
G01X976171Y878542D02*
X979371D01*
G01X976171Y884742D02*
Y878542D01*
G01X979371Y884742D02*
X976171D01*
G01X969733Y899100D02*
Y895900D01*
G01X975933D02*
Y899100D01*
G01X969733Y895900D02*
X975933D01*
G01Y899100D02*
X969733D01*
G01X975933Y899900D02*
Y903100D01*
G01X969733Y899900D02*
X975933D01*
G01X969733Y903100D02*
Y899900D01*
G01X975933Y903100D02*
X969733D01*
G01X975933Y903900D02*
Y907100D01*
G01X969733Y903900D02*
X975933D01*
G01X969733Y907100D02*
Y903900D01*
G01X975933Y907100D02*
X969733D01*
G01X963368Y1042537D02*
Y1030724D01*
G01Y1070024D02*
Y1058143D01*
G01X964660Y1046232D02*
Y1055132D01*
G01X969709Y1116103D02*
Y1122103D01*
G01X970178Y1138169D02*
Y1144169D01*
G01X969709Y1125103D02*
Y1131103D01*
G01X970178Y1146169D02*
Y1152169D01*
G01X970048Y1219532D02*
X973248D01*
G01X970048Y1225732D02*
Y1219532D01*
G01X973248D02*
Y1225732D01*
G01D02*
X970048D01*
G01X973272Y1233157D02*
X970072D01*
G01X973272Y1226957D02*
Y1233157D01*
G01X970072D02*
Y1226957D01*
G01D02*
X973272D01*
G01X963458Y1442874D02*
X969658D01*
Y1446074D01*
X963458D01*
Y1442874D01*
G01X989406Y71448D02*
Y74548D01*
G01X987796D02*
Y71448D01*
G01Y72998D02*
X989406D01*
G01X985501Y71448D02*
Y74548D01*
X985961Y73928D01*
G01Y71448D02*
X985041D01*
G01X982401D02*
Y74548D01*
X982861Y73928D01*
G01Y71448D02*
X981941D01*
G01X979301D02*
Y74548D01*
X979761Y73928D01*
G01Y71448D02*
X978841D01*
G01X992620Y323854D02*
X997220D01*
G01X992620Y334054D02*
Y323854D01*
G01X985720Y324014D02*
X992120D01*
G01D02*
Y336894D01*
G01X985720D02*
Y324014D01*
G01X997220Y334054D02*
X992620D01*
G01X985720Y336894D02*
X992120D01*
G01X981681Y358782D02*
Y364982D01*
G01X978481Y358782D02*
X981681D01*
G01X978481Y364982D02*
Y358782D01*
G01X981681Y364982D02*
X978481D01*
G01X1052362Y388583D02*
G02I-31496J0D01*
G01X988359Y767175D02*
X994559D01*
G01X988359Y770375D02*
Y767175D01*
G01X994559Y770375D02*
X988359D01*
G01X993600Y781900D02*
Y788100D01*
X990400D01*
Y781900D01*
X993600D01*
G01X987479Y875008D02*
Y878208D01*
G01D02*
X981279D01*
G01Y875008D02*
X987479D01*
G01X981279Y878208D02*
Y875008D01*
G01X979371Y878542D02*
Y884742D01*
G01X982004Y891833D02*
Y886833D01*
G01X984204Y894033D02*
X982004Y891833D01*
G01Y896233D02*
X984204Y894033D01*
G01X982004Y901233D02*
Y896233D01*
G01Y886833D02*
X1001604Y886883D01*
G01Y901233D02*
X982004D01*
G01X986924Y1357206D02*
Y1363406D01*
X983724D01*
Y1357206D01*
X986924D01*
G01X989100Y1367600D02*
X995300D01*
Y1370800D01*
X989100D01*
Y1367600D01*
G01Y1371800D02*
X995300D01*
Y1375000D01*
X989100D01*
Y1371800D01*
G01Y1383600D02*
X995300D01*
Y1386800D01*
X989100D01*
Y1383600D01*
G01Y1392600D02*
X995300D01*
Y1395800D01*
X989100D01*
Y1392600D01*
G01Y1387600D02*
X995300D01*
Y1390800D01*
X989100D01*
Y1387600D01*
G01X989071Y1396671D02*
X995271D01*
Y1399871D01*
X989071D01*
Y1396671D01*
G01X985643Y1442640D02*
X991843D01*
Y1445840D01*
X985643D01*
Y1442640D01*
G01X1014893Y-55300D02*
Y-52200D01*
X1014127D01*
X1013820Y-52355D01*
X1013590Y-52562D01*
X1013398Y-52872D01*
X1013245Y-53233D01*
X1013207Y-53750D01*
X1013245Y-54267D01*
X1013398Y-54628D01*
X1013590Y-54938D01*
X1013820Y-55145D01*
X1014127Y-55300D01*
X1014893D01*
G01X1010183D02*
X1011717D01*
Y-52200D01*
X1010183D01*
G01X1010797Y-53698D02*
X1011717D01*
G01X1007850Y-55300D02*
Y-52200D01*
X1008310Y-52820D01*
G01Y-55300D02*
X1007390D01*
G01X1005478Y-54008D02*
X1005210Y-53647D01*
X1004980Y-53440D01*
X1004673Y-53337D01*
X1004405Y-53440D01*
X1004213Y-53647D01*
X1004060Y-53957D01*
X1004022Y-54318D01*
X1004060Y-54628D01*
X1004213Y-54938D01*
X1004443Y-55197D01*
X1004712Y-55300D01*
X1005018Y-55197D01*
X1005287Y-54887D01*
X1005440Y-54422D01*
X1005478Y-53905D01*
X1005402Y-53233D01*
X1005287Y-52872D01*
X1005095Y-52510D01*
X1004827Y-52252D01*
X1004558Y-52200D01*
X1004290Y-52303D01*
X1004098Y-52562D01*
G01X1001650Y-52200D02*
Y-55300D01*
G01X1002532Y-52200D02*
X1000768D01*
G01X999700Y-56333D02*
X997400D01*
G01X996293Y-54680D02*
X996063Y-55042D01*
X995757Y-55248D01*
X995412Y-55300D01*
X995105Y-55248D01*
X994798Y-54990D01*
X994607Y-54680D01*
X994568Y-54370D01*
X994645Y-54008D01*
X994913Y-53750D01*
X995182Y-53647D01*
X995527D01*
G01X995182D02*
X994952Y-53492D01*
X994760Y-53233D01*
X994683Y-52923D01*
X994760Y-52613D01*
X994952Y-52355D01*
X995297Y-52200D01*
X995642Y-52252D01*
X995987Y-52458D01*
G01X1010056Y-50126D02*
Y-33526D01*
X1000456D01*
Y-50126D01*
X1010056D01*
G01X997220Y323854D02*
Y334054D01*
G01X1006916Y314094D02*
X1017116D01*
G01X1006916Y318694D02*
Y314094D01*
G01X1017116Y318694D02*
X1006916D01*
G01X1006158Y329110D02*
Y325910D01*
G01D02*
X1012358D01*
G01X998078Y326307D02*
X1001278D01*
G01X998078Y332507D02*
Y326307D01*
G01X1001278D02*
Y332507D01*
G01X1006158Y324986D02*
Y321786D01*
G01X1012358Y324986D02*
X1006158D01*
G01Y321786D02*
X1012358D01*
G01X1005020Y334654D02*
Y339254D01*
G01X994820Y334654D02*
X1005020D01*
G01X994820Y339254D02*
Y334654D01*
G01X1005020Y339254D02*
X994820D01*
G01Y344254D02*
Y339654D01*
G01X1005020D02*
Y344254D01*
G01X994820Y339654D02*
X1005020D01*
G01X1012358Y329110D02*
X1006158D01*
G01X1001278Y332507D02*
X998078D01*
G01X1006158Y334688D02*
Y331488D01*
G01X1012358Y334688D02*
X1006158D01*
G01Y331488D02*
X1012358D01*
G01X1006158Y341480D02*
Y338280D01*
G01X1012358Y341480D02*
X1006158D01*
G01Y338280D02*
X1012358D01*
G01X1001320Y346654D02*
X1011520D01*
G01X1001320Y351254D02*
Y346654D01*
G01X1011520Y351254D02*
X1001320D01*
G01Y356254D02*
Y351654D01*
G01X1011520Y356254D02*
X1001320D01*
G01Y351654D02*
X1011520D01*
G01X1005020Y344254D02*
X994820D01*
G01X1002480Y462126D02*
Y540866D01*
G01X1081220Y462126D02*
X1002480D01*
G01Y540866D02*
X1002652D01*
G01X1002564D02*
X1081220D01*
G01X994559Y767175D02*
Y770375D01*
G01X1000901Y803075D02*
Y799875D01*
G01X1007101Y803075D02*
X1000901D01*
G01X1007101Y799875D02*
Y803075D01*
G01X1000901Y799875D02*
X1007101D01*
G01X1004905Y818557D02*
Y815357D01*
G01X1011105Y818557D02*
X1004905D01*
G01Y815357D02*
X1011105D01*
G01X1008215Y876794D02*
Y873594D01*
G01X1014415Y876794D02*
X1008215D01*
G01Y873594D02*
X1014415D01*
G01X1008215Y880794D02*
Y877594D01*
G01D02*
X1014415D01*
G01X1002307Y868798D02*
Y871998D01*
G01X996107Y868798D02*
X1002307D01*
G01X996107Y871998D02*
Y868798D01*
G01X1002307Y871998D02*
X996107D01*
G01X1010588Y872914D02*
X1007388D01*
G01Y866714D02*
X1010588D01*
G01X1007388Y872914D02*
Y866714D01*
G01X1014415Y880794D02*
X1008215D01*
G01X1007013Y895900D02*
Y902100D01*
G01X1003813Y895900D02*
X1007013D01*
G01X1003813Y902100D02*
Y895900D01*
G01X1006224Y882253D02*
X1004002D01*
X1003537Y882406D01*
X1003227Y882713D01*
X1003124Y883096D01*
X1003227Y883479D01*
X1003537Y883786D01*
X1004002Y883939D01*
X1006224D01*
G01X1004416Y885468D02*
X1004777Y885736D01*
X1004984Y885966D01*
X1005087Y886273D01*
X1004984Y886541D01*
X1004777Y886733D01*
X1004467Y886886D01*
X1004106Y886924D01*
X1003796Y886886D01*
X1003486Y886733D01*
X1003227Y886503D01*
X1003124Y886234D01*
X1003227Y885928D01*
X1003537Y885659D01*
X1004002Y885506D01*
X1004519Y885468D01*
X1005191Y885544D01*
X1005552Y885659D01*
X1005914Y885851D01*
X1006172Y886119D01*
X1006224Y886388D01*
X1006121Y886656D01*
X1005862Y886848D01*
G01X1003124Y889219D02*
X1003796Y889296D01*
X1004364Y889411D01*
X1004881Y889564D01*
X1005449Y889756D01*
X1006224Y890063D01*
Y888529D01*
G01X1001604Y886883D02*
Y901233D01*
G01X1007013Y902100D02*
X1003813D01*
G01X1006119Y957922D02*
Y951722D01*
X1009319D01*
Y957922D01*
X1006119D01*
G01X1004209Y1049826D02*
G03X1062401Y1066535I26697J16709D01*
G01X1020406Y1096229D02*
G03X999492Y1064282I10500J-29693D01*
G01X1062401Y1263386D02*
G03X1051742Y1239768I-31496J0D01*
G01X1009754Y1442912D02*
X1015954D01*
Y1446112D01*
X1009754D01*
Y1442912D01*
G01X1019543Y304627D02*
X1029743D01*
G01X1019543Y309227D02*
Y304627D01*
G01X1029743Y309227D02*
X1019543D01*
G01X1017116Y314094D02*
Y318694D01*
G01X1019851Y315804D02*
X1023051D01*
G01X1019851Y322004D02*
Y315804D01*
G01X1023051Y322004D02*
X1019851D01*
G01X1023051Y315804D02*
Y322004D01*
G01X1024320Y315728D02*
X1027520D01*
G01X1024320Y321928D02*
Y315728D01*
G01X1027520Y321928D02*
X1024320D01*
G01X1012358Y325910D02*
Y329110D01*
G01Y321786D02*
Y324986D01*
G01X1021945Y339601D02*
Y345801D01*
G01X1018745Y339601D02*
X1021945D01*
G01X1018745Y345801D02*
Y339601D01*
G01X1012358Y331488D02*
Y334688D01*
G01Y338280D02*
Y341480D01*
G01X1011520Y346654D02*
Y351254D01*
G01Y351654D02*
Y356254D01*
G01X1021945Y345801D02*
X1018745D01*
G01X1025935Y753046D02*
X1025667Y753098D01*
X1025360Y753253D01*
X1025168Y753511D01*
X1025092Y753873D01*
X1025168Y754234D01*
X1025398Y754544D01*
X1025743Y754699D01*
X1026127D01*
X1026357Y754803D01*
X1026548Y755061D01*
X1026625Y755423D01*
X1026510Y755784D01*
X1026242Y756043D01*
X1025935Y756146D01*
X1025628Y756043D01*
X1025360Y755784D01*
X1025245Y755423D01*
X1025322Y755061D01*
X1025513Y754803D01*
X1025743Y754699D01*
X1026127D01*
X1026472Y754544D01*
X1026702Y754234D01*
X1026778Y753873D01*
X1026702Y753511D01*
X1026510Y753253D01*
X1026203Y753098D01*
X1025935Y753046D01*
G01X1011105Y815357D02*
Y818557D01*
G01X1026235Y823246D02*
Y826346D01*
X1026695Y825726D01*
G01Y823246D02*
X1025775D01*
G01X1014415Y873594D02*
Y876794D01*
G01Y877594D02*
Y880794D01*
G01X1010588Y866714D02*
Y872914D01*
G01X1014681Y872881D02*
X1011481D01*
G01X1014681Y866681D02*
Y872881D01*
G01X1011481Y866681D02*
X1014681D01*
G01X1011481Y872881D02*
Y866681D01*
G01X1015497Y895596D02*
Y901796D01*
G01X1012297Y895596D02*
X1015497D01*
G01X1012297Y901796D02*
Y895596D01*
G01X1012302Y888730D02*
X1015502D01*
G01X1012302Y894930D02*
Y888730D01*
G01X1015502Y894930D02*
X1012302D01*
G01X1015502Y888730D02*
Y894930D01*
G01X1015497Y901796D02*
X1012297D01*
G01X1028519Y935422D02*
X1022319D01*
Y932222D01*
X1028519D01*
Y935422D01*
G01X1031895Y955822D02*
X1025695D01*
Y952622D01*
X1031895D01*
Y955822D01*
G01X1051401Y90451D02*
Y93551D01*
G01X1049791D02*
Y90451D01*
G01Y92001D02*
X1051401D01*
G01X1047496Y90451D02*
Y93551D01*
X1047956Y92931D01*
G01Y90451D02*
X1047036D01*
G01X1044396D02*
Y93551D01*
X1044856Y92931D01*
G01Y90451D02*
X1043936D01*
G01X1042024Y93034D02*
X1041794Y93344D01*
X1041526Y93499D01*
X1041219Y93551D01*
X1040836Y93448D01*
X1040568Y93189D01*
X1040491Y92879D01*
X1040529Y92569D01*
X1040683Y92311D01*
X1041449Y91794D01*
X1041794Y91433D01*
X1042024Y90916D01*
X1042101Y90451D01*
X1040491D01*
G01X1029743Y304627D02*
Y309227D01*
G01X1038406Y323152D02*
Y326352D01*
G01X1032206Y323152D02*
X1038406D01*
G01X1032206Y326352D02*
Y323152D01*
G01X1038406Y326352D02*
X1032206D01*
G01X1028073Y315804D02*
X1031273D01*
G01X1028073Y322004D02*
Y315804D01*
G01X1031273Y322004D02*
X1028073D01*
G01X1031273Y315804D02*
Y322004D01*
G01X1027520Y315728D02*
Y321928D01*
G01X1040820Y346254D02*
Y341654D01*
G01D02*
X1051020D01*
G01X1042320Y339054D02*
Y335854D01*
G01X1048520Y339054D02*
X1042320D01*
G01Y335854D02*
X1048520D01*
G01X1038385Y336136D02*
Y339336D01*
G01X1032185Y336136D02*
X1038385D01*
G01X1032185Y339336D02*
Y336136D01*
G01X1038385Y339336D02*
X1032185D01*
G01X1038452Y331919D02*
Y335119D01*
G01X1032252Y331919D02*
X1038452D01*
G01X1032252Y335119D02*
Y331919D01*
G01X1038452Y335119D02*
X1032252D01*
G01X1030430Y339544D02*
Y345744D01*
G01X1027230Y339544D02*
X1030430D01*
G01X1027230Y345744D02*
Y339544D01*
G01X1051020Y346254D02*
X1040820D01*
G01X1039480Y354154D02*
Y347754D01*
G01D02*
X1052360D01*
G01Y354154D02*
X1039480D01*
G01X1030430Y345744D02*
X1027230D01*
G01X1028019Y894445D02*
Y891245D01*
G01X1034219Y894445D02*
X1028019D01*
G01X1034219Y891245D02*
Y894445D01*
G01X1028019Y891245D02*
X1034219D01*
G01X1028019Y886445D02*
Y883245D01*
G01X1034219Y886445D02*
X1028019D01*
G01X1034219Y883245D02*
Y886445D01*
G01X1028019Y883245D02*
X1034219D01*
G01X1028019Y890445D02*
Y887245D01*
G01X1034219Y890445D02*
X1028019D01*
G01X1034219Y887245D02*
Y890445D01*
G01X1028019Y887245D02*
X1034219D01*
G01X1054452Y1087453D02*
G03X1036043Y1097609I-23546J-20917D01*
G01X1035420Y1442996D02*
X1041620D01*
Y1446196D01*
X1035420D01*
Y1442996D01*
G01X1049863Y1514762D02*
G03X1101968Y1490945I20609J-23817D01*
G01X1056360Y313654D02*
Y307254D01*
G01X1043480Y313654D02*
Y307254D01*
G01D02*
X1056360D01*
G01X1044820Y319254D02*
Y314654D01*
G01X1055020Y319254D02*
X1044820D01*
G01X1055020Y314654D02*
Y319254D01*
G01X1044820Y314654D02*
X1055020D01*
G01X1056360Y313654D02*
X1043480D01*
G01X1051020Y341654D02*
Y346254D01*
G01X1048520Y335854D02*
Y339054D01*
G01X1052360Y354154D02*
Y347754D01*
G01X1053127Y1440911D02*
Y1447111D01*
X1049927D01*
Y1440911D01*
X1053127D01*
G01X1061048Y1433826D02*
Y1440026D01*
X1057848D01*
Y1433826D01*
X1061048D01*
G01X1053921Y1440025D02*
Y1433825D01*
X1057121D01*
Y1440025D01*
X1053921D01*
G01X1085393Y-94100D02*
Y-91000D01*
X1084627D01*
X1084320Y-91155D01*
X1084090Y-91362D01*
X1083898Y-91672D01*
X1083745Y-92033D01*
X1083707Y-92550D01*
X1083745Y-93067D01*
X1083898Y-93428D01*
X1084090Y-93738D01*
X1084320Y-93945D01*
X1084627Y-94100D01*
X1085393D01*
G01X1080683D02*
X1082217D01*
Y-91000D01*
X1080683D01*
G01X1081297Y-92498D02*
X1082217D01*
G01X1078350Y-91000D02*
X1078657Y-91103D01*
X1078887Y-91362D01*
X1079040Y-91672D01*
X1079155Y-92085D01*
X1079193Y-92550D01*
X1079155Y-93015D01*
X1079040Y-93428D01*
X1078887Y-93738D01*
X1078657Y-93997D01*
X1078350Y-94100D01*
X1078043Y-93997D01*
X1077813Y-93738D01*
X1077660Y-93428D01*
X1077545Y-93015D01*
X1077507Y-92550D01*
X1077545Y-92085D01*
X1077660Y-91672D01*
X1077813Y-91362D01*
X1078043Y-91103D01*
X1078350Y-91000D01*
G01X1075978Y-92808D02*
X1075710Y-92447D01*
X1075480Y-92240D01*
X1075173Y-92137D01*
X1074905Y-92240D01*
X1074713Y-92447D01*
X1074560Y-92757D01*
X1074522Y-93118D01*
X1074560Y-93428D01*
X1074713Y-93738D01*
X1074943Y-93997D01*
X1075212Y-94100D01*
X1075518Y-93997D01*
X1075787Y-93687D01*
X1075940Y-93222D01*
X1075978Y-92705D01*
X1075902Y-92033D01*
X1075787Y-91672D01*
X1075595Y-91310D01*
X1075327Y-91052D01*
X1075058Y-91000D01*
X1074790Y-91103D01*
X1074598Y-91362D01*
G01X1072878Y-94100D02*
Y-91000D01*
X1071422D01*
G01X1071958Y-92498D02*
X1072878D01*
G01X1070200Y-95133D02*
X1067900D01*
G01X1065490Y-94100D02*
Y-91000D01*
X1066908Y-93222D01*
X1064992D01*
G01X1080056Y-89306D02*
Y-72706D01*
X1070456D01*
Y-89306D01*
X1080056D01*
G01X1062401Y1066535D02*
G03X1062035Y1071326I-31496J3D01*
G01X1072612Y1133809D02*
X1075812D01*
G01X1072612Y1140009D02*
Y1133809D01*
G01X1075812Y1140009D02*
X1072612D01*
G01X1068872Y1133809D02*
X1072072D01*
G01X1068872Y1140009D02*
Y1133809D01*
G01X1072072Y1140009D02*
X1068872D01*
G01X1072072Y1133809D02*
Y1140009D01*
G01X1068778Y1150130D02*
Y1146930D01*
G01X1074978Y1150130D02*
X1068778D01*
G01X1074978Y1146930D02*
Y1150130D01*
G01X1068778Y1146930D02*
X1074978D01*
G01X1069237Y1166160D02*
Y1162960D01*
G01X1075437Y1166160D02*
X1069237D01*
G01Y1162960D02*
X1075437D01*
G01X1069237Y1170700D02*
Y1167500D01*
G01X1075437Y1170700D02*
X1069237D01*
G01Y1167500D02*
X1075437D01*
G01X1069022Y1162250D02*
Y1159050D01*
G01X1075222Y1162250D02*
X1069022D01*
G01Y1159050D02*
X1075222D01*
G01X1062291Y1260752D02*
G03X1062401Y1263386I-31386J2630D01*
G01X1074331Y1695110D02*
Y1576803D01*
G01X1094442Y71243D02*
Y74343D01*
G01X1092832D02*
Y71243D01*
G01Y72793D02*
X1094442D01*
G01X1090537Y71243D02*
Y74343D01*
X1090997Y73723D01*
G01Y71243D02*
X1090077D01*
G01X1088165Y73826D02*
X1087935Y74136D01*
X1087667Y74291D01*
X1087360Y74343D01*
X1086977Y74240D01*
X1086709Y73981D01*
X1086632Y73671D01*
X1086670Y73361D01*
X1086824Y73103D01*
X1087590Y72586D01*
X1087935Y72225D01*
X1088165Y71708D01*
X1088242Y71243D01*
X1086632D01*
G01X1084337Y74343D02*
X1084644Y74240D01*
X1084874Y73981D01*
X1085027Y73671D01*
X1085142Y73258D01*
X1085180Y72793D01*
X1085142Y72328D01*
X1085027Y71915D01*
X1084874Y71605D01*
X1084644Y71346D01*
X1084337Y71243D01*
X1084030Y71346D01*
X1083800Y71605D01*
X1083647Y71915D01*
X1083532Y72328D01*
X1083494Y72793D01*
X1083532Y73258D01*
X1083647Y73671D01*
X1083800Y73981D01*
X1084030Y74240D01*
X1084337Y74343D01*
G01X1081220Y540866D02*
Y462126D01*
G01X1078222Y1127708D02*
Y1123108D01*
G01D02*
X1088422D01*
G01D02*
Y1127708D01*
G01D02*
X1078222D01*
G01X1075812Y1133809D02*
Y1140009D01*
G01X1079552D02*
X1076352D01*
G01X1079552Y1133809D02*
Y1140009D01*
G01X1076352Y1133809D02*
X1079552D01*
G01X1076352Y1140009D02*
Y1133809D01*
G01X1075437Y1162960D02*
Y1166160D01*
G01Y1167500D02*
Y1170700D01*
G01X1075222Y1159050D02*
Y1162250D01*
G01X1087500Y1518700D02*
X1097700D01*
Y1523300D01*
X1087500D01*
Y1518700D01*
G01X1101968Y1490945D02*
G03X1077209Y1521712I-31496J0D01*
G01X1093390Y1538857D02*
X1087190D01*
Y1535657D01*
X1093390D01*
Y1538857D01*
G01X1087190Y1531857D02*
X1093390D01*
Y1535057D01*
X1087190D01*
Y1531857D01*
G01X1092673Y552000D02*
Y548800D01*
G01X1098873Y552000D02*
X1092673D01*
G01X1098873Y548800D02*
Y552000D01*
G01X1092673Y548800D02*
X1098873D01*
G01X1092673Y556000D02*
Y552800D01*
G01X1098873D02*
Y556000D01*
G01X1092673Y552800D02*
X1098873D01*
G01X1103459Y546567D02*
Y543367D01*
G01X1109659Y546567D02*
X1103459D01*
G01Y543367D02*
X1109659D01*
G01X1098873Y556000D02*
X1092673D01*
G01X1106173Y592800D02*
X1112373D01*
G01X1106173Y596000D02*
Y592800D01*
G01X1112373Y596000D02*
X1106173D01*
G01Y600800D02*
X1112373D01*
G01X1106173Y604000D02*
Y600800D01*
G01X1112373Y604000D02*
X1106173D01*
G01Y596800D02*
X1112373D01*
G01X1106173Y600000D02*
Y596800D01*
G01X1112373Y600000D02*
X1106173D01*
G01Y604800D02*
X1112373D01*
G01X1106173Y608000D02*
Y604800D01*
G01X1112373Y608000D02*
X1106173D01*
G01Y608800D02*
X1112373D01*
G01X1106173Y612000D02*
Y608800D01*
G01X1112373Y612000D02*
X1106173D01*
G01Y612800D02*
X1112373D01*
G01X1106173Y616000D02*
Y612800D01*
G01X1112373Y616000D02*
X1106173D01*
G01Y620000D02*
Y616800D01*
G01X1112373Y620000D02*
X1106173D01*
G01Y616800D02*
X1112373D01*
G01X1097342Y1191389D02*
Y1186789D01*
G01D02*
X1107542D01*
G01D02*
Y1191389D01*
G01D02*
X1097342D01*
G01X1112063Y1510682D02*
X1104563D01*
Y1508442D01*
X1104938Y1507695D01*
X1105813Y1507135D01*
X1106813Y1506948D01*
X1107813Y1507135D01*
X1108563Y1507602D01*
X1108938Y1508442D01*
Y1510682D01*
G01X1112063Y1503182D02*
X1104563D01*
Y1500848D01*
X1104938Y1500102D01*
X1105438Y1499635D01*
X1106438Y1499448D01*
X1107438Y1499635D01*
X1108063Y1500195D01*
X1108438Y1500848D01*
Y1503182D01*
G01Y1500848D02*
X1112063Y1499448D01*
G01Y1491948D02*
Y1495682D01*
X1104563D01*
Y1491948D01*
G01X1108188Y1493442D02*
Y1495682D01*
G01X1111063Y1488275D02*
X1111688Y1487528D01*
X1112063Y1486688D01*
Y1485942D01*
X1111688Y1485195D01*
X1111063Y1484635D01*
X1110188Y1484355D01*
X1109313Y1484542D01*
X1108563Y1485008D01*
X1108063Y1485848D01*
X1107813Y1486968D01*
X1107313Y1487622D01*
X1106438Y1487902D01*
X1105563Y1487715D01*
X1104938Y1487248D01*
X1104563Y1486595D01*
Y1485942D01*
X1104813Y1485288D01*
X1105438Y1484728D01*
G01X1111063Y1480775D02*
X1111688Y1480028D01*
X1112063Y1479188D01*
Y1478442D01*
X1111688Y1477695D01*
X1111063Y1477135D01*
X1110188Y1476855D01*
X1109313Y1477042D01*
X1108563Y1477508D01*
X1108063Y1478348D01*
X1107813Y1479468D01*
X1107313Y1480122D01*
X1106438Y1480402D01*
X1105563Y1480215D01*
X1104938Y1479748D01*
X1104563Y1479095D01*
Y1478442D01*
X1104813Y1477788D01*
X1105438Y1477228D01*
G01X1109563Y1472528D02*
Y1470102D01*
G01X1112063Y1465588D02*
X1104563D01*
Y1462042D01*
G01X1108188Y1463348D02*
Y1465588D01*
G01X1104563Y1457435D02*
Y1455195D01*
G01Y1456315D02*
X1112063D01*
G01Y1457435D02*
Y1455195D01*
G01X1104563Y1448815D02*
X1112063D01*
G01X1104563Y1450962D02*
Y1446668D01*
G01X1102900Y1514998D02*
X1096700D01*
Y1511798D01*
X1102900D01*
Y1514998D01*
G01X1109793Y254685D02*
Y333425D01*
G01X1188533Y254685D02*
X1109793D01*
G01Y333425D02*
X1109965D01*
G01X1109877D02*
X1188533D01*
G01X1110459Y546567D02*
Y543367D01*
G01X1116659Y546567D02*
X1110459D01*
G01X1116659Y543367D02*
Y546567D01*
G01X1110459Y543367D02*
X1116659D01*
G01X1109659D02*
Y546567D01*
G01X1112373Y592800D02*
Y596000D01*
G01Y600800D02*
Y604000D01*
G01Y596800D02*
Y600000D01*
G01Y604800D02*
Y608000D01*
G01Y608800D02*
Y612000D01*
G01Y612800D02*
Y616000D01*
G01Y616800D02*
Y620000D01*
G01X1109646Y669501D02*
Y748241D01*
G01X1188800Y669539D02*
X1110060D01*
G01X1109646Y748241D02*
X1109818D01*
G01X1109730D02*
X1188386D01*
G01X1130415Y1164591D02*
X1120215D01*
G01D02*
Y1159991D01*
G01D02*
X1130415D01*
G01X1115118Y1425158D02*
Y1689331D01*
G01X1228110Y1425158D02*
X1115118D01*
G01Y1689331D02*
X1228110D01*
G01X1133073Y534900D02*
X1136273D01*
G01X1133073Y541100D02*
Y534900D01*
G01X1136273D02*
Y541100D01*
G01Y548600D02*
X1133073D01*
G01X1136273Y542400D02*
Y548600D01*
G01X1133073Y542400D02*
X1136273D01*
G01X1133073Y548600D02*
Y542400D01*
G01X1136273Y541100D02*
X1133073D01*
G01X1124876Y550147D02*
Y559447D01*
G01X1135476Y550147D02*
X1124876D01*
G01X1135476Y559547D02*
Y550147D01*
G01X1135664Y563918D02*
Y561696D01*
X1135511Y561231D01*
X1135204Y560921D01*
X1134821Y560818D01*
X1134438Y560921D01*
X1134131Y561231D01*
X1133978Y561696D01*
Y563918D01*
G01X1132449Y563401D02*
X1132219Y563711D01*
X1131951Y563866D01*
X1131644Y563918D01*
X1131261Y563815D01*
X1130993Y563556D01*
X1130916Y563246D01*
X1130954Y562936D01*
X1131108Y562678D01*
X1131874Y562161D01*
X1132219Y561800D01*
X1132449Y561283D01*
X1132526Y560818D01*
X1130916D01*
G01X1128621D02*
X1128353Y560870D01*
X1128046Y561025D01*
X1127854Y561283D01*
X1127778Y561645D01*
X1127854Y562006D01*
X1128084Y562316D01*
X1128429Y562471D01*
X1128813D01*
X1129043Y562575D01*
X1129234Y562833D01*
X1129311Y563195D01*
X1129196Y563556D01*
X1128928Y563815D01*
X1128621Y563918D01*
X1128314Y563815D01*
X1128046Y563556D01*
X1127931Y563195D01*
X1128008Y562833D01*
X1128199Y562575D01*
X1128429Y562471D01*
X1128813D01*
X1129158Y562316D01*
X1129388Y562006D01*
X1129464Y561645D01*
X1129388Y561283D01*
X1129196Y561025D01*
X1128889Y560870D01*
X1128621Y560818D01*
G01X1124876Y559547D02*
X1135476D01*
G01X1133275Y770459D02*
X1127075D01*
Y767259D01*
X1133275D01*
Y770459D01*
G01X1129368Y785080D02*
Y773268D01*
X1141992D01*
Y785080D01*
X1129368D01*
G01X1141030Y786674D02*
X1141337Y786726D01*
X1141605Y786932D01*
X1141835Y787242D01*
X1141988Y787604D01*
X1142065Y788017D01*
Y788431D01*
X1141988Y788844D01*
X1141835Y789206D01*
X1141605Y789516D01*
X1141337Y789722D01*
X1141030Y789774D01*
X1140723Y789722D01*
X1140455Y789516D01*
X1140225Y789206D01*
X1140072Y788844D01*
X1139995Y788431D01*
Y788017D01*
X1140072Y787604D01*
X1140225Y787242D01*
X1140455Y786932D01*
X1140723Y786726D01*
X1141030Y786674D01*
G01X1140723Y787501D02*
X1140263Y786674D01*
G01X1138658Y789257D02*
X1138428Y789567D01*
X1138160Y789722D01*
X1137853Y789774D01*
X1137470Y789671D01*
X1137202Y789412D01*
X1137125Y789102D01*
X1137163Y788792D01*
X1137317Y788534D01*
X1138083Y788017D01*
X1138428Y787656D01*
X1138658Y787139D01*
X1138735Y786674D01*
X1137125D01*
G01X1134370D02*
Y789774D01*
X1135788Y787552D01*
X1133872D01*
G01X1131730Y786674D02*
Y789774D01*
X1132190Y789154D01*
G01Y786674D02*
X1131270D01*
G01X1145376Y1164591D02*
X1135176D01*
G01D02*
Y1159991D01*
G01D02*
X1145376D01*
G01X1130415D02*
Y1164591D01*
G01X1136525Y1212352D02*
X1139725D01*
G01X1136525Y1218552D02*
Y1212352D01*
G01X1139725Y1218552D02*
X1136525D01*
G01X1139725Y1212352D02*
Y1218552D01*
G01X1154236Y90491D02*
Y93591D01*
G01X1152626D02*
Y90491D01*
G01Y92041D02*
X1154236D01*
G01X1150331Y90491D02*
Y93591D01*
X1150791Y92971D01*
G01Y90491D02*
X1149871D01*
G01X1147231D02*
Y93591D01*
X1147691Y92971D01*
G01Y90491D02*
X1146771D01*
G01X1144974Y91111D02*
X1144744Y90749D01*
X1144438Y90543D01*
X1144093Y90491D01*
X1143786Y90543D01*
X1143479Y90801D01*
X1143288Y91111D01*
X1143249Y91421D01*
X1143326Y91783D01*
X1143594Y92041D01*
X1143863Y92144D01*
X1144208D01*
G01X1143863D02*
X1143633Y92299D01*
X1143441Y92558D01*
X1143364Y92868D01*
X1143441Y93178D01*
X1143633Y93436D01*
X1143978Y93591D01*
X1144323Y93539D01*
X1144668Y93333D01*
G01X1153582Y425429D02*
X1159782D01*
G01X1153582Y428629D02*
Y425429D01*
G01X1159782Y428629D02*
X1153582D01*
G01Y429429D02*
X1159782D01*
G01X1153582Y432629D02*
Y429429D01*
G01X1159782Y432629D02*
X1153582D01*
G01Y433429D02*
X1159782D01*
G01X1153582Y436629D02*
Y433429D01*
G01X1159782Y436629D02*
X1153582D01*
G01X1163177Y785574D02*
X1151169D01*
Y769534D01*
X1163177D01*
Y785574D01*
G01X1150917Y790031D02*
Y786831D01*
G01X1157117Y790031D02*
X1150917D01*
G01Y786831D02*
X1157117D01*
G01X1150585Y799042D02*
Y802242D01*
G01X1144385Y799042D02*
X1150585D01*
G01X1144385Y802242D02*
Y799042D01*
G01Y798742D02*
Y795542D01*
G01X1150585Y798742D02*
X1144385D01*
G01X1150585Y795542D02*
Y798742D01*
G01X1144385Y795542D02*
X1150585D01*
G01Y802242D02*
X1144385D01*
G01X1150585Y805042D02*
Y808242D01*
G01X1144385Y805042D02*
X1150585D01*
G01X1144385Y808242D02*
Y805042D01*
G01X1150585Y808242D02*
X1144385D01*
G01Y811742D02*
Y808542D01*
G01X1150585Y811742D02*
X1144385D01*
G01X1150585Y808542D02*
Y811742D01*
G01X1144385Y808542D02*
X1150585D01*
G01X1144817Y1131810D02*
Y1121610D01*
G01D02*
X1149417D01*
G01D02*
Y1131810D01*
G01D02*
X1144817D01*
G01X1164077Y1164591D02*
X1153877D01*
G01D02*
Y1159991D01*
G01D02*
X1164077D01*
G01X1145376D02*
Y1164591D01*
G01X1149389Y1197884D02*
Y1208084D01*
G01X1144789D02*
Y1197884D01*
G01D02*
X1149389D01*
G01Y1208084D02*
X1144789D01*
G01X1159782Y425429D02*
Y428629D01*
G01X1160614Y428617D02*
Y425417D01*
G01X1166814D02*
Y428617D01*
G01X1160614Y425417D02*
X1166814D01*
G01X1159782Y429429D02*
Y432629D01*
G01Y433429D02*
Y436629D01*
G01X1166814Y428617D02*
X1160614D01*
G01X1160582Y432629D02*
Y429429D01*
G01X1166782Y432629D02*
X1160582D01*
G01X1166782Y429429D02*
Y432629D01*
G01X1160582Y429429D02*
X1166782D01*
G01X1160582Y436629D02*
Y433429D01*
G01X1166782Y436629D02*
X1160582D01*
G01X1166782Y433429D02*
Y436629D01*
G01X1160582Y433429D02*
X1166782D01*
G01X1171217Y439923D02*
Y436723D01*
G01X1177417Y439923D02*
X1171217D01*
G01Y436723D02*
X1177417D01*
G01X1173597Y454159D02*
Y451937D01*
X1173444Y451472D01*
X1173137Y451162D01*
X1172754Y451059D01*
X1172371Y451162D01*
X1172064Y451472D01*
X1171911Y451937D01*
Y454159D01*
G01X1170497Y451679D02*
X1170267Y451317D01*
X1169961Y451111D01*
X1169616Y451059D01*
X1169309Y451111D01*
X1169002Y451369D01*
X1168811Y451679D01*
X1168772Y451989D01*
X1168849Y452351D01*
X1169117Y452609D01*
X1169386Y452712D01*
X1169731D01*
G01X1169386D02*
X1169156Y452867D01*
X1168964Y453126D01*
X1168887Y453436D01*
X1168964Y453746D01*
X1169156Y454004D01*
X1169501Y454159D01*
X1169846Y454107D01*
X1170191Y453901D01*
G01X1167397Y451679D02*
X1167167Y451317D01*
X1166861Y451111D01*
X1166516Y451059D01*
X1166209Y451111D01*
X1165902Y451369D01*
X1165711Y451679D01*
X1165672Y451989D01*
X1165749Y452351D01*
X1166017Y452609D01*
X1166286Y452712D01*
X1166631D01*
G01X1166286D02*
X1166056Y452867D01*
X1165864Y453126D01*
X1165787Y453436D01*
X1165864Y453746D01*
X1166056Y454004D01*
X1166401Y454159D01*
X1166746Y454107D01*
X1167091Y453901D01*
G01X1167773Y767565D02*
X1165551D01*
X1165086Y767718D01*
X1164776Y768025D01*
X1164673Y768408D01*
X1164776Y768791D01*
X1165086Y769098D01*
X1165551Y769251D01*
X1167773D01*
G01X1165965Y770780D02*
X1166326Y771048D01*
X1166533Y771278D01*
X1166636Y771585D01*
X1166533Y771853D01*
X1166326Y772045D01*
X1166016Y772198D01*
X1165655Y772236D01*
X1165345Y772198D01*
X1165035Y772045D01*
X1164776Y771815D01*
X1164673Y771546D01*
X1164776Y771240D01*
X1165086Y770971D01*
X1165551Y770818D01*
X1166068Y770780D01*
X1166740Y770856D01*
X1167101Y770971D01*
X1167463Y771163D01*
X1167721Y771431D01*
X1167773Y771700D01*
X1167670Y771968D01*
X1167411Y772160D01*
G01X1164673Y775068D02*
X1167773D01*
X1165551Y773650D01*
Y775566D01*
G01X1163173Y775558D02*
X1159773Y777558D01*
X1163073Y779358D01*
G01X1157117Y786831D02*
Y790031D01*
G01X1158597Y792810D02*
X1161797D01*
G01X1158597Y799010D02*
Y792810D01*
G01X1161797Y799010D02*
X1158597D01*
G01X1161797Y792810D02*
Y799010D01*
G01X1172097Y792810D02*
X1175297D01*
G01X1172097Y799010D02*
Y792810D01*
G01X1175297Y799010D02*
X1172097D01*
G01X1165797D02*
X1162597D01*
G01X1165797Y792810D02*
Y799010D01*
G01X1162597Y792810D02*
X1165797D01*
G01X1162597Y799010D02*
Y792810D01*
G01X1171297Y799010D02*
X1168097D01*
G01X1171297Y792810D02*
Y799010D01*
G01X1168097Y792810D02*
X1171297D01*
G01X1168097Y799010D02*
Y792810D01*
G01X1164077Y1159991D02*
Y1164591D01*
G01X1168908Y1746366D02*
X1170518Y1743266D01*
G01X1168908D02*
X1170518Y1746366D01*
G01X1172813D02*
X1173081Y1746314D01*
X1173388Y1746159D01*
X1173580Y1745901D01*
X1173656Y1745539D01*
X1173580Y1745178D01*
X1173350Y1744868D01*
X1173005Y1744713D01*
X1172621D01*
X1172391Y1744609D01*
X1172200Y1744351D01*
X1172123Y1743989D01*
X1172238Y1743628D01*
X1172506Y1743369D01*
X1172813Y1743266D01*
X1173120Y1743369D01*
X1173388Y1743628D01*
X1173503Y1743989D01*
X1173426Y1744351D01*
X1173235Y1744609D01*
X1173005Y1744713D01*
X1172621D01*
X1172276Y1744868D01*
X1172046Y1745178D01*
X1171970Y1745539D01*
X1172046Y1745901D01*
X1172238Y1746159D01*
X1172545Y1746314D01*
X1172813Y1746366D01*
G01X1175913D02*
Y1743266D01*
X1175453Y1743886D01*
G01Y1746366D02*
X1176373D01*
G01X1179263Y1748116D02*
Y1747566D01*
X1169263D01*
G01Y1755066D02*
Y1760066D01*
G01Y1747566D02*
Y1750066D01*
G01Y1765066D02*
Y1767566D01*
X1179263D01*
Y1767016D01*
G01X1168861Y1794235D02*
X1170471Y1791135D01*
G01X1168861D02*
X1170471Y1794235D01*
G01X1172689D02*
X1172766Y1793563D01*
X1172881Y1792995D01*
X1173034Y1792478D01*
X1173226Y1791910D01*
X1173533Y1791135D01*
X1171999D01*
G01X1176326Y1794235D02*
Y1791135D01*
X1174908Y1793357D01*
X1176824D01*
G01X1179216Y1795985D02*
Y1795435D01*
X1169216D01*
G01Y1802935D02*
Y1807935D01*
G01Y1795435D02*
Y1797935D01*
G01Y1812935D02*
Y1815435D01*
X1179216D01*
Y1814885D01*
G01X1188533Y333425D02*
Y254685D01*
G01X1187073Y382900D02*
X1193273D01*
G01X1187073Y386100D02*
Y382900D01*
G01X1193273Y386100D02*
X1187073D01*
G01Y386400D02*
X1193273D01*
G01X1187073Y389600D02*
Y386400D01*
G01X1193273Y389600D02*
X1187073D01*
G01X1177417Y436723D02*
Y439923D01*
G01X1181436Y444206D02*
Y441006D01*
G01X1187636D02*
Y444206D01*
G01X1181436Y441006D02*
X1187636D01*
G01Y444206D02*
X1181436D01*
G01Y448206D02*
Y445006D01*
G01X1187636Y448206D02*
X1181436D01*
G01X1187636Y445006D02*
Y448206D01*
G01X1181436Y445006D02*
X1187636D01*
G01X1191508Y449871D02*
X1182208D01*
G01X1182108D02*
Y460471D01*
G01X1182743Y461879D02*
X1188943D01*
G01X1182743Y465079D02*
Y461879D01*
G01X1188943Y465079D02*
X1182743D01*
G01X1182108Y460471D02*
X1191508D01*
G01X1188386Y748241D02*
Y669501D01*
G01X1175297Y792810D02*
Y799010D01*
G01X1179031Y875913D02*
X1175831D01*
G01X1179031Y869713D02*
Y875913D01*
G01X1175831Y869713D02*
X1179031D01*
G01X1175831Y875913D02*
Y869713D01*
G01X1185831Y877213D02*
X1189031D01*
G01X1185831Y883413D02*
Y877213D01*
G01Y869713D02*
X1189031D01*
G01X1185831Y875913D02*
Y869713D01*
G01X1189031Y875913D02*
X1185831D01*
G01X1179031Y877213D02*
Y883413D01*
G01X1175831Y877213D02*
X1179031D01*
G01X1175831Y883413D02*
Y877213D01*
G01X1181831Y869713D02*
X1185031D01*
G01X1181831Y875913D02*
Y869713D01*
G01X1185031Y875913D02*
X1181831D01*
G01X1185031Y869713D02*
Y875913D01*
G01X1175052Y890499D02*
Y887299D01*
G01X1181252Y890499D02*
X1175052D01*
G01X1181252Y887299D02*
Y890499D01*
G01X1175052Y887299D02*
X1181252D01*
G01X1189031Y883413D02*
X1185831D01*
G01X1179031D02*
X1175831D01*
G01X1184143Y903034D02*
X1182950Y904034D01*
G01Y902134D02*
X1184143Y903034D01*
G01X1182950Y907134D02*
Y904034D01*
G01X1195352Y907134D02*
X1182950D01*
G01Y898934D02*
X1195352D01*
G01X1182950Y902034D02*
Y898934D01*
G01X1178786Y928934D02*
Y935134D01*
G01X1175586Y928934D02*
X1178786D01*
G01X1175586Y935134D02*
Y928934D01*
G01X1185551D02*
X1188751D01*
G01X1185551Y935134D02*
Y928934D01*
G01X1188751D02*
Y935134D01*
G01X1182751Y928934D02*
Y935134D01*
G01X1179551Y928934D02*
X1182751D01*
G01X1179551Y935134D02*
Y928934D01*
G01X1185551Y921934D02*
X1188751D01*
G01X1185551Y928134D02*
Y921934D01*
G01X1188751Y928134D02*
X1185551D01*
G01X1188751Y921934D02*
Y928134D01*
G01X1182751D02*
X1179551D01*
G01X1182751Y921934D02*
Y928134D01*
G01X1179551Y921934D02*
X1182751D01*
G01X1179551Y928134D02*
Y921934D01*
G01X1178786Y935134D02*
X1175586D01*
G01X1188751D02*
X1185551D01*
G01X1182751D02*
X1179551D01*
G01X1187619Y941689D02*
X1190819D01*
G01X1187619Y947889D02*
Y941689D01*
G01X1185008Y954364D02*
X1182786D01*
X1182321Y954517D01*
X1182011Y954824D01*
X1181908Y955207D01*
X1182011Y955590D01*
X1182321Y955897D01*
X1182786Y956050D01*
X1185008D01*
G01X1182528Y957464D02*
X1182166Y957694D01*
X1181960Y958000D01*
X1181908Y958345D01*
X1181960Y958652D01*
X1182218Y958959D01*
X1182528Y959150D01*
X1182838Y959189D01*
X1183200Y959112D01*
X1183458Y958844D01*
X1183561Y958575D01*
Y958230D01*
G01Y958575D02*
X1183716Y958805D01*
X1183975Y958997D01*
X1184285Y959074D01*
X1184595Y958997D01*
X1184853Y958805D01*
X1185008Y958460D01*
X1184956Y958115D01*
X1184750Y957770D01*
G01X1181908Y961407D02*
X1185008D01*
X1184388Y960947D01*
G01X1181908D02*
Y961867D01*
G01Y964507D02*
X1181960Y964775D01*
X1182115Y965082D01*
X1182373Y965274D01*
X1182735Y965350D01*
X1183096Y965274D01*
X1183406Y965044D01*
X1183561Y964699D01*
Y964315D01*
X1183665Y964085D01*
X1183923Y963894D01*
X1184285Y963817D01*
X1184646Y963932D01*
X1184905Y964200D01*
X1185008Y964507D01*
X1184905Y964814D01*
X1184646Y965082D01*
X1184285Y965197D01*
X1183923Y965120D01*
X1183665Y964929D01*
X1183561Y964699D01*
Y964315D01*
X1183406Y963970D01*
X1183096Y963740D01*
X1182735Y963664D01*
X1182373Y963740D01*
X1182115Y963932D01*
X1181960Y964239D01*
X1181908Y964507D01*
G01X1190819Y947889D02*
X1187619D01*
G01X1185983Y962397D02*
X1198187D01*
G01X1185983Y973921D02*
Y962397D01*
G01X1198187Y973921D02*
X1185983D01*
G01X1184379Y973343D02*
X1181179D01*
G01X1184379Y967143D02*
Y973343D01*
G01X1181179Y967143D02*
X1184379D01*
G01X1181179Y973343D02*
Y967143D01*
G01X1187619Y988189D02*
X1190819D01*
G01X1187619Y994389D02*
Y988189D01*
G01X1190819Y994389D02*
X1187619D01*
G01X1179263Y1758116D02*
Y1757016D01*
G01X1179216Y1805985D02*
Y1804885D01*
G01X1205738Y50669D02*
Y53769D01*
G01X1204128D02*
Y50669D01*
G01Y52219D02*
X1205738D01*
G01X1201833Y50669D02*
Y53769D01*
X1202293Y53149D01*
G01Y50669D02*
X1201373D01*
G01X1199461Y53252D02*
X1199231Y53562D01*
X1198963Y53717D01*
X1198656Y53769D01*
X1198273Y53666D01*
X1198005Y53407D01*
X1197928Y53097D01*
X1197966Y52787D01*
X1198120Y52529D01*
X1198886Y52012D01*
X1199231Y51651D01*
X1199461Y51134D01*
X1199538Y50669D01*
X1197928D01*
G01X1195633D02*
Y53769D01*
X1196093Y53149D01*
G01Y50669D02*
X1195173D01*
G01X1193573Y386100D02*
Y382900D01*
G01X1199773Y386100D02*
X1193573D01*
G01X1199773Y382900D02*
Y386100D01*
G01X1193573Y382900D02*
X1199773D01*
G01Y386400D02*
Y389600D01*
G01X1193573Y386400D02*
X1199773D01*
G01X1193573Y389600D02*
Y386400D01*
G01X1199773Y389600D02*
X1193573D01*
G01X1193273Y382900D02*
Y386100D01*
G01Y386400D02*
Y389600D01*
G01X1199544Y453552D02*
X1205744D01*
G01X1199544Y456752D02*
Y453552D01*
G01X1205744Y456752D02*
X1199544D01*
G01Y449552D02*
X1205744D01*
G01X1199544Y452752D02*
Y449552D01*
G01X1205744Y452752D02*
X1199544D01*
G01X1191508Y460471D02*
Y449871D01*
G01X1188943Y461879D02*
Y465079D01*
G01X1197928Y461635D02*
Y464835D01*
G01X1191728Y461635D02*
X1197928D01*
G01X1191728Y464835D02*
Y461635D01*
G01X1197928Y464835D02*
X1191728D01*
G01X1191745Y468967D02*
Y465767D01*
G01X1197945Y468967D02*
X1191745D01*
G01X1197945Y465767D02*
Y468967D01*
G01X1191745Y465767D02*
X1197945D01*
G01X1194031Y875913D02*
X1190831D01*
G01X1194031Y869713D02*
Y875913D01*
G01X1190831Y869713D02*
X1194031D01*
G01X1190831Y875913D02*
Y869713D01*
G01X1194031Y877213D02*
Y883413D01*
G01X1190831Y877213D02*
X1194031D01*
G01X1190831Y883413D02*
Y877213D01*
G01X1189031D02*
Y883413D01*
G01Y869713D02*
Y875913D01*
G01X1194031Y883413D02*
X1190831D01*
G01X1199832Y897617D02*
X1197610D01*
X1197145Y897770D01*
X1196835Y898077D01*
X1196732Y898460D01*
X1196835Y898843D01*
X1197145Y899150D01*
X1197610Y899303D01*
X1199832D01*
G01X1197352Y900717D02*
X1196990Y900947D01*
X1196784Y901253D01*
X1196732Y901598D01*
X1196784Y901905D01*
X1197042Y902212D01*
X1197352Y902403D01*
X1197662Y902442D01*
X1198024Y902365D01*
X1198282Y902097D01*
X1198385Y901828D01*
Y901483D01*
G01Y901828D02*
X1198540Y902058D01*
X1198799Y902250D01*
X1199109Y902327D01*
X1199419Y902250D01*
X1199677Y902058D01*
X1199832Y901713D01*
X1199780Y901368D01*
X1199574Y901023D01*
G01X1199832Y904660D02*
X1199729Y904353D01*
X1199470Y904123D01*
X1199160Y903970D01*
X1198747Y903855D01*
X1198282Y903817D01*
X1197817Y903855D01*
X1197404Y903970D01*
X1197094Y904123D01*
X1196835Y904353D01*
X1196732Y904660D01*
X1196835Y904967D01*
X1197094Y905197D01*
X1197404Y905350D01*
X1197817Y905465D01*
X1198282Y905503D01*
X1198747Y905465D01*
X1199160Y905350D01*
X1199470Y905197D01*
X1199729Y904967D01*
X1199832Y904660D01*
G01X1197094Y907108D02*
X1196835Y907377D01*
X1196732Y907683D01*
X1196835Y907990D01*
X1197145Y908258D01*
X1197610Y908450D01*
X1198075Y908527D01*
X1198644D01*
X1199109Y908450D01*
X1199522Y908258D01*
X1199729Y908028D01*
X1199832Y907760D01*
X1199729Y907453D01*
X1199522Y907223D01*
X1199212Y907070D01*
X1198799Y906993D01*
X1198437Y907070D01*
X1198075Y907262D01*
X1197869Y907492D01*
X1197817Y907760D01*
X1197920Y908067D01*
X1198179Y908297D01*
X1198644Y908527D01*
G01X1195352Y898934D02*
Y907134D01*
G01X1196718Y928934D02*
Y935134D01*
G01X1193518Y928934D02*
X1196718D01*
G01X1193518Y935134D02*
Y928934D01*
G01X1192751Y928134D02*
X1189551D01*
G01X1192751Y921934D02*
Y928134D01*
G01X1189551Y921934D02*
X1192751D01*
G01X1189551Y928134D02*
Y921934D01*
G01X1192751Y928934D02*
Y935134D01*
G01X1189551Y928934D02*
X1192751D01*
G01X1189551Y935134D02*
Y928934D01*
G01X1196718Y935134D02*
X1193518D01*
G01X1194819Y941689D02*
Y947889D01*
G01X1191619Y941689D02*
X1194819D01*
G01X1191619Y947889D02*
Y941689D01*
G01X1202819D02*
Y947889D01*
G01X1199619Y941689D02*
X1202819D01*
G01X1199619Y947889D02*
Y941689D01*
G01X1198819D02*
Y947889D01*
G01X1195619Y941689D02*
X1198819D01*
G01X1195619Y947889D02*
Y941689D01*
G01X1192751Y935134D02*
X1189551D01*
G01X1190819Y941689D02*
Y947889D01*
G01X1202819Y952189D02*
Y955389D01*
G01X1196619Y952189D02*
X1202819D01*
G01X1196619Y955389D02*
Y952189D01*
G01X1202819Y955389D02*
X1196619D01*
G01X1194819Y947889D02*
X1191619D01*
G01X1202819D02*
X1199619D01*
G01X1198819D02*
X1195619D01*
G01X1198187Y971159D02*
Y973921D01*
G01X1195085Y968159D02*
X1198187Y971159D01*
G01Y965057D02*
X1195085Y968159D01*
G01X1198187Y962397D02*
Y965057D01*
G01X1204319Y972389D02*
X1201119D01*
G01X1204319Y966189D02*
Y972389D01*
G01X1201119Y966189D02*
X1204319D01*
G01X1201119Y972389D02*
Y966189D01*
G01X1202819Y981189D02*
Y984389D01*
G01X1196619Y981189D02*
X1202819D01*
G01X1196619Y984389D02*
Y981189D01*
G01X1202819Y984389D02*
X1196619D01*
G01X1194819Y988189D02*
Y994389D01*
G01X1191619Y988189D02*
X1194819D01*
G01X1191619Y994389D02*
Y988189D01*
G01X1190819D02*
Y994389D01*
G01X1194819D02*
X1191619D01*
G01X1204017Y1182431D02*
X1207217D01*
G01X1204017Y1188631D02*
Y1182431D01*
G01X1207217Y1188631D02*
X1204017D01*
G01X1207217Y1181150D02*
X1204017D01*
G01Y1174950D02*
X1207217D01*
G01X1204017Y1181150D02*
Y1174950D01*
G01X1216356Y379512D02*
Y376312D01*
G01D02*
X1222556D01*
G01Y379512D02*
X1216356D01*
G01Y391512D02*
Y388312D01*
G01X1222556Y391512D02*
X1216356D01*
G01Y388312D02*
X1222556D01*
G01X1216356Y383512D02*
Y380312D01*
G01X1222556Y383512D02*
X1216356D01*
G01Y380312D02*
X1222556D01*
G01X1216356Y395524D02*
Y392324D01*
G01D02*
X1222556D01*
G01X1216356Y387512D02*
Y384312D01*
G01X1222556Y387512D02*
X1216356D01*
G01Y384312D02*
X1222556D01*
G01Y395524D02*
X1216356D01*
G01Y399512D02*
Y396312D01*
G01X1222556Y399512D02*
X1216356D01*
G01Y396312D02*
X1222556D01*
G01X1216356Y403524D02*
Y400324D01*
G01X1222556Y403524D02*
X1216356D01*
G01Y400324D02*
X1222556D01*
G01X1216356Y407524D02*
Y404324D01*
G01X1222556Y407524D02*
X1216356D01*
G01Y404324D02*
X1222556D01*
G01X1216356Y411524D02*
Y408324D01*
G01D02*
X1222556D01*
G01Y411524D02*
X1216356D01*
G01X1205744Y453552D02*
Y456752D01*
G01Y449552D02*
Y452752D01*
G01X1218230Y453305D02*
X1215030D01*
G01X1218230Y447105D02*
Y453305D01*
G01X1215030Y447105D02*
X1218230D01*
G01X1215030Y453305D02*
Y447105D01*
G01X1214280Y453305D02*
X1211080D01*
G01X1214280Y447105D02*
Y453305D01*
G01X1211080Y447105D02*
X1214280D01*
G01X1211080Y453305D02*
Y447105D01*
G01X1216762Y461868D02*
Y540608D01*
G01X1295502Y461868D02*
X1216762D01*
G01Y540866D02*
X1216934D01*
G01X1216846Y540608D02*
X1295502D01*
G01X1208819Y972389D02*
X1205619D01*
G01X1208819Y966189D02*
Y972389D01*
G01X1205619Y966189D02*
X1208819D01*
G01X1205619Y972389D02*
Y966189D01*
G01X1213898Y1137549D02*
Y1143749D01*
G01X1210698Y1137549D02*
X1213898D01*
G01X1210698Y1143749D02*
Y1137549D01*
G01X1213898Y1143749D02*
X1210698D01*
G01X1213898Y1151229D02*
X1210698D01*
G01X1213898Y1145029D02*
Y1151229D01*
G01X1210698Y1145029D02*
X1213898D01*
G01X1210698Y1151229D02*
Y1145029D01*
G01X1218135Y1160779D02*
X1228335D01*
G01Y1165379D02*
X1218135D01*
G01D02*
Y1160779D01*
G01X1217371Y1165390D02*
X1207171D01*
G01D02*
Y1160790D01*
G01D02*
X1217371D01*
G01D02*
Y1165390D01*
G01X1207217Y1182431D02*
Y1188631D01*
G01Y1174950D02*
Y1181150D01*
G01X1221079Y1744208D02*
X1255655Y1731095D01*
G01Y1757321D02*
X1221079Y1744208D01*
G01X1242493Y-94400D02*
Y-91300D01*
X1241727D01*
X1241420Y-91455D01*
X1241190Y-91662D01*
X1240998Y-91972D01*
X1240845Y-92333D01*
X1240807Y-92850D01*
X1240845Y-93367D01*
X1240998Y-93728D01*
X1241190Y-94038D01*
X1241420Y-94245D01*
X1241727Y-94400D01*
X1242493D01*
G01X1237783D02*
X1239317D01*
Y-91300D01*
X1237783D01*
G01X1238397Y-92798D02*
X1239317D01*
G01X1235450Y-91300D02*
X1235757Y-91403D01*
X1235987Y-91662D01*
X1236140Y-91972D01*
X1236255Y-92385D01*
X1236293Y-92850D01*
X1236255Y-93315D01*
X1236140Y-93728D01*
X1235987Y-94038D01*
X1235757Y-94297D01*
X1235450Y-94400D01*
X1235143Y-94297D01*
X1234913Y-94038D01*
X1234760Y-93728D01*
X1234645Y-93315D01*
X1234607Y-92850D01*
X1234645Y-92385D01*
X1234760Y-91972D01*
X1234913Y-91662D01*
X1235143Y-91403D01*
X1235450Y-91300D01*
G01X1233078Y-93108D02*
X1232810Y-92747D01*
X1232580Y-92540D01*
X1232273Y-92437D01*
X1232005Y-92540D01*
X1231813Y-92747D01*
X1231660Y-93057D01*
X1231622Y-93418D01*
X1231660Y-93728D01*
X1231813Y-94038D01*
X1232043Y-94297D01*
X1232312Y-94400D01*
X1232618Y-94297D01*
X1232887Y-93987D01*
X1233040Y-93522D01*
X1233078Y-93005D01*
X1233002Y-92333D01*
X1232887Y-91972D01*
X1232695Y-91610D01*
X1232427Y-91352D01*
X1232158Y-91300D01*
X1231890Y-91403D01*
X1231698Y-91662D01*
G01X1229978Y-94400D02*
Y-91300D01*
X1228522D01*
G01X1229058Y-92798D02*
X1229978D01*
G01X1227300Y-95433D02*
X1225000D01*
G01X1223893Y-93780D02*
X1223663Y-94142D01*
X1223357Y-94348D01*
X1223012Y-94400D01*
X1222705Y-94348D01*
X1222398Y-94090D01*
X1222207Y-93780D01*
X1222168Y-93470D01*
X1222245Y-93108D01*
X1222513Y-92850D01*
X1222782Y-92747D01*
X1223127D01*
G01X1222782D02*
X1222552Y-92592D01*
X1222360Y-92333D01*
X1222283Y-92023D01*
X1222360Y-91713D01*
X1222552Y-91455D01*
X1222897Y-91300D01*
X1223242Y-91352D01*
X1223587Y-91558D01*
G01X1226536Y-72678D02*
Y-89278D01*
X1236136D01*
Y-72678D01*
X1226536D01*
G01X1247393Y-55400D02*
Y-52300D01*
X1246627D01*
X1246320Y-52455D01*
X1246090Y-52662D01*
X1245898Y-52972D01*
X1245745Y-53333D01*
X1245707Y-53850D01*
X1245745Y-54367D01*
X1245898Y-54728D01*
X1246090Y-55038D01*
X1246320Y-55245D01*
X1246627Y-55400D01*
X1247393D01*
G01X1242683D02*
X1244217D01*
Y-52300D01*
X1242683D01*
G01X1243297Y-53798D02*
X1244217D01*
G01X1240350Y-55400D02*
Y-52300D01*
X1240810Y-52920D01*
G01Y-55400D02*
X1239890D01*
G01X1237978Y-54108D02*
X1237710Y-53747D01*
X1237480Y-53540D01*
X1237173Y-53437D01*
X1236905Y-53540D01*
X1236713Y-53747D01*
X1236560Y-54057D01*
X1236522Y-54418D01*
X1236560Y-54728D01*
X1236713Y-55038D01*
X1236943Y-55297D01*
X1237212Y-55400D01*
X1237518Y-55297D01*
X1237787Y-54987D01*
X1237940Y-54522D01*
X1237978Y-54005D01*
X1237902Y-53333D01*
X1237787Y-52972D01*
X1237595Y-52610D01*
X1237327Y-52352D01*
X1237058Y-52300D01*
X1236790Y-52403D01*
X1236598Y-52662D01*
G01X1234150Y-52300D02*
Y-55400D01*
G01X1235032Y-52300D02*
X1233268D01*
G01X1232200Y-56433D02*
X1229900D01*
G01X1227490Y-55400D02*
Y-52300D01*
X1228908Y-54522D01*
X1226992D01*
G01X1231892Y-33628D02*
Y-50228D01*
X1241492D01*
Y-33628D01*
X1231892D01*
G01X1222556Y376312D02*
Y379512D01*
G01Y388312D02*
Y391512D01*
G01Y380312D02*
Y383512D01*
G01Y392324D02*
Y395524D01*
G01Y384312D02*
Y387512D01*
G01Y396312D02*
Y399512D01*
G01Y400324D02*
Y403524D01*
G01Y404324D02*
Y407524D01*
G01Y408324D02*
Y411524D01*
G01X1235729Y1069048D02*
G03X1298621Y1066535I31396J-2513D01*
G01X1228335Y1160779D02*
Y1165379D01*
G01X1298621Y1263386D02*
G03X1235643Y1262440I-31496J0D01*
G01X1228110Y1689331D02*
Y1425158D01*
G01X1255843Y90451D02*
Y93551D01*
G01X1254233D02*
Y90451D01*
G01Y92001D02*
X1255843D01*
G01X1251938Y90451D02*
Y93551D01*
X1252398Y92931D01*
G01Y90451D02*
X1251478D01*
G01X1249566Y93034D02*
X1249336Y93344D01*
X1249068Y93499D01*
X1248761Y93551D01*
X1248378Y93448D01*
X1248110Y93189D01*
X1248033Y92879D01*
X1248071Y92569D01*
X1248225Y92311D01*
X1248991Y91794D01*
X1249336Y91433D01*
X1249566Y90916D01*
X1249643Y90451D01*
X1248033D01*
G01X1246466Y93034D02*
X1246236Y93344D01*
X1245968Y93499D01*
X1245661Y93551D01*
X1245278Y93448D01*
X1245010Y93189D01*
X1244933Y92879D01*
X1244971Y92569D01*
X1245125Y92311D01*
X1245891Y91794D01*
X1246236Y91433D01*
X1246466Y90916D01*
X1246543Y90451D01*
X1244933D01*
G01X1298621Y1066535D02*
G03X1245692Y1089614I-31496J0D01*
G01X1245637Y1240359D02*
G03X1298621Y1263386I21488J23028D01*
G01X1259130Y328857D02*
Y325657D01*
G01X1265330D02*
Y328857D01*
G01X1259130Y325657D02*
X1265330D01*
G01X1266037Y328857D02*
Y325657D01*
G01D02*
X1272237D01*
G01X1265330Y328857D02*
X1259130D01*
G01X1272237D02*
X1266037D01*
G01X1268133Y862872D02*
X1271333D01*
G01X1268133Y869072D02*
Y862872D01*
G01X1271333Y869072D02*
X1268133D01*
G01X1277449Y943464D02*
X1277756Y943516D01*
X1278024Y943722D01*
X1278254Y944032D01*
X1278407Y944394D01*
X1278484Y944807D01*
Y945221D01*
X1278407Y945634D01*
X1278254Y945996D01*
X1278024Y946306D01*
X1277756Y946512D01*
X1277449Y946564D01*
X1277142Y946512D01*
X1276874Y946306D01*
X1276644Y945996D01*
X1276491Y945634D01*
X1276414Y945221D01*
Y944807D01*
X1276491Y944394D01*
X1276644Y944032D01*
X1276874Y943722D01*
X1277142Y943516D01*
X1277449Y943464D01*
G01X1277142Y944291D02*
X1276682Y943464D01*
G01X1274349D02*
Y946564D01*
X1274809Y945944D01*
G01Y943464D02*
X1273889D01*
G01X1271977Y946047D02*
X1271747Y946357D01*
X1271479Y946512D01*
X1271172Y946564D01*
X1270789Y946461D01*
X1270521Y946202D01*
X1270444Y945892D01*
X1270482Y945582D01*
X1270636Y945324D01*
X1271402Y944807D01*
X1271747Y944446D01*
X1271977Y943929D01*
X1272054Y943464D01*
X1270444D01*
G01X1267689D02*
Y946564D01*
X1269107Y944342D01*
X1267191D01*
G01X1267642Y942028D02*
X1278156D01*
G01X1267642Y933366D02*
Y942028D01*
G01X1278156Y933366D02*
X1267642D01*
G01X1259834Y1738525D02*
X1260144Y1738333D01*
X1260351Y1738103D01*
X1260454Y1737835D01*
X1260351Y1737528D01*
X1260144Y1737298D01*
X1259834Y1737068D01*
X1259421Y1736991D01*
X1257354D01*
G01X1260454Y1734198D02*
X1257354D01*
X1259576Y1735616D01*
Y1733700D01*
G01X1260454Y1731635D02*
X1259782Y1731558D01*
X1259214Y1731443D01*
X1258697Y1731290D01*
X1258129Y1731098D01*
X1257354Y1730791D01*
Y1732325D01*
G01X1255655Y1731095D02*
Y1757321D01*
G01X1302493Y-55200D02*
Y-52100D01*
X1301727D01*
X1301420Y-52255D01*
X1301190Y-52462D01*
X1300998Y-52772D01*
X1300845Y-53133D01*
X1300807Y-53650D01*
X1300845Y-54167D01*
X1300998Y-54528D01*
X1301190Y-54838D01*
X1301420Y-55045D01*
X1301727Y-55200D01*
X1302493D01*
G01X1297783D02*
X1299317D01*
Y-52100D01*
X1297783D01*
G01X1298397Y-53598D02*
X1299317D01*
G01X1295450Y-55200D02*
Y-52100D01*
X1295910Y-52720D01*
G01Y-55200D02*
X1294990D01*
G01X1293078Y-53908D02*
X1292810Y-53547D01*
X1292580Y-53340D01*
X1292273Y-53237D01*
X1292005Y-53340D01*
X1291813Y-53547D01*
X1291660Y-53857D01*
X1291622Y-54218D01*
X1291660Y-54528D01*
X1291813Y-54838D01*
X1292043Y-55097D01*
X1292312Y-55200D01*
X1292618Y-55097D01*
X1292887Y-54787D01*
X1293040Y-54322D01*
X1293078Y-53805D01*
X1293002Y-53133D01*
X1292887Y-52772D01*
X1292695Y-52410D01*
X1292427Y-52152D01*
X1292158Y-52100D01*
X1291890Y-52203D01*
X1291698Y-52462D01*
G01X1289250Y-52100D02*
Y-55200D01*
G01X1290132Y-52100D02*
X1288368D01*
G01X1287300Y-56233D02*
X1285000D01*
G01X1283050Y-55200D02*
Y-52100D01*
X1283510Y-52720D01*
G01Y-55200D02*
X1282590D01*
G01X1272237Y325657D02*
Y328857D01*
G01X1274900Y332100D02*
Y328900D01*
G01X1281100Y332100D02*
X1274900D01*
G01X1281100Y328900D02*
Y332100D01*
G01X1274900Y328900D02*
X1281100D01*
G01X1274900Y336100D02*
Y332900D01*
G01X1281100Y336100D02*
X1274900D01*
G01X1281100Y332900D02*
Y336100D01*
G01X1274900Y332900D02*
X1281100D01*
G01X1271333Y862872D02*
Y869072D01*
G01X1285405Y899716D02*
Y895116D01*
G01D02*
X1295605D01*
G01Y899716D02*
X1285405D01*
G01X1280817Y903573D02*
Y906773D01*
G01X1274617Y903573D02*
X1280817D01*
G01X1274617Y906773D02*
Y903573D01*
G01X1280817Y906773D02*
X1274617D01*
G01X1278156Y942028D02*
Y933366D01*
G01X1284037Y1496511D02*
X1276537D01*
Y1494271D01*
X1276912Y1493524D01*
X1277787Y1492964D01*
X1278787Y1492777D01*
X1279787Y1492964D01*
X1280537Y1493431D01*
X1280912Y1494271D01*
Y1496511D01*
G01X1284037Y1489011D02*
X1276537D01*
Y1486677D01*
X1276912Y1485931D01*
X1277412Y1485464D01*
X1278412Y1485277D01*
X1279412Y1485464D01*
X1280037Y1486024D01*
X1280412Y1486677D01*
Y1489011D01*
G01Y1486677D02*
X1284037Y1485277D01*
G01Y1477777D02*
Y1481511D01*
X1276537D01*
Y1477777D01*
G01X1280162Y1479271D02*
Y1481511D01*
G01X1283037Y1474104D02*
X1283662Y1473357D01*
X1284037Y1472517D01*
Y1471771D01*
X1283662Y1471024D01*
X1283037Y1470464D01*
X1282162Y1470184D01*
X1281287Y1470371D01*
X1280537Y1470837D01*
X1280037Y1471677D01*
X1279787Y1472797D01*
X1279287Y1473451D01*
X1278412Y1473731D01*
X1277537Y1473544D01*
X1276912Y1473077D01*
X1276537Y1472424D01*
Y1471771D01*
X1276787Y1471117D01*
X1277412Y1470557D01*
G01X1283037Y1466604D02*
X1283662Y1465857D01*
X1284037Y1465017D01*
Y1464271D01*
X1283662Y1463524D01*
X1283037Y1462964D01*
X1282162Y1462684D01*
X1281287Y1462871D01*
X1280537Y1463337D01*
X1280037Y1464177D01*
X1279787Y1465297D01*
X1279287Y1465951D01*
X1278412Y1466231D01*
X1277537Y1466044D01*
X1276912Y1465577D01*
X1276537Y1464924D01*
Y1464271D01*
X1276787Y1463617D01*
X1277412Y1463057D01*
G01X1281537Y1458357D02*
Y1455931D01*
G01X1284037Y1451417D02*
X1276537D01*
Y1447871D01*
G01X1280162Y1449177D02*
Y1451417D01*
G01X1276537Y1443264D02*
Y1441024D01*
G01Y1442144D02*
X1284037D01*
G01Y1443264D02*
Y1441024D01*
G01X1276537Y1434644D02*
X1284037D01*
G01X1276537Y1436791D02*
Y1432497D01*
G01X1296556Y-50256D02*
Y-33656D01*
X1286956D01*
Y-50256D01*
X1296556D01*
G01X1309899Y49986D02*
Y53086D01*
G01X1308289D02*
Y49986D01*
G01Y51536D02*
X1309899D01*
G01X1305994Y49986D02*
Y53086D01*
X1306454Y52466D01*
G01Y49986D02*
X1305534D01*
G01X1302894Y53086D02*
X1303201Y52983D01*
X1303431Y52724D01*
X1303584Y52414D01*
X1303699Y52001D01*
X1303737Y51536D01*
X1303699Y51071D01*
X1303584Y50658D01*
X1303431Y50348D01*
X1303201Y50089D01*
X1302894Y49986D01*
X1302587Y50089D01*
X1302357Y50348D01*
X1302204Y50658D01*
X1302089Y51071D01*
X1302051Y51536D01*
X1302089Y52001D01*
X1302204Y52414D01*
X1302357Y52724D01*
X1302587Y52983D01*
X1302894Y53086D01*
G01X1300522Y51278D02*
X1300254Y51639D01*
X1300024Y51846D01*
X1299717Y51949D01*
X1299449Y51846D01*
X1299257Y51639D01*
X1299104Y51329D01*
X1299066Y50968D01*
X1299104Y50658D01*
X1299257Y50348D01*
X1299487Y50089D01*
X1299756Y49986D01*
X1300062Y50089D01*
X1300331Y50399D01*
X1300484Y50864D01*
X1300522Y51381D01*
X1300446Y52053D01*
X1300331Y52414D01*
X1300139Y52776D01*
X1299871Y53034D01*
X1299602Y53086D01*
X1299334Y52983D01*
X1299142Y52724D01*
G01X1295502Y540608D02*
Y461868D01*
G01X1302045Y831097D02*
X1307495D01*
G01X1302045Y833397D02*
Y831097D01*
G01X1298774Y848970D02*
Y844370D01*
G01D02*
X1308974D01*
G01X1307495Y833397D02*
X1302045D01*
G01X1302033Y834835D02*
X1307483D01*
G01X1302033Y837135D02*
Y834835D01*
G01X1307483Y837135D02*
X1302033D01*
G01X1308974Y848970D02*
X1298774D01*
G01X1296984Y866288D02*
Y861688D01*
G01D02*
X1307184D01*
G01X1290632Y862260D02*
Y868460D01*
G01X1287432Y862260D02*
X1290632D01*
G01X1287432Y868460D02*
Y862260D01*
G01X1301620Y853674D02*
X1307070D01*
G01X1301620Y855974D02*
Y853674D01*
G01X1307070Y855974D02*
X1301620D01*
G01X1301626Y850043D02*
X1307076D01*
G01X1301626Y852343D02*
Y850043D01*
G01X1307076Y852343D02*
X1301626D01*
G01X1301733Y857938D02*
X1307183D01*
G01X1301733Y860238D02*
Y857938D01*
G01X1307183Y860238D02*
X1301733D01*
G01X1307184Y866288D02*
X1296984D01*
G01X1301100Y878200D02*
Y881400D01*
G01X1294900Y878200D02*
X1301100D01*
G01X1294900Y881400D02*
Y878200D01*
G01Y873400D02*
Y870200D01*
G01X1301100Y873400D02*
X1294900D01*
G01X1301100Y870200D02*
Y873400D01*
G01X1294900Y870200D02*
X1301100D01*
G01X1294900Y877400D02*
Y874200D01*
G01X1301100Y877400D02*
X1294900D01*
G01X1301100Y874200D02*
Y877400D01*
G01X1294900Y874200D02*
X1301100D01*
G01X1290632Y868460D02*
X1287432D01*
G01X1286364Y880202D02*
X1292564D01*
Y883402D01*
X1286364D01*
Y880202D01*
G01X1295605Y895116D02*
Y899716D01*
G01X1301100Y881400D02*
X1294900D01*
G01X1286364Y884051D02*
X1292564D01*
G01X1286364Y887251D02*
Y884051D01*
G01X1292564Y887251D02*
X1286364D01*
G01X1292564Y884051D02*
Y887251D01*
G01X1301100Y886200D02*
Y889400D01*
G01X1294900Y886200D02*
X1301100D01*
G01X1294900Y889400D02*
Y886200D01*
G01X1301100Y889400D02*
X1294900D01*
G01X1301100Y882200D02*
Y885400D01*
G01X1294900Y882200D02*
X1301100D01*
G01X1294900Y885400D02*
Y882200D01*
G01X1301100Y885400D02*
X1294900D01*
G01Y893400D02*
Y890200D01*
G01X1301100Y893400D02*
X1294900D01*
G01X1301100Y890200D02*
Y893400D01*
G01X1294900Y890200D02*
X1301100D01*
G01X1301554Y909878D02*
Y913078D01*
G01X1295354Y909878D02*
X1301554D01*
G01X1295354Y913078D02*
Y909878D01*
G01X1301554Y913078D02*
X1295354D01*
G01X1307600Y945600D02*
X1301400D01*
Y942400D01*
X1307600D01*
Y945600D01*
G01X1288347Y1425158D02*
Y1689331D01*
G01X1401339Y1425158D02*
X1288347D01*
G01Y1689331D02*
X1401339D01*
G01X1305219Y329571D02*
Y319571D01*
G01X1309819D02*
Y329571D01*
G01X1309719Y319571D02*
X1309819D01*
G01X1305219D02*
X1309819D01*
G01X1310540Y331077D02*
Y319077D01*
G01X1316540D02*
Y331077D01*
G01X1310540Y319077D02*
X1316540D01*
G01X1305219Y329571D02*
X1309819D01*
G01X1316540Y331077D02*
X1310540D01*
G01X1318670Y347626D02*
Y344426D01*
G01X1324870Y347626D02*
X1318670D01*
G01Y344426D02*
X1324870D01*
G01X1316600Y814900D02*
Y821100D01*
G01X1313400Y814900D02*
X1316600D01*
G01X1313400Y821100D02*
Y814900D01*
G01X1317900D02*
X1321100D01*
G01X1317900Y821100D02*
Y814900D01*
G01X1305391Y820067D02*
X1309991D01*
G01X1305391Y830267D02*
Y820067D01*
G01X1309991Y830267D02*
X1305391D01*
G01X1309991Y820067D02*
Y830267D01*
G01X1316600Y821100D02*
X1313400D01*
G01X1321100D02*
X1317900D01*
G01X1307495Y831097D02*
Y833397D01*
G01X1308974Y844370D02*
Y848970D01*
G01X1314161Y839771D02*
X1319611D01*
G01X1314161Y842071D02*
Y839771D01*
G01X1319611Y842071D02*
X1314161D01*
G01X1307483Y834835D02*
Y837135D01*
G01X1307184Y861688D02*
Y866288D01*
G01X1317391Y861978D02*
X1322841D01*
G01X1317391Y864278D02*
Y861978D01*
G01X1313410Y868482D02*
Y863032D01*
G01X1315710D02*
Y868482D01*
G01X1313410Y863032D02*
X1315710D01*
G01X1307070Y853674D02*
Y855974D01*
G01X1307076Y850043D02*
Y852343D01*
G01X1307183Y857938D02*
Y860238D01*
G01X1322841Y864278D02*
X1317391D01*
G01X1315710Y868482D02*
X1313410D01*
G01X1314180Y883838D02*
X1319630D01*
G01X1314180Y886138D02*
Y883838D01*
G01X1319630Y886138D02*
X1314180D01*
G01X1305237Y897730D02*
Y892280D01*
G01X1307537D02*
Y897730D01*
G01X1305237Y892280D02*
X1307537D01*
G01X1309332Y897730D02*
Y892280D01*
G01X1311632D02*
Y897730D01*
G01X1309332Y892280D02*
X1311632D01*
G01X1307537Y897730D02*
X1305237D01*
G01X1311632D02*
X1309332D01*
G01X1309864Y1096068D02*
Y1090068D01*
X1321864D01*
Y1096068D01*
X1309864D01*
G01X1309858Y1088881D02*
Y1082881D01*
X1321858D01*
Y1088881D01*
X1309858D01*
G01X1316405Y1115247D02*
X1322405D01*
G01X1316405Y1127247D02*
Y1115247D01*
G01X1322405Y1127247D02*
X1316405D01*
G01X1314709Y1220114D02*
Y1209914D01*
X1319309D01*
Y1220114D01*
X1314709D01*
G01X1309399Y1253696D02*
Y1243496D01*
X1313999D01*
Y1253696D01*
X1309399D01*
G01X1309043Y1249202D02*
Y1266904D01*
G01X1320895Y1249202D02*
X1309043D01*
G01Y1266904D02*
X1320895D01*
G01X1321599Y1269165D02*
Y1275365D01*
X1318399D01*
Y1269165D01*
X1321599D01*
G01X1316204D02*
Y1275365D01*
X1313004D01*
Y1269165D01*
X1316204D01*
G01X1322372Y1277952D02*
Y1288152D01*
X1317772D01*
Y1277952D01*
X1322372D01*
G01X1316918Y1278007D02*
Y1288207D01*
X1312318D01*
Y1278007D01*
X1316918D01*
G01X1340093Y-94400D02*
Y-91300D01*
X1339327D01*
X1339020Y-91455D01*
X1338790Y-91662D01*
X1338598Y-91972D01*
X1338445Y-92333D01*
X1338407Y-92850D01*
X1338445Y-93367D01*
X1338598Y-93728D01*
X1338790Y-94038D01*
X1339020Y-94245D01*
X1339327Y-94400D01*
X1340093D01*
G01X1335383D02*
X1336917D01*
Y-91300D01*
X1335383D01*
G01X1335997Y-92798D02*
X1336917D01*
G01X1333050Y-91300D02*
X1333357Y-91403D01*
X1333587Y-91662D01*
X1333740Y-91972D01*
X1333855Y-92385D01*
X1333893Y-92850D01*
X1333855Y-93315D01*
X1333740Y-93728D01*
X1333587Y-94038D01*
X1333357Y-94297D01*
X1333050Y-94400D01*
X1332743Y-94297D01*
X1332513Y-94038D01*
X1332360Y-93728D01*
X1332245Y-93315D01*
X1332207Y-92850D01*
X1332245Y-92385D01*
X1332360Y-91972D01*
X1332513Y-91662D01*
X1332743Y-91403D01*
X1333050Y-91300D01*
G01X1330678Y-93108D02*
X1330410Y-92747D01*
X1330180Y-92540D01*
X1329873Y-92437D01*
X1329605Y-92540D01*
X1329413Y-92747D01*
X1329260Y-93057D01*
X1329222Y-93418D01*
X1329260Y-93728D01*
X1329413Y-94038D01*
X1329643Y-94297D01*
X1329912Y-94400D01*
X1330218Y-94297D01*
X1330487Y-93987D01*
X1330640Y-93522D01*
X1330678Y-93005D01*
X1330602Y-92333D01*
X1330487Y-91972D01*
X1330295Y-91610D01*
X1330027Y-91352D01*
X1329758Y-91300D01*
X1329490Y-91403D01*
X1329298Y-91662D01*
G01X1327578Y-94400D02*
Y-91300D01*
X1326122D01*
G01X1326658Y-92798D02*
X1327578D01*
G01X1324900Y-95433D02*
X1322600D01*
G01X1320650Y-94400D02*
Y-91300D01*
X1321110Y-91920D01*
G01Y-94400D02*
X1320190D01*
G01X1336556Y-89306D02*
Y-72706D01*
X1326956D01*
Y-89306D01*
X1336556D01*
G01X1319055Y339215D02*
Y336015D01*
G01X1325255Y339215D02*
X1319055D01*
G01X1325255Y336015D02*
Y339215D01*
G01X1319055Y336015D02*
X1325255D01*
G01X1325001Y329632D02*
X1328201D01*
G01X1325001Y335832D02*
Y329632D01*
G01X1328201Y335832D02*
X1325001D01*
G01X1328201Y329632D02*
Y335832D01*
G01X1332125Y329581D02*
X1335325D01*
G01X1332125Y335781D02*
Y329581D01*
G01X1335325Y335781D02*
X1332125D01*
G01X1324870Y344426D02*
Y347626D01*
G01X1329178Y354388D02*
Y351188D01*
G01X1335378Y354388D02*
X1329178D01*
G01Y351188D02*
X1335378D01*
G01X1328089Y355176D02*
X1324889D01*
G01X1328089Y348976D02*
Y355176D01*
G01X1324889Y348976D02*
X1328089D01*
G01X1324889Y355176D02*
Y348976D01*
G01X1325600Y814900D02*
Y821100D01*
G01X1322400Y814900D02*
X1325600D01*
G01X1322400Y821100D02*
Y814900D01*
G01X1330100D02*
Y821100D01*
G01X1326900Y814900D02*
X1330100D01*
G01X1326900Y821100D02*
Y814900D01*
G01X1334600D02*
Y821100D01*
G01X1331400Y814900D02*
X1334600D01*
G01X1331400Y821100D02*
Y814900D01*
G01X1321100D02*
Y821100D01*
G01X1325600D02*
X1322400D01*
G01X1330100D02*
X1326900D01*
G01X1334600D02*
X1331400D01*
G01X1332228Y833444D02*
Y838894D01*
G01X1329928Y833444D02*
X1332228D01*
G01X1329928Y838894D02*
Y833444D01*
G01X1332228Y838894D02*
X1329928D01*
G01X1319611Y839771D02*
Y842071D01*
G01X1333078Y849192D02*
X1335378D01*
G01X1333078Y854642D02*
Y849192D01*
G01X1335378Y854642D02*
X1333078D01*
G01X1322841Y861978D02*
Y864278D01*
G01X1333078Y879840D02*
Y874390D01*
G01X1335378Y879840D02*
X1333078D01*
G01Y874390D02*
X1335378D01*
G01X1333078Y895588D02*
Y890138D01*
G01X1335378Y895588D02*
X1333078D01*
G01Y890138D02*
X1335378D01*
G01X1319630Y883838D02*
Y886138D01*
G01X1322269Y1112397D02*
Y1100397D01*
G01X1328269D02*
Y1112397D01*
G01X1322269Y1100397D02*
X1328269D01*
G01Y1112397D02*
X1322269D01*
G01X1330405Y1115247D02*
Y1127247D01*
G01X1324405Y1115247D02*
X1330405D01*
G01X1324405Y1127247D02*
Y1115247D01*
G01X1322405D02*
Y1127247D01*
G01X1330930Y1109598D02*
X1337130D01*
Y1112798D01*
X1330930D01*
Y1109598D01*
G01X1330405Y1127247D02*
X1324405D01*
G01X1333738Y1137574D02*
Y1135148D01*
G01X1324770Y1138272D02*
X1341700D01*
G01X1324770Y1174012D02*
Y1138272D01*
G01X1332783Y1178837D02*
Y1176597D01*
G01X1331158Y1177810D02*
X1334408D01*
G01X1324768Y1174012D02*
X1341708Y1174015D01*
G01X1324768Y1174612D02*
X1341743Y1174616D01*
G01X1324768Y1175212D02*
X1341751Y1175206D01*
G01X1324768Y1175212D02*
Y1174012D01*
G01X1341700D02*
X1324770D01*
G01X1330643Y1189471D02*
Y1201471D01*
G01X1324643Y1189471D02*
X1330643D01*
G01X1324643Y1201471D02*
Y1189471D01*
G01X1330643Y1201471D02*
X1324643D01*
G01X1327050Y1220114D02*
Y1209914D01*
X1331650D01*
Y1220114D01*
X1327050D01*
G01X1321615D02*
Y1209914D01*
X1326215D01*
Y1220114D01*
X1321615D01*
G01X1324243Y1247418D02*
X1333143D01*
G01X1324243Y1267704D02*
Y1247418D01*
G01X1333143D02*
Y1267704D01*
G01X1337536Y1269165D02*
Y1275365D01*
X1334336D01*
Y1269165D01*
X1337536D01*
G01X1327078D02*
Y1275365D01*
X1323878D01*
Y1269165D01*
X1327078D01*
G01X1332182D02*
Y1275365D01*
X1328982D01*
Y1269165D01*
X1332182D01*
G01X1333143Y1267704D02*
X1324243D01*
G01X1338173Y1282087D02*
Y1292287D01*
X1333573D01*
Y1282087D01*
X1338173D01*
G01X1327744D02*
Y1292287D01*
X1323144D01*
Y1282087D01*
X1327744D01*
G01X1332894D02*
Y1292287D01*
X1328294D01*
Y1282087D01*
X1332894D01*
G01X1343019Y335399D02*
Y338599D01*
G01X1336819Y335399D02*
X1343019D01*
G01X1336819Y338599D02*
Y335399D01*
G01X1343019Y338599D02*
X1336819D01*
G01X1335325Y329581D02*
Y335781D01*
G01X1343349Y344366D02*
Y347566D01*
G01X1337149Y344366D02*
X1343349D01*
G01X1337149Y347566D02*
Y344366D01*
G01X1343349Y347566D02*
X1337149D01*
G01X1342237Y351167D02*
Y354367D01*
G01X1336037Y351167D02*
X1342237D01*
G01X1336037Y354367D02*
Y351167D01*
G01X1342237Y354367D02*
X1336037D01*
G01X1335378Y351188D02*
Y354388D01*
G01X1343600Y814900D02*
Y821100D01*
G01X1340400Y814900D02*
X1343600D01*
G01X1340400Y821100D02*
Y814900D01*
G01X1348100D02*
Y821100D01*
G01X1344900Y814900D02*
X1348100D01*
G01X1344900Y821100D02*
Y814900D01*
G01X1349400D02*
X1352600D01*
G01X1349400Y821100D02*
Y814900D01*
G01X1339100D02*
Y821100D01*
G01X1335900Y814900D02*
X1339100D01*
G01X1335900Y821100D02*
Y814900D01*
G01X1343600Y821100D02*
X1340400D01*
G01X1348100D02*
X1344900D01*
G01X1352600D02*
X1349400D01*
G01X1339100D02*
X1335900D01*
G01X1351126Y842044D02*
X1345676D01*
G01X1351126Y839744D02*
Y842044D01*
G01X1345676Y839744D02*
X1351126D01*
G01X1345676Y842044D02*
Y839744D01*
G01X1345677Y857792D02*
Y852342D01*
G01X1347977Y857792D02*
X1345677D01*
G01X1347977Y852342D02*
Y857792D01*
G01X1345677Y852342D02*
X1347977D01*
G01X1348827Y857792D02*
Y852342D01*
G01X1351127Y857792D02*
X1348827D01*
G01X1351127Y852342D02*
Y857792D01*
G01X1348827Y852342D02*
X1351127D01*
G01X1342528Y857792D02*
Y852342D01*
G01X1344828Y857792D02*
X1342528D01*
G01X1344828Y852342D02*
Y857792D01*
G01X1342528Y852342D02*
X1344828D01*
G01X1339378Y857792D02*
Y852342D01*
G01X1341678Y857792D02*
X1339378D01*
G01X1341678Y852342D02*
Y857792D01*
G01X1339378Y852342D02*
X1341678D01*
G01X1348827Y864092D02*
Y858642D01*
G01X1351127D02*
Y864092D01*
G01X1348827Y858642D02*
X1351127D01*
G01X1339378Y864092D02*
Y858642D01*
G01X1341678D02*
Y864092D01*
G01X1339378Y858642D02*
X1341678D01*
G01X1345676Y864092D02*
Y858642D01*
G01X1347976D02*
Y864092D01*
G01X1345676Y858642D02*
X1347976D01*
G01X1342527Y864092D02*
Y858642D01*
G01X1344827D02*
Y864092D01*
G01X1342527Y858642D02*
X1344827D01*
G01X1338528D02*
Y864092D01*
G01X1336228Y858642D02*
X1338528D01*
G01X1336228Y864092D02*
Y858642D01*
G01X1338528Y852342D02*
Y857792D01*
G01X1336228Y852342D02*
X1338528D01*
G01X1336228Y857792D02*
Y852342D01*
G01X1338528Y857792D02*
X1336228D01*
G01X1335378Y849192D02*
Y854642D01*
G01X1351124Y864940D02*
Y870390D01*
G01X1348824Y864940D02*
X1351124D01*
G01X1348824Y870390D02*
Y864940D01*
G01X1351124Y870390D02*
X1348824D01*
G01X1347975Y864940D02*
Y870390D01*
G01X1345675Y864940D02*
X1347975D01*
G01X1345675Y870390D02*
Y864940D01*
G01X1347975Y870390D02*
X1345675D01*
G01X1341677Y864940D02*
Y870390D01*
G01X1339377Y864940D02*
X1341677D01*
G01X1339377Y870390D02*
Y864940D01*
G01X1341677Y870390D02*
X1339377D01*
G01X1344826Y864940D02*
Y870390D01*
G01X1342526Y864940D02*
X1344826D01*
G01X1342526Y870390D02*
Y864940D01*
G01X1344826Y870390D02*
X1342526D01*
G01X1351127Y864092D02*
X1348827D01*
G01X1341678D02*
X1339378D01*
G01X1347976D02*
X1345676D01*
G01X1344827D02*
X1342527D01*
G01X1341677Y871240D02*
Y876690D01*
G01X1339377Y871240D02*
X1341677D01*
G01X1339377Y876690D02*
Y871240D01*
G01X1341677Y876690D02*
X1339377D01*
G01X1344826Y871240D02*
Y876690D01*
G01X1342526Y871240D02*
X1344826D01*
G01X1342526Y876690D02*
Y871240D01*
G01X1344826Y876690D02*
X1342526D01*
G01X1347975Y871240D02*
Y876690D01*
G01X1345675Y871240D02*
X1347975D01*
G01X1345675Y876690D02*
Y871240D01*
G01X1347975Y876690D02*
X1345675D01*
G01X1351124Y871240D02*
Y876690D01*
G01X1348824Y871240D02*
X1351124D01*
G01X1348824Y876690D02*
Y871240D01*
G01X1351124Y876690D02*
X1348824D01*
G01X1338528Y864092D02*
X1336228D01*
G01X1336227Y870391D02*
Y864941D01*
G01X1338527Y870391D02*
X1336227D01*
G01X1338527Y864941D02*
Y870391D01*
G01X1336227Y864941D02*
X1338527D01*
G01X1336227Y877539D02*
X1341677D01*
G01X1336227Y879839D02*
Y877539D01*
G01X1341677Y879839D02*
X1336227D01*
G01X1341677Y877539D02*
Y879839D01*
G01X1335378Y874390D02*
Y879840D01*
G01X1336227Y876690D02*
Y871240D01*
G01X1338527Y876690D02*
X1336227D01*
G01X1338527Y871240D02*
Y876690D01*
G01X1336227Y871240D02*
X1338527D01*
G01X1345676Y890138D02*
X1351126D01*
G01X1345676Y892438D02*
Y890138D01*
G01X1351126Y892438D02*
X1345676D01*
G01X1351126Y890138D02*
Y892438D01*
G01X1335378Y890138D02*
Y895588D01*
G01X1344100Y922600D02*
X1340900D01*
G01X1344100Y916400D02*
Y922600D01*
G01X1340900Y916400D02*
X1344100D01*
G01X1340900Y922600D02*
Y916400D01*
G01X1348100Y922600D02*
X1344900D01*
G01X1348100Y916400D02*
Y922600D01*
G01X1344900Y916400D02*
X1348100D01*
G01X1344900Y922600D02*
Y916400D01*
G01X1352100Y922600D02*
X1348900D01*
G01Y916400D02*
X1352100D01*
G01X1348900Y922600D02*
Y916400D01*
G01X1336900D02*
X1340100D01*
G01X1336900Y922600D02*
Y916400D01*
G01X1340100Y922600D02*
X1336900D01*
G01X1340100Y916400D02*
Y922600D01*
G01X1343359Y1113496D02*
Y1107296D01*
X1346559D01*
Y1113496D01*
X1343359D01*
G01X1348533Y1115247D02*
X1354533D01*
G01X1348533Y1127247D02*
Y1115247D01*
G01X1344559Y1120496D02*
X1341359D01*
G01X1344559Y1114296D02*
Y1120496D01*
G01X1341359Y1114296D02*
X1344559D01*
G01X1341359Y1120496D02*
Y1114296D01*
G01X1338085Y1113994D02*
Y1107794D01*
X1341285D01*
Y1113994D01*
X1338085D01*
G01X1347683Y1121151D02*
Y1127351D01*
X1344483D01*
Y1121151D01*
X1347683D01*
G01X1343818Y1121188D02*
Y1127388D01*
X1340618D01*
Y1121188D01*
X1343818D01*
G01X1354533Y1127247D02*
X1348533D01*
G01X1341700Y1138272D02*
Y1174012D01*
G01X1344149Y1161539D02*
Y1149539D01*
G01X1350149D02*
Y1161539D01*
G01X1344149Y1149539D02*
X1350149D01*
G01Y1161539D02*
X1344149D01*
G01X1341701Y1175162D02*
X1341697Y1173653D01*
G01X1344108Y1189471D02*
Y1201471D01*
G01X1338108Y1189471D02*
X1344108D01*
G01X1338108Y1201471D02*
Y1189471D01*
G01X1344108Y1201471D02*
X1338108D01*
G01X1354463Y1220114D02*
X1349863D01*
G01Y1209914D02*
X1354463D01*
G01X1349863Y1220114D02*
Y1209914D01*
G01X1342032Y1220114D02*
Y1209914D01*
X1346632D01*
Y1220114D01*
X1342032D01*
G01X1367345Y1215076D02*
X1349643D01*
G01D02*
Y1225738D01*
G01X1348351Y1239176D02*
Y1230276D01*
G01D02*
X1368637D01*
G01X1349643Y1241254D02*
Y1254376D01*
G01X1348343Y1249202D02*
X1337397D01*
G01X1348343Y1266904D02*
Y1249202D01*
G01X1368637Y1239176D02*
X1348351D01*
G01X1349643Y1254376D02*
X1367345D01*
G01X1337397Y1266904D02*
X1348343D01*
G01X1347962Y1269165D02*
Y1275365D01*
X1344762D01*
Y1269165D01*
X1347962D01*
G01X1353273D02*
Y1275365D01*
X1350073D01*
Y1269165D01*
X1353273D01*
G01X1342826D02*
Y1275365D01*
X1339626D01*
Y1269165D01*
X1342826D01*
G01X1343437Y1282087D02*
Y1292287D01*
X1338837D01*
Y1282087D01*
X1343437D01*
G01X1348671D02*
Y1292287D01*
X1344071D01*
Y1282087D01*
X1348671D01*
G01X1353968D02*
Y1292287D01*
X1349368D01*
Y1282087D01*
X1353968D01*
G01X1362900Y814900D02*
X1366100D01*
G01X1362900Y821100D02*
Y814900D01*
G01X1366100D02*
Y821100D01*
G01X1367400Y814900D02*
X1370600D01*
G01X1367400Y821100D02*
Y814900D01*
G01X1358400D02*
X1361600D01*
G01X1358400Y821100D02*
Y814900D01*
G01X1361600D02*
Y821100D01*
G01X1353900Y814900D02*
X1357100D01*
G01X1353900Y821100D02*
Y814900D01*
G01X1357100D02*
Y821100D01*
G01X1352600Y814900D02*
Y821100D01*
G01X1366100D02*
X1362900D01*
G01X1370600D02*
X1367400D01*
G01X1361600D02*
X1358400D01*
G01X1357100D02*
X1353900D01*
G01X1363724Y836594D02*
Y842044D01*
G01X1361424Y836594D02*
X1363724D01*
G01X1361424Y842044D02*
Y836594D01*
G01X1363724Y842044D02*
X1361424D01*
G01X1355125Y864092D02*
Y858642D01*
G01X1357425D02*
Y864092D01*
G01X1355125Y858642D02*
X1357425D01*
G01X1358275Y864092D02*
Y858642D01*
G01X1360575D02*
Y864092D01*
G01X1358275Y858642D02*
X1360575D01*
G01X1355125Y857792D02*
Y852342D01*
G01X1357425Y857792D02*
X1355125D01*
G01X1357425Y852342D02*
Y857792D01*
G01X1355125Y852342D02*
X1357425D01*
G01X1363724D02*
Y857792D01*
G01X1361424Y852342D02*
X1363724D01*
G01X1361424Y857792D02*
Y852342D01*
G01X1363724Y857792D02*
X1361424D01*
G01X1358275D02*
Y852342D01*
G01X1360575Y857792D02*
X1358275D01*
G01X1360575Y852342D02*
Y857792D01*
G01X1358275Y852342D02*
X1360575D01*
G01X1351976Y857792D02*
Y852342D01*
G01X1354276Y857792D02*
X1351976D01*
G01X1354276Y852342D02*
Y857792D01*
G01X1351976Y852342D02*
X1354276D01*
G01X1351976Y864092D02*
Y858642D01*
G01X1354276D02*
Y864092D01*
G01X1351976Y858642D02*
X1354276D01*
G01X1357425Y864092D02*
X1355125D01*
G01X1360575D02*
X1358275D01*
G01X1357423Y864940D02*
Y870390D01*
G01X1355123Y864940D02*
X1357423D01*
G01X1355123Y870390D02*
Y864940D01*
G01X1357423Y870390D02*
X1355123D01*
G01X1360573Y864940D02*
Y870390D01*
G01X1358273Y864940D02*
X1360573D01*
G01X1358273Y870390D02*
Y864940D01*
G01X1360573Y870390D02*
X1358273D01*
G01X1360575Y879839D02*
X1355125D01*
G01X1360575Y877539D02*
Y879839D01*
G01X1355125Y877539D02*
X1360575D01*
G01X1355125Y879839D02*
Y877539D01*
G01X1361422Y876689D02*
Y871239D01*
G01X1363722Y876689D02*
X1361422D01*
G01X1363722Y871239D02*
Y876689D01*
G01X1361422Y871239D02*
X1363722D01*
G01X1360573D02*
Y876689D01*
G01X1358273Y871239D02*
X1360573D01*
G01X1358273Y876689D02*
Y871239D01*
G01X1360573Y876689D02*
X1358273D01*
G01X1357423Y871240D02*
Y876690D01*
G01X1355123Y871240D02*
X1357423D01*
G01X1355123Y876690D02*
Y871240D01*
G01X1357423Y876690D02*
X1355123D01*
G01X1354273Y864940D02*
Y870390D01*
G01X1351973Y864940D02*
X1354273D01*
G01X1351973Y870390D02*
Y864940D01*
G01X1354273Y870390D02*
X1351973D01*
G01X1354276Y864092D02*
X1351976D01*
G01X1354273Y871240D02*
Y876690D01*
G01X1351973Y871240D02*
X1354273D01*
G01X1351973Y876690D02*
Y871240D01*
G01X1354273Y876690D02*
X1351973D01*
G01X1364574Y895588D02*
Y890138D01*
G01X1366874Y895588D02*
X1364574D01*
G01X1366874Y890138D02*
Y895588D01*
G01X1364574Y890138D02*
X1366874D01*
G01X1360100Y922600D02*
X1356900D01*
G01X1360100Y916400D02*
Y922600D01*
G01X1356900Y916400D02*
X1360100D01*
G01X1356900Y922600D02*
Y916400D01*
G01X1356100Y922600D02*
X1352900D01*
G01X1356100Y916400D02*
Y922600D01*
G01X1352900Y916400D02*
X1356100D01*
G01X1352900Y922600D02*
Y916400D01*
G01X1364100Y922600D02*
X1360900D01*
G01X1364100Y916400D02*
Y922600D01*
G01X1360900Y916400D02*
X1364100D01*
G01X1360900Y922600D02*
Y916400D01*
G01X1368100Y922600D02*
X1364900D01*
G01Y916400D02*
X1368100D01*
G01X1364900Y922600D02*
Y916400D01*
G01X1352100D02*
Y922600D01*
G01X1367165Y1005666D02*
X1370365D01*
G01X1367165Y1011866D02*
Y1005666D01*
G01X1366365D02*
Y1011866D01*
X1363165D01*
Y1005666D01*
X1366365D01*
G01X1363165Y1012666D02*
X1366365D01*
G01X1363165Y1018866D02*
Y1012666D01*
G01X1366365Y1018866D02*
X1363165D01*
G01X1366365Y1012666D02*
Y1018866D01*
G01X1362865D02*
X1359665D01*
G01X1362865Y1012666D02*
Y1018866D01*
G01X1359665Y1012666D02*
X1362865D01*
G01X1359665Y1018866D02*
Y1012666D01*
G01X1359365Y1018866D02*
X1356165D01*
G01X1359365Y1012666D02*
Y1018866D01*
G01X1356165Y1012666D02*
X1359365D01*
G01X1356165Y1018866D02*
Y1012666D01*
G01X1370365Y1011866D02*
X1367165D01*
G01X1363418Y1090088D02*
Y1096088D01*
X1351418D01*
Y1090088D01*
X1363418D01*
G01X1354397Y1112397D02*
Y1100397D01*
G01X1360397D02*
Y1112397D01*
G01X1354397Y1100397D02*
X1360397D01*
G01Y1112397D02*
X1354397D01*
G01X1362533Y1115247D02*
Y1127247D01*
G01X1356533Y1115247D02*
X1362533D01*
G01X1356533Y1127247D02*
Y1115247D01*
G01X1354533D02*
Y1127247D01*
G01X1363141Y1109598D02*
X1369341D01*
Y1112798D01*
X1363141D01*
Y1109598D01*
G01X1362533Y1127247D02*
X1356533D01*
G01X1361566Y1137574D02*
Y1135148D01*
G01X1352598Y1138272D02*
X1369528D01*
G01X1352598Y1174012D02*
Y1138272D01*
G01X1360611Y1178837D02*
Y1176597D01*
G01X1358986Y1177810D02*
X1362236D01*
G01X1352596Y1174012D02*
X1369536Y1174015D01*
G01X1352596Y1174612D02*
X1369571Y1174616D01*
G01X1352596Y1175212D02*
X1369579Y1175206D01*
G01X1352596Y1175212D02*
Y1174012D01*
G01X1369528D02*
X1352598D01*
G01X1354463Y1209914D02*
Y1220114D01*
G01X1366923D02*
X1362323D01*
G01X1366923Y1209914D02*
Y1220114D01*
G01X1362323Y1209914D02*
X1366923D01*
G01X1362323Y1220114D02*
Y1209914D01*
G01X1355330Y1220114D02*
Y1209914D01*
X1359930D01*
Y1220114D01*
X1355330D01*
G01X1367345Y1225738D02*
Y1215076D01*
G01Y1254376D02*
Y1241254D01*
G01X1358456Y1269165D02*
Y1275365D01*
X1355256D01*
Y1269165D01*
X1358456D01*
G01X1369428D02*
Y1275365D01*
X1366228D01*
Y1269165D01*
X1369428D01*
G01X1363908D02*
Y1275365D01*
X1360708D01*
Y1269165D01*
X1363908D01*
G01X1359171Y1282087D02*
Y1292287D01*
X1354571D01*
Y1282087D01*
X1359171D01*
G01X1369981D02*
Y1292287D01*
X1365381D01*
Y1282087D01*
X1369981D01*
G01X1364569D02*
Y1292287D01*
X1359969D01*
Y1282087D01*
X1364569D01*
G01X1370300Y1424500D02*
X1364100D01*
Y1421300D01*
X1370300D01*
Y1424500D01*
G01X1381333Y559400D02*
X1387533D01*
G01X1381333Y562600D02*
Y559400D01*
G01X1387533Y562600D02*
X1381333D01*
G01Y570600D02*
Y567400D01*
G01X1387533Y570600D02*
X1381333D01*
G01Y567400D02*
X1387533D01*
G01X1381333Y566600D02*
Y563400D01*
G01X1387533Y566600D02*
X1381333D01*
G01Y563400D02*
X1387533D01*
G01X1381333Y605900D02*
X1387533D01*
G01X1381333Y609100D02*
Y605900D01*
G01X1387533Y609100D02*
X1381333D01*
G01Y617100D02*
Y613900D01*
G01X1387533Y617100D02*
X1381333D01*
G01Y613900D02*
X1387533D01*
G01X1381333Y613100D02*
Y609900D01*
G01X1387533Y613100D02*
X1381333D01*
G01Y609900D02*
X1387533D01*
G01X1375100Y814900D02*
Y821100D01*
G01X1371900Y814900D02*
X1375100D01*
G01X1371900Y821100D02*
Y814900D01*
G01X1381067Y814771D02*
X1384267D01*
G01X1381067Y820971D02*
Y814771D01*
G01X1376400Y814900D02*
X1379600D01*
G01X1376400Y821100D02*
Y814900D01*
G01X1379600D02*
Y821100D01*
G01X1370600Y814900D02*
Y821100D01*
G01X1375100D02*
X1371900D01*
G01X1384267Y820971D02*
X1381067D01*
G01X1379600Y821100D02*
X1376400D01*
G01X1379416Y845171D02*
X1373966D01*
G01X1379416Y842871D02*
Y845171D01*
G01X1373966Y842871D02*
X1379416D01*
G01X1373966Y845171D02*
Y842871D01*
G01X1370873Y870391D02*
Y864941D01*
G01X1373173Y870391D02*
X1370873D01*
G01X1373173Y864941D02*
Y870391D01*
G01X1370873Y864941D02*
X1373173D01*
G01X1382611Y886171D02*
X1377161D01*
G01X1382611Y883871D02*
Y886171D01*
G01X1377161Y883871D02*
X1382611D01*
G01X1377161Y886171D02*
Y883871D01*
G01X1384100Y922600D02*
X1380900D01*
G01Y916400D02*
X1384100D01*
G01X1380900Y922600D02*
Y916400D01*
G01X1372100Y922600D02*
X1368900D01*
G01X1372100Y916400D02*
Y922600D01*
G01X1368900Y916400D02*
X1372100D01*
G01X1368900Y922600D02*
Y916400D01*
G01X1380100Y922600D02*
X1376900D01*
G01X1380100Y916400D02*
Y922600D01*
G01X1376900Y916400D02*
X1380100D01*
G01X1376900Y922600D02*
Y916400D01*
G01X1372900D02*
X1376100D01*
G01X1372900Y922600D02*
Y916400D01*
G01X1376100Y922600D02*
X1372900D01*
G01X1376100Y916400D02*
Y922600D01*
G01X1368100Y916400D02*
Y922600D01*
G01X1371959Y1008925D02*
Y1005725D01*
G01X1378159Y1008925D02*
X1371959D01*
G01X1378159Y1005725D02*
Y1008925D01*
G01X1371959Y1005725D02*
X1378159D01*
G01X1368859Y1003780D02*
Y1000580D01*
G01X1375059Y1003780D02*
X1368859D01*
G01X1375059Y1000580D02*
Y1003780D01*
G01X1368859Y1000580D02*
X1375059D01*
G01X1370365Y1005666D02*
Y1011866D01*
G01X1372951Y1022099D02*
X1376151D01*
G01X1372951Y1028299D02*
Y1022099D01*
G01X1376151D02*
Y1028299D01*
G01X1377165Y1016166D02*
Y1012966D01*
G01X1383365Y1016166D02*
X1377165D01*
G01X1383365Y1012966D02*
Y1016166D01*
G01X1377165Y1012966D02*
X1383365D01*
G01X1372151Y1022099D02*
Y1028299D01*
X1368951D01*
Y1022099D01*
X1372151D01*
G01X1380159Y1022080D02*
Y1028280D01*
X1376959D01*
Y1022080D01*
X1380159D01*
G01X1376151Y1028299D02*
X1372951D01*
G01X1375451Y1096068D02*
Y1090068D01*
X1387451D01*
Y1096068D01*
X1375451D01*
G01X1375487Y1113496D02*
Y1107296D01*
X1378687D01*
Y1113496D01*
X1375487D01*
G01X1381992Y1115247D02*
X1387992D01*
G01X1381992Y1127247D02*
Y1115247D01*
G01X1376687Y1120496D02*
X1373487D01*
G01X1376687Y1114296D02*
Y1120496D01*
G01X1373487Y1114296D02*
X1376687D01*
G01X1373487Y1120496D02*
Y1114296D01*
G01X1370192Y1113995D02*
Y1107795D01*
X1373392D01*
Y1113995D01*
X1370192D01*
G01X1387992Y1127247D02*
X1381992D01*
G01X1369528Y1138272D02*
Y1174012D01*
G01X1369529Y1175162D02*
X1369525Y1173653D01*
G01X1380946Y1199071D02*
Y1195871D01*
G01X1387146Y1199071D02*
X1380946D01*
G01Y1195871D02*
X1387146D01*
G01X1380946Y1191871D02*
X1387146D01*
G01X1380946Y1195071D02*
Y1191871D01*
G01X1387146Y1195071D02*
X1380946D01*
G01X1374472Y1195871D02*
Y1199071D01*
G01X1368272Y1195871D02*
X1374472D01*
G01X1368272Y1199071D02*
Y1195871D01*
G01X1374472Y1199071D02*
X1368272D01*
G01Y1195071D02*
Y1191871D01*
G01X1374472Y1195071D02*
X1368272D01*
G01X1374472Y1191871D02*
Y1195071D01*
G01X1368272Y1191871D02*
X1374472D01*
G01X1387839Y1220114D02*
X1383239D01*
G01Y1209914D02*
X1387839D01*
G01X1383239Y1220114D02*
Y1209914D01*
G01X1382672Y1220114D02*
X1378072D01*
G01X1382672Y1209914D02*
Y1220114D01*
G01X1378072Y1209914D02*
X1382672D01*
G01X1378072Y1220114D02*
Y1209914D01*
G01X1377461Y1220114D02*
X1372861D01*
G01X1377461Y1209914D02*
Y1220114D01*
G01X1372861D02*
Y1209914D01*
G01D02*
X1377461D01*
G01X1372245Y1220114D02*
X1367645D01*
G01X1372245Y1209914D02*
Y1220114D01*
G01X1367645Y1209914D02*
X1372245D01*
G01X1367645Y1220114D02*
Y1209914D01*
G01X1368637Y1230276D02*
Y1239176D01*
G01X1370578Y1260699D02*
Y1256099D01*
G01X1380778Y1260699D02*
X1370578D01*
G01Y1256099D02*
X1380778D01*
G01D02*
Y1260699D01*
G01X1373752Y1269132D02*
Y1275332D01*
X1370552D01*
Y1269132D01*
X1373752D01*
G01X1382536Y1261255D02*
Y1267455D01*
X1379336D01*
Y1261255D01*
X1382536D01*
G01X1375332Y1282043D02*
Y1292243D01*
X1370732D01*
Y1282043D01*
X1375332D01*
G01X1387797Y1274233D02*
Y1284433D01*
X1383197D01*
Y1274233D01*
X1387797D01*
G01X1382611Y1274177D02*
Y1284377D01*
X1378011D01*
Y1274177D01*
X1382611D01*
G01X1405435Y90609D02*
Y93709D01*
G01X1403825D02*
Y90609D01*
G01Y92159D02*
X1405435D01*
G01X1401530Y90609D02*
Y93709D01*
X1401990Y93089D01*
G01Y90609D02*
X1401070D01*
G01X1398430Y93709D02*
X1398737Y93606D01*
X1398967Y93347D01*
X1399120Y93037D01*
X1399235Y92624D01*
X1399273Y92159D01*
X1399235Y91694D01*
X1399120Y91281D01*
X1398967Y90971D01*
X1398737Y90712D01*
X1398430Y90609D01*
X1398123Y90712D01*
X1397893Y90971D01*
X1397740Y91281D01*
X1397625Y91694D01*
X1397587Y92159D01*
X1397625Y92624D01*
X1397740Y93037D01*
X1397893Y93347D01*
X1398123Y93606D01*
X1398430Y93709D01*
G01X1394870Y90609D02*
Y93709D01*
X1396288Y91487D01*
X1394372D01*
G01X1387533Y559400D02*
Y562600D01*
G01Y567400D02*
Y570600D01*
G01Y563400D02*
Y566600D01*
G01Y605900D02*
Y609100D01*
G01Y613900D02*
Y617100D01*
G01Y609900D02*
Y613100D01*
G01X1384267Y814771D02*
Y820971D01*
G01X1398449Y851821D02*
Y856421D01*
G01X1388249Y851821D02*
X1398449D01*
G01X1388249Y856421D02*
Y851821D01*
G01X1398449Y856421D02*
X1388249D01*
G01X1395120Y863979D02*
X1389670D01*
G01X1395120Y861679D02*
Y863979D01*
G01X1389670Y861679D02*
X1395120D01*
G01X1389670Y863979D02*
Y861679D01*
G01X1396924Y878608D02*
Y883208D01*
G01X1386724Y878608D02*
X1396924D01*
G01X1386724Y883208D02*
Y878608D01*
G01X1395097Y867770D02*
X1389647D01*
G01X1395097Y865470D02*
Y867770D01*
G01X1389647Y865470D02*
X1395097D01*
G01X1389647Y867770D02*
Y865470D01*
G01X1394151Y872168D02*
X1388701D01*
G01X1394151Y869868D02*
Y872168D01*
G01X1388701Y869868D02*
X1394151D01*
G01X1388701Y872168D02*
Y869868D01*
G01X1394138Y877354D02*
X1388688D01*
G01X1394138Y875054D02*
Y877354D01*
G01X1388688Y875054D02*
X1394138D01*
G01X1388688Y877354D02*
Y875054D01*
G01X1399080Y893911D02*
Y904111D01*
G01X1394480Y893911D02*
X1399080D01*
G01X1394480Y904111D02*
Y893911D01*
G01X1396924Y883208D02*
X1386724D01*
G01X1399080Y904111D02*
X1394480D01*
G01X1384100Y916400D02*
Y922600D01*
G01X1387895D02*
X1384695D01*
G01X1387895Y916400D02*
Y922600D01*
G01X1384695Y916400D02*
X1387895D01*
G01X1384695Y922600D02*
Y916400D01*
G01X1392917Y982437D02*
X1399117D01*
Y985637D01*
X1392917D01*
Y982437D01*
G01X1391481Y1028727D02*
Y1022527D01*
X1394681D01*
Y1028727D01*
X1391481D01*
G01X1396689Y1028569D02*
Y1022369D01*
X1399889D01*
Y1028569D01*
X1396689D01*
G01X1387856Y1112397D02*
Y1100397D01*
G01X1393856D02*
Y1112397D01*
G01X1387856Y1100397D02*
X1393856D01*
G01Y1112397D02*
X1387856D01*
G01X1395992Y1115247D02*
Y1127247D01*
G01X1389992Y1115247D02*
X1395992D01*
G01X1389992Y1127247D02*
Y1115247D01*
G01X1387992D02*
Y1127247D01*
G01X1396588Y1109658D02*
X1402788D01*
Y1112858D01*
X1396588D01*
Y1109658D01*
G01X1395992Y1127247D02*
X1389992D01*
G01X1399325Y1137574D02*
Y1135148D01*
G01X1390357Y1138272D02*
X1407287D01*
G01X1390357Y1174012D02*
Y1138272D01*
G01X1398370Y1178837D02*
Y1176597D01*
G01X1396745Y1177810D02*
X1399995D01*
G01X1390355Y1174012D02*
X1407295Y1174015D01*
G01X1390355Y1174612D02*
X1407330Y1174616D01*
G01X1390355Y1175212D02*
X1407338Y1175206D01*
G01X1390355Y1175212D02*
Y1174012D01*
G01X1407287D02*
X1390357D01*
G01X1397845Y1189471D02*
X1403845D01*
G01X1397845Y1201471D02*
Y1189471D01*
G01X1403845Y1201471D02*
X1397845D01*
G01X1387146Y1195871D02*
Y1199071D01*
G01Y1191871D02*
Y1195071D01*
G01X1399396Y1220114D02*
X1394796D01*
G01X1399396Y1209914D02*
Y1220114D01*
G01X1394796D02*
Y1209914D01*
G01D02*
X1399396D01*
G01X1392955Y1220114D02*
X1388355D01*
G01X1392955Y1209914D02*
Y1220114D01*
G01X1388355D02*
Y1209914D01*
G01D02*
X1392955D01*
G01X1387839D02*
Y1220114D01*
G01X1388352Y1215076D02*
Y1226905D01*
G01X1406054Y1215076D02*
X1388352D01*
G01X1387060Y1230276D02*
X1407346D01*
G01X1387060Y1239176D02*
Y1230276D01*
G01X1388352Y1242420D02*
Y1254376D01*
G01X1407346Y1239176D02*
X1387060D01*
G01X1388352Y1254376D02*
X1406054D01*
G01X1387722Y1261311D02*
Y1267511D01*
X1384522D01*
Y1261311D01*
X1387722D01*
G01X1403028Y1261275D02*
Y1267475D01*
X1399828D01*
Y1261275D01*
X1403028D01*
G01X1392872Y1261277D02*
Y1267477D01*
X1389672D01*
Y1261277D01*
X1392872D01*
G01X1397896Y1261275D02*
Y1267475D01*
X1394696D01*
Y1261275D01*
X1397896D01*
G01X1403103Y1275649D02*
Y1285849D01*
X1398503D01*
Y1275649D01*
X1403103D01*
G01X1392947Y1274199D02*
Y1284399D01*
X1388347D01*
Y1274199D01*
X1392947D01*
G01X1397971Y1274197D02*
Y1284397D01*
X1393371D01*
Y1274197D01*
X1397971D01*
G01X1406739Y959581D02*
Y962781D01*
G01X1400539Y959581D02*
X1406739D01*
G01X1400539Y962781D02*
Y959581D01*
G01X1406739Y962781D02*
X1400539D01*
G01X1407215Y991261D02*
X1413415D01*
Y994461D01*
X1407215D01*
Y991261D01*
G01X1412106Y1025854D02*
X1405906D01*
Y1022654D01*
X1412106D01*
Y1025854D01*
G01Y1029867D02*
X1405906D01*
Y1026667D01*
X1412106D01*
Y1029867D01*
G01X1408946Y1113496D02*
Y1107296D01*
X1412146D01*
Y1113496D01*
X1408946D01*
G01X1414120Y1115247D02*
X1420120D01*
G01X1414120Y1127247D02*
Y1115247D01*
G01X1410146Y1120496D02*
X1406946D01*
G01X1410146Y1114296D02*
Y1120496D01*
G01X1406946Y1114296D02*
X1410146D01*
G01X1406946Y1120496D02*
Y1114296D01*
G01X1403589Y1113993D02*
Y1107793D01*
X1406789D01*
Y1113993D01*
X1403589D01*
G01X1409554Y1121362D02*
Y1127562D01*
X1406354D01*
Y1121362D01*
X1409554D01*
G01X1413429Y1121339D02*
Y1127539D01*
X1410229D01*
Y1121339D01*
X1413429D01*
G01X1420120Y1127247D02*
X1414120D01*
G01X1407287Y1138272D02*
Y1174012D01*
G01X1409736Y1161539D02*
Y1149539D01*
G01X1415736D02*
Y1161539D01*
G01X1409736Y1149539D02*
X1415736D01*
G01Y1161539D02*
X1409736D01*
G01X1407288Y1175162D02*
X1407284Y1173653D01*
G01X1411310Y1189471D02*
X1417310D01*
G01X1411310Y1201471D02*
Y1189471D01*
G01X1417310Y1201471D02*
X1411310D01*
G01X1403845Y1189471D02*
Y1201471D01*
G01X1409134Y1220114D02*
Y1209914D01*
X1413734D01*
Y1220114D01*
X1409134D01*
G01X1414283D02*
Y1209914D01*
X1418883D01*
Y1220114D01*
X1414283D01*
G01X1400780D02*
Y1209914D01*
X1405380D01*
Y1220114D01*
X1400780D01*
G01X1406054Y1226905D02*
Y1215076D01*
G01X1407346Y1230276D02*
Y1239176D01*
G01X1407354Y1249202D02*
Y1260626D01*
G01X1419280Y1249202D02*
X1407354D01*
G01X1406054Y1254376D02*
Y1242420D01*
G01X1412784Y1264010D02*
Y1270210D01*
X1409584D01*
Y1264010D01*
X1412784D01*
G01X1416781D02*
Y1270210D01*
X1413581D01*
Y1264010D01*
X1416781D01*
G01X1408516D02*
Y1270210D01*
X1405316D01*
Y1264010D01*
X1408516D01*
G01X1414692Y1275762D02*
Y1285962D01*
X1410092D01*
Y1275762D01*
X1414692D01*
G01X1420580Y1271136D02*
Y1281336D01*
X1415980D01*
Y1271136D01*
X1420580D01*
G01X1409532Y1275752D02*
Y1285952D01*
X1404932D01*
Y1275752D01*
X1409532D01*
G01X1406300Y1422100D02*
X1412500D01*
Y1425300D01*
X1406300D01*
Y1422100D01*
G01X1401339Y1689331D02*
Y1425158D01*
G01X1432044Y598125D02*
Y604325D01*
G01X1428844Y598125D02*
X1432044D01*
G01X1428844Y604325D02*
Y598125D01*
G01X1432044Y604325D02*
X1428844D01*
G01X1431817Y875702D02*
X1428617D01*
G01X1431817Y869502D02*
Y875702D01*
G01X1428617Y869502D02*
X1431817D01*
G01X1428617Y875702D02*
Y869502D01*
G01X1426400Y899100D02*
Y895900D01*
G01D02*
X1432600D01*
G01Y899100D02*
X1426400D01*
G01Y903900D02*
X1432600D01*
G01X1426400Y907100D02*
Y903900D01*
G01X1432600Y907100D02*
X1426400D01*
G01Y899900D02*
X1432600D01*
G01X1426400Y903100D02*
Y899900D01*
G01X1432600Y903100D02*
X1426400D01*
G01X1428863Y1082890D02*
Y1088890D01*
X1416863D01*
Y1082890D01*
X1428863D01*
G01X1429005Y1090088D02*
Y1096088D01*
X1417005D01*
Y1090088D01*
X1429005D01*
G01X1419984Y1112397D02*
Y1100397D01*
G01X1425984D02*
Y1112397D01*
G01X1419984Y1100397D02*
X1425984D01*
G01Y1112397D02*
X1419984D01*
G01X1428120Y1115247D02*
Y1127247D01*
G01X1422120Y1115247D02*
X1428120D01*
G01X1422120Y1127247D02*
Y1115247D01*
G01X1420120D02*
Y1127247D01*
G01X1428831Y1109597D02*
X1435031D01*
Y1112797D01*
X1428831D01*
Y1109597D01*
G01X1428120Y1127247D02*
X1422120D01*
G01X1427153Y1137574D02*
Y1135148D01*
G01X1418185Y1138272D02*
X1435115D01*
G01X1418185Y1174012D02*
Y1138272D01*
G01X1426198Y1178837D02*
Y1176597D01*
G01X1424573Y1177810D02*
X1427823D01*
G01X1418183Y1174012D02*
X1435123Y1174015D01*
G01X1418183Y1174612D02*
X1435158Y1174616D01*
G01X1418183Y1175212D02*
X1435166Y1175206D01*
G01X1418183Y1175212D02*
Y1174012D01*
G01X1435115D02*
X1418185D01*
G01X1417310Y1189471D02*
Y1201471D01*
G01X1425010Y1190371D02*
X1429610D01*
G01X1425010Y1200571D02*
Y1190371D01*
G01X1429610Y1200571D02*
X1425010D01*
G01X1429610Y1190371D02*
Y1200571D01*
G01X1422556Y1220114D02*
Y1209914D01*
X1427156D01*
Y1220114D01*
X1422556D01*
G01X1427829D02*
Y1209914D01*
X1432429D01*
Y1220114D01*
X1427829D01*
G01X1422554Y1247910D02*
X1431454D01*
G01X1422554Y1268196D02*
Y1247910D01*
G01X1431454D02*
Y1268196D01*
G01X1421051Y1263954D02*
Y1270154D01*
X1417851D01*
Y1263954D01*
X1421051D01*
G01X1431454Y1268196D02*
X1422554D01*
G01X1432636Y1271136D02*
Y1281336D01*
X1428036D01*
Y1271136D01*
X1432636D01*
G01X1427152D02*
Y1281336D01*
X1422552D01*
Y1271136D01*
X1427152D01*
G01X1458607Y49803D02*
Y52903D01*
G01X1456997D02*
Y49803D01*
G01Y51353D02*
X1458607D01*
G01X1454702Y49803D02*
Y52903D01*
X1455162Y52283D01*
G01Y49803D02*
X1454242D01*
G01X1452330Y52386D02*
X1452100Y52696D01*
X1451832Y52851D01*
X1451525Y52903D01*
X1451142Y52800D01*
X1450874Y52541D01*
X1450797Y52231D01*
X1450835Y51921D01*
X1450989Y51663D01*
X1451755Y51146D01*
X1452100Y50785D01*
X1452330Y50268D01*
X1452407Y49803D01*
X1450797D01*
G01X1449230Y51095D02*
X1448962Y51456D01*
X1448732Y51663D01*
X1448425Y51766D01*
X1448157Y51663D01*
X1447965Y51456D01*
X1447812Y51146D01*
X1447774Y50785D01*
X1447812Y50475D01*
X1447965Y50165D01*
X1448195Y49906D01*
X1448464Y49803D01*
X1448770Y49906D01*
X1449039Y50216D01*
X1449192Y50681D01*
X1449230Y51198D01*
X1449154Y51870D01*
X1449039Y52231D01*
X1448847Y52593D01*
X1448579Y52851D01*
X1448310Y52903D01*
X1448042Y52800D01*
X1447850Y52541D01*
G01X1446633Y599479D02*
Y602679D01*
G01X1440433Y599479D02*
X1446633D01*
G01X1440433Y602679D02*
Y599479D01*
G01X1446633Y602679D02*
X1440433D01*
G01X1444566Y875008D02*
Y878208D01*
G01X1438366Y875008D02*
X1444566D01*
G01X1438366Y878208D02*
Y875008D01*
G01X1444566Y878208D02*
X1438366D01*
G01X1436458Y878542D02*
Y884742D01*
G01X1433258Y878542D02*
X1436458D01*
G01X1433258Y884742D02*
Y878542D01*
G01X1445478Y873259D02*
X1451678D01*
G01X1445478Y876459D02*
Y873259D01*
G01X1451678Y876459D02*
X1445478D01*
G01X1436458Y884742D02*
X1433258D01*
G01X1432600Y895900D02*
Y899100D01*
G01X1439091Y891833D02*
Y886833D01*
G01X1441291Y894033D02*
X1439091Y891833D01*
G01Y896233D02*
X1441291Y894033D01*
G01X1439091Y901233D02*
Y896233D01*
G01Y886833D02*
X1458691Y886883D01*
G01X1432600Y903900D02*
Y907100D01*
G01Y899900D02*
Y903100D01*
G01X1453421Y913586D02*
Y911364D01*
X1453268Y910899D01*
X1452961Y910589D01*
X1452578Y910486D01*
X1452195Y910589D01*
X1451888Y910899D01*
X1451735Y911364D01*
Y913586D01*
G01X1450206Y911778D02*
X1449938Y912139D01*
X1449708Y912346D01*
X1449401Y912449D01*
X1449133Y912346D01*
X1448941Y912139D01*
X1448788Y911829D01*
X1448750Y911468D01*
X1448788Y911158D01*
X1448941Y910848D01*
X1449171Y910589D01*
X1449440Y910486D01*
X1449746Y910589D01*
X1450015Y910899D01*
X1450168Y911364D01*
X1450206Y911881D01*
X1450130Y912553D01*
X1450015Y912914D01*
X1449823Y913276D01*
X1449555Y913534D01*
X1449286Y913586D01*
X1449018Y913483D01*
X1448826Y913224D01*
G01X1446378Y910486D02*
X1446110Y910538D01*
X1445803Y910693D01*
X1445611Y910951D01*
X1445535Y911313D01*
X1445611Y911674D01*
X1445841Y911984D01*
X1446186Y912139D01*
X1446570D01*
X1446800Y912243D01*
X1446991Y912501D01*
X1447068Y912863D01*
X1446953Y913224D01*
X1446685Y913483D01*
X1446378Y913586D01*
X1446071Y913483D01*
X1445803Y913224D01*
X1445688Y912863D01*
X1445765Y912501D01*
X1445956Y912243D01*
X1446186Y912139D01*
X1446570D01*
X1446915Y911984D01*
X1447145Y911674D01*
X1447221Y911313D01*
X1447145Y910951D01*
X1446953Y910693D01*
X1446646Y910538D01*
X1446378Y910486D01*
G01X1458691Y901233D02*
X1439091D01*
G01X1438900Y928600D02*
Y925400D01*
G01X1445100Y928600D02*
X1438900D01*
G01X1445100Y925400D02*
Y928600D01*
G01X1438900Y925400D02*
X1445100D01*
G01Y929900D02*
Y933100D01*
G01X1438900Y929900D02*
X1445100D01*
G01X1438900Y933100D02*
Y929900D01*
G01X1445100Y933100D02*
X1438900D01*
G01X1445100Y934400D02*
Y937600D01*
G01X1438900Y934400D02*
X1445100D01*
G01X1438900Y937600D02*
Y934400D01*
G01X1445100Y937600D02*
X1438900D01*
G01X1441074Y1113496D02*
Y1107296D01*
X1444274D01*
Y1113496D01*
X1441074D01*
G01X1442274Y1120496D02*
X1439074D01*
G01X1442274Y1114296D02*
Y1120496D01*
G01X1439074Y1114296D02*
X1442274D01*
G01X1439074Y1120496D02*
Y1114296D01*
G01X1435752Y1114019D02*
Y1107819D01*
X1438952D01*
Y1114019D01*
X1435752D01*
G01X1435115Y1138272D02*
Y1174012D01*
G01X1435116Y1175162D02*
X1435112Y1173653D01*
G01X1436060Y1220114D02*
Y1209914D01*
X1440660D01*
Y1220114D01*
X1436060D01*
G01X1446654Y1249202D02*
X1435962D01*
G01X1446654Y1266904D02*
Y1249202D01*
G01X1442011Y1264010D02*
Y1270210D01*
X1438811D01*
Y1264010D01*
X1442011D01*
G01X1445981D02*
Y1270210D01*
X1442781D01*
Y1264010D01*
X1445981D01*
G01X1438039Y1264035D02*
Y1270235D01*
X1434839D01*
Y1264035D01*
X1438039D01*
G01X1438551Y1271136D02*
Y1281336D01*
X1433951D01*
Y1271136D01*
X1438551D01*
G01X1444492D02*
Y1281336D01*
X1439892D01*
Y1271136D01*
X1444492D01*
G01X1459645Y462126D02*
Y540866D01*
G01X1538385Y462126D02*
X1459645D01*
G01Y540866D02*
X1459817D01*
G01X1459729D02*
X1538385D01*
G01X1467675Y872914D02*
X1464475D01*
G01Y866714D02*
X1467675D01*
G01X1464475Y872914D02*
Y866714D01*
G01X1451678Y873259D02*
Y876459D01*
G01X1464100Y895900D02*
Y902100D01*
G01X1460900Y895900D02*
X1464100D01*
G01X1460900Y902100D02*
Y895900D01*
G01X1464865D02*
X1468065D01*
G01X1464865Y902100D02*
Y895900D01*
G01X1458691Y886883D02*
Y901233D01*
G01X1464100Y902100D02*
X1460900D01*
G01X1468065D02*
X1464865D01*
G01X1463820Y923906D02*
Y921684D01*
X1463667Y921219D01*
X1463360Y920909D01*
X1462977Y920806D01*
X1462594Y920909D01*
X1462287Y921219D01*
X1462134Y921684D01*
Y923906D01*
G01X1460529Y921168D02*
X1460260Y920909D01*
X1459954Y920806D01*
X1459647Y920909D01*
X1459379Y921219D01*
X1459187Y921684D01*
X1459110Y922149D01*
Y922718D01*
X1459187Y923183D01*
X1459379Y923596D01*
X1459609Y923803D01*
X1459877Y923906D01*
X1460184Y923803D01*
X1460414Y923596D01*
X1460567Y923286D01*
X1460644Y922873D01*
X1460567Y922511D01*
X1460375Y922149D01*
X1460145Y921943D01*
X1459877Y921891D01*
X1459570Y921994D01*
X1459340Y922253D01*
X1459110Y922718D01*
G01X1456854Y920806D02*
X1456777Y921478D01*
X1456662Y922046D01*
X1456509Y922563D01*
X1456317Y923131D01*
X1456010Y923906D01*
X1457544D01*
G01X1452109Y937950D02*
Y925746D01*
G01X1463058D02*
X1468533D01*
G01X1460321Y928483D02*
X1463058Y925746D01*
G01X1457584D02*
X1460321Y928483D01*
G01X1452109Y925746D02*
X1457584D01*
G01X1468533Y937950D02*
X1452109D01*
G01X1475054Y954706D02*
Y952484D01*
X1474901Y952019D01*
X1474594Y951709D01*
X1474211Y951606D01*
X1473828Y951709D01*
X1473521Y952019D01*
X1473368Y952484D01*
Y954706D01*
G01X1471111Y951606D02*
Y954706D01*
X1471571Y954086D01*
G01Y951606D02*
X1470651D01*
G01X1468011Y954706D02*
X1468318Y954603D01*
X1468548Y954344D01*
X1468701Y954034D01*
X1468816Y953621D01*
X1468854Y953156D01*
X1468816Y952691D01*
X1468701Y952278D01*
X1468548Y951968D01*
X1468318Y951709D01*
X1468011Y951606D01*
X1467704Y951709D01*
X1467474Y951968D01*
X1467321Y952278D01*
X1467206Y952691D01*
X1467168Y953156D01*
X1467206Y953621D01*
X1467321Y954034D01*
X1467474Y954344D01*
X1467704Y954603D01*
X1468011Y954706D01*
G01X1464911Y951606D02*
Y954706D01*
X1465371Y954086D01*
G01Y951606D02*
X1464451D01*
G01X1463163Y964778D02*
Y955978D01*
G01X1468963D02*
X1463163D01*
G01X1476763Y964778D02*
X1463163D01*
G01X1467643Y969781D02*
X1461843D01*
G01Y978581D02*
Y969781D01*
G01X1473467Y984156D02*
Y981934D01*
X1473314Y981469D01*
X1473007Y981159D01*
X1472624Y981056D01*
X1472241Y981159D01*
X1471934Y981469D01*
X1471781Y981934D01*
Y984156D01*
G01X1469524Y981056D02*
Y984156D01*
X1469984Y983536D01*
G01Y981056D02*
X1469064D01*
G01X1466424Y984156D02*
X1466731Y984053D01*
X1466961Y983794D01*
X1467114Y983484D01*
X1467229Y983071D01*
X1467267Y982606D01*
X1467229Y982141D01*
X1467114Y981728D01*
X1466961Y981418D01*
X1466731Y981159D01*
X1466424Y981056D01*
X1466117Y981159D01*
X1465887Y981418D01*
X1465734Y981728D01*
X1465619Y982141D01*
X1465581Y982606D01*
X1465619Y983071D01*
X1465734Y983484D01*
X1465887Y983794D01*
X1466117Y984053D01*
X1466424Y984156D01*
G01X1464167Y981676D02*
X1463937Y981314D01*
X1463631Y981108D01*
X1463286Y981056D01*
X1462979Y981108D01*
X1462672Y981366D01*
X1462481Y981676D01*
X1462442Y981986D01*
X1462519Y982348D01*
X1462787Y982606D01*
X1463056Y982709D01*
X1463401D01*
G01X1463056D02*
X1462826Y982864D01*
X1462634Y983123D01*
X1462557Y983433D01*
X1462634Y983743D01*
X1462826Y984001D01*
X1463171Y984156D01*
X1463516Y984104D01*
X1463861Y983898D01*
G01X1475443Y978581D02*
X1461843D01*
G01X1456915Y1061414D02*
G03X1519487Y1066535I31076J5121D01*
G01X1458396Y1274158D02*
G03X1464298Y1242636I29596J-10772D01*
G01X1519487Y1263386D02*
G03X1461121Y1279815I-31495J0D01*
G01X1457265Y1496511D02*
X1449765D01*
Y1494271D01*
X1450140Y1493524D01*
X1451015Y1492964D01*
X1452015Y1492777D01*
X1453015Y1492964D01*
X1453765Y1493431D01*
X1454140Y1494271D01*
Y1496511D01*
G01X1457265Y1489011D02*
X1449765D01*
Y1486677D01*
X1450140Y1485931D01*
X1450640Y1485464D01*
X1451640Y1485277D01*
X1452640Y1485464D01*
X1453265Y1486024D01*
X1453640Y1486677D01*
Y1489011D01*
G01Y1486677D02*
X1457265Y1485277D01*
G01Y1477777D02*
Y1481511D01*
X1449765D01*
Y1477777D01*
G01X1453390Y1479271D02*
Y1481511D01*
G01X1456265Y1474104D02*
X1456890Y1473357D01*
X1457265Y1472517D01*
Y1471771D01*
X1456890Y1471024D01*
X1456265Y1470464D01*
X1455390Y1470184D01*
X1454515Y1470371D01*
X1453765Y1470837D01*
X1453265Y1471677D01*
X1453015Y1472797D01*
X1452515Y1473451D01*
X1451640Y1473731D01*
X1450765Y1473544D01*
X1450140Y1473077D01*
X1449765Y1472424D01*
Y1471771D01*
X1450015Y1471117D01*
X1450640Y1470557D01*
G01X1456265Y1466604D02*
X1456890Y1465857D01*
X1457265Y1465017D01*
Y1464271D01*
X1456890Y1463524D01*
X1456265Y1462964D01*
X1455390Y1462684D01*
X1454515Y1462871D01*
X1453765Y1463337D01*
X1453265Y1464177D01*
X1453015Y1465297D01*
X1452515Y1465951D01*
X1451640Y1466231D01*
X1450765Y1466044D01*
X1450140Y1465577D01*
X1449765Y1464924D01*
Y1464271D01*
X1450015Y1463617D01*
X1450640Y1463057D01*
G01X1454765Y1458357D02*
Y1455931D01*
G01X1457265Y1451417D02*
X1449765D01*
Y1447871D01*
G01X1453390Y1449177D02*
Y1451417D01*
G01X1449765Y1443264D02*
Y1441024D01*
G01Y1442144D02*
X1457265D01*
G01Y1443264D02*
Y1441024D01*
G01X1449765Y1434644D02*
X1457265D01*
G01X1449765Y1436791D02*
Y1432497D01*
G01X1461575Y1425158D02*
Y1689331D01*
G01X1574567Y1425158D02*
X1461575D01*
G01Y1689331D02*
X1574567D01*
G01X1497293Y-94400D02*
Y-91300D01*
X1496527D01*
X1496220Y-91455D01*
X1495990Y-91662D01*
X1495798Y-91972D01*
X1495645Y-92333D01*
X1495607Y-92850D01*
X1495645Y-93367D01*
X1495798Y-93728D01*
X1495990Y-94038D01*
X1496220Y-94245D01*
X1496527Y-94400D01*
X1497293D01*
G01X1492583D02*
X1494117D01*
Y-91300D01*
X1492583D01*
G01X1493197Y-92798D02*
X1494117D01*
G01X1490250Y-91300D02*
X1490557Y-91403D01*
X1490787Y-91662D01*
X1490940Y-91972D01*
X1491055Y-92385D01*
X1491093Y-92850D01*
X1491055Y-93315D01*
X1490940Y-93728D01*
X1490787Y-94038D01*
X1490557Y-94297D01*
X1490250Y-94400D01*
X1489943Y-94297D01*
X1489713Y-94038D01*
X1489560Y-93728D01*
X1489445Y-93315D01*
X1489407Y-92850D01*
X1489445Y-92385D01*
X1489560Y-91972D01*
X1489713Y-91662D01*
X1489943Y-91403D01*
X1490250Y-91300D01*
G01X1487878Y-93108D02*
X1487610Y-92747D01*
X1487380Y-92540D01*
X1487073Y-92437D01*
X1486805Y-92540D01*
X1486613Y-92747D01*
X1486460Y-93057D01*
X1486422Y-93418D01*
X1486460Y-93728D01*
X1486613Y-94038D01*
X1486843Y-94297D01*
X1487112Y-94400D01*
X1487418Y-94297D01*
X1487687Y-93987D01*
X1487840Y-93522D01*
X1487878Y-93005D01*
X1487802Y-92333D01*
X1487687Y-91972D01*
X1487495Y-91610D01*
X1487227Y-91352D01*
X1486958Y-91300D01*
X1486690Y-91403D01*
X1486498Y-91662D01*
G01X1484778Y-94400D02*
Y-91300D01*
X1483322D01*
G01X1483858Y-92798D02*
X1484778D01*
G01X1482100Y-95433D02*
X1479800D01*
G01X1478578Y-91817D02*
X1478348Y-91507D01*
X1478080Y-91352D01*
X1477773Y-91300D01*
X1477390Y-91403D01*
X1477122Y-91662D01*
X1477045Y-91972D01*
X1477083Y-92282D01*
X1477237Y-92540D01*
X1478003Y-93057D01*
X1478348Y-93418D01*
X1478578Y-93935D01*
X1478655Y-94400D01*
X1477045D01*
G01X1465302Y880794D02*
Y877594D01*
G01X1471502D02*
Y880794D01*
G01X1465302Y877594D02*
X1471502D01*
G01X1465302Y876794D02*
Y873594D01*
G01X1471502Y876794D02*
X1465302D01*
G01X1471502Y873594D02*
Y876794D01*
G01X1465302Y873594D02*
X1471502D01*
G01X1471768Y872881D02*
X1468568D01*
G01X1471768Y866681D02*
Y872881D01*
G01X1468568Y866681D02*
X1471768D01*
G01X1468568Y872881D02*
Y866681D01*
G01X1467675Y866714D02*
Y872914D01*
G01X1471502Y880794D02*
X1465302D01*
G01X1468065Y895900D02*
Y902100D01*
G01X1465956Y888774D02*
X1469156D01*
G01X1465956Y894974D02*
Y888774D01*
G01X1469156Y894974D02*
X1465956D01*
G01X1469156Y888774D02*
Y894974D01*
G01X1469400Y925100D02*
Y921900D01*
G01X1475600Y925100D02*
X1469400D01*
G01X1475600Y921900D02*
Y925100D01*
G01X1469400Y921900D02*
X1475600D01*
G01X1475595Y928924D02*
Y925724D01*
G01X1481795Y928924D02*
X1475595D01*
G01Y925724D02*
X1481795D01*
G01X1468533Y925746D02*
Y937950D01*
G01X1475595Y932924D02*
Y929724D01*
G01X1481795Y932924D02*
X1475595D01*
G01Y929724D02*
X1481795D01*
G01X1475595Y940924D02*
Y937724D01*
G01X1481795Y940924D02*
X1475595D01*
G01Y937724D02*
X1481795D01*
G01X1475595Y936924D02*
Y933724D01*
G01X1481795Y936924D02*
X1475595D01*
G01Y933724D02*
X1481795D01*
G01X1469963Y957478D02*
X1468963Y955978D01*
G01X1470963D02*
X1469963Y957478D01*
G01X1476763Y955978D02*
Y964778D01*
G01Y955978D02*
X1470963D01*
G01X1477916Y957413D02*
X1484116D01*
G01X1477916Y960613D02*
Y957413D01*
G01X1484116Y960613D02*
X1477916D01*
G01X1475443Y969781D02*
X1469643D01*
G01X1475443D02*
Y978581D01*
G01X1468643Y971281D02*
X1467643Y969781D01*
G01X1469643D02*
X1468643Y971281D01*
G01X1477308Y1096164D02*
G03X1465633Y1088718I10684J-29628D01*
G01X1477340Y1233747D02*
G03X1510393Y1241247I10652J29640D01*
G01X1483036Y-72678D02*
Y-89278D01*
X1492636D01*
Y-72678D01*
X1483036D01*
G01X1508312Y90372D02*
Y93472D01*
G01X1506702D02*
Y90372D01*
G01Y91922D02*
X1508312D01*
G01X1504407Y90372D02*
Y93472D01*
X1504867Y92852D01*
G01Y90372D02*
X1503947D01*
G01X1501307D02*
Y93472D01*
X1501767Y92852D01*
G01Y90372D02*
X1500847D01*
G01X1499050Y90837D02*
X1498820Y90579D01*
X1498552Y90424D01*
X1498207Y90372D01*
X1497862Y90475D01*
X1497594Y90682D01*
X1497402Y91044D01*
X1497364Y91457D01*
X1497440Y91870D01*
X1497632Y92129D01*
X1497900Y92335D01*
X1498169Y92387D01*
X1498437Y92335D01*
X1498782Y92129D01*
X1498667Y93472D01*
X1497632D01*
G01X1496146Y325600D02*
Y328800D01*
G01X1489946Y325600D02*
X1496146D01*
G01X1489946Y328800D02*
Y325600D01*
G01X1496600Y319600D02*
X1490400D01*
Y316400D01*
X1496600D01*
Y319600D01*
G01X1496146Y328800D02*
X1489946D01*
G01X1495963Y877939D02*
Y874739D01*
G01X1502163Y877939D02*
X1495963D01*
G01Y874739D02*
X1502163D01*
G01X1489663Y879239D02*
Y882439D01*
G01X1483463Y879239D02*
X1489663D01*
G01X1483463Y882439D02*
Y879239D01*
G01X1489663Y868739D02*
Y871939D01*
G01X1483463Y868739D02*
X1489663D01*
G01X1483463Y871939D02*
Y868739D01*
G01X1489663Y871939D02*
X1483463D01*
G01X1496663Y879239D02*
Y882439D01*
G01X1490463Y879239D02*
X1496663D01*
G01X1490463Y882439D02*
Y879239D01*
G01X1496663Y868739D02*
Y871939D01*
G01X1490463Y868739D02*
X1496663D01*
G01X1490463Y871939D02*
Y868739D01*
G01X1496663Y871939D02*
X1490463D01*
G01X1489663Y882439D02*
X1483463D01*
G01X1496663D02*
X1490463D01*
G01X1485736Y893215D02*
Y890015D01*
G01X1491936Y893215D02*
X1485736D01*
G01X1491936Y890015D02*
Y893215D01*
G01X1485736Y890015D02*
X1491936D01*
G01X1492707Y889292D02*
X1489507D01*
G01X1492707Y883092D02*
Y889292D01*
G01X1489507Y883092D02*
X1492707D01*
G01X1489507Y889292D02*
Y883092D01*
G01X1488707Y889292D02*
X1485507D01*
G01X1488707Y883092D02*
Y889292D01*
G01X1485507Y883092D02*
X1488707D01*
G01X1485507Y889292D02*
Y883092D01*
G01X1494963Y928440D02*
X1504963D01*
G01X1494963Y928540D02*
Y928440D01*
G01Y933040D02*
Y928440D01*
G01X1494863Y922940D02*
X1505063D01*
G01X1494863Y927540D02*
Y922940D01*
G01X1505063Y927540D02*
X1494863D01*
G01X1491600Y925600D02*
X1488400D01*
G01X1491600Y919400D02*
Y925600D01*
G01X1488400Y919400D02*
X1491600D01*
G01X1488400Y925600D02*
Y919400D01*
G01X1497400Y918400D02*
X1503600D01*
G01X1497400Y921600D02*
Y918400D01*
G01X1503600Y921600D02*
X1497400D01*
G01X1481795Y925724D02*
Y928924D01*
G01X1504963Y933040D02*
X1494963D01*
G01X1486200Y935900D02*
X1490800D01*
G01X1486200Y946100D02*
Y935900D01*
G01X1490800D02*
Y946100D01*
G01X1491900Y938400D02*
X1495100D01*
G01X1491900Y944600D02*
Y938400D01*
G01X1495100Y944600D02*
X1491900D01*
G01X1495100Y938400D02*
Y944600D01*
G01X1481795Y929724D02*
Y932924D01*
G01Y937724D02*
Y940924D01*
G01Y933724D02*
Y936924D01*
G01X1490800Y946100D02*
X1486200D01*
G01X1492100Y953100D02*
X1488900D01*
G01X1492100Y946900D02*
Y953100D01*
G01X1488900Y946900D02*
X1492100D01*
G01X1488900Y953100D02*
Y946900D01*
G01X1500600Y954600D02*
X1497400D01*
G01Y948400D02*
X1500600D01*
G01X1497400Y954600D02*
Y948400D01*
G01X1484116Y957413D02*
Y960613D01*
G01X1492363Y959978D02*
Y956778D01*
G01X1498563Y959978D02*
X1492363D01*
G01Y956778D02*
X1498563D01*
G01X1485363Y959978D02*
Y956778D01*
G01X1491563Y959978D02*
X1485363D01*
G01X1491563Y956778D02*
Y959978D01*
G01X1485363Y956778D02*
X1491563D01*
G01X1492400Y965100D02*
Y961900D01*
G01X1498600Y965100D02*
X1492400D01*
G01Y961900D02*
X1498600D01*
G01X1485400Y965100D02*
Y961900D01*
G01X1491600Y965100D02*
X1485400D01*
G01X1491600Y961900D02*
Y965100D01*
G01X1485400Y961900D02*
X1491600D01*
G01X1492400Y969600D02*
Y966400D01*
G01X1498600Y969600D02*
X1492400D01*
G01Y966400D02*
X1498600D01*
G01X1485400Y969600D02*
Y966400D01*
G01X1491600Y969600D02*
X1485400D01*
G01X1491600Y966400D02*
Y969600D01*
G01X1485400Y966400D02*
X1491600D01*
G01X1485043Y978781D02*
Y975581D01*
G01X1491243D02*
Y978781D01*
G01X1485043Y975581D02*
X1491243D01*
G01X1492043Y978781D02*
Y975581D01*
G01D02*
X1498243D01*
G01X1491243Y978781D02*
X1485043D01*
G01X1498243D02*
X1492043D01*
G01X1510081Y1088986D02*
G03X1493495Y1097547I-22090J-22450D01*
G01X1532893Y-55800D02*
Y-52700D01*
X1532127D01*
X1531820Y-52855D01*
X1531590Y-53062D01*
X1531398Y-53372D01*
X1531245Y-53733D01*
X1531207Y-54250D01*
X1531245Y-54767D01*
X1531398Y-55128D01*
X1531590Y-55438D01*
X1531820Y-55645D01*
X1532127Y-55800D01*
X1532893D01*
G01X1528183D02*
X1529717D01*
Y-52700D01*
X1528183D01*
G01X1528797Y-54198D02*
X1529717D01*
G01X1525850Y-55800D02*
Y-52700D01*
X1526310Y-53320D01*
G01Y-55800D02*
X1525390D01*
G01X1523478Y-54508D02*
X1523210Y-54147D01*
X1522980Y-53940D01*
X1522673Y-53837D01*
X1522405Y-53940D01*
X1522213Y-54147D01*
X1522060Y-54457D01*
X1522022Y-54818D01*
X1522060Y-55128D01*
X1522213Y-55438D01*
X1522443Y-55697D01*
X1522712Y-55800D01*
X1523018Y-55697D01*
X1523287Y-55387D01*
X1523440Y-54922D01*
X1523478Y-54405D01*
X1523402Y-53733D01*
X1523287Y-53372D01*
X1523095Y-53010D01*
X1522827Y-52752D01*
X1522558Y-52700D01*
X1522290Y-52803D01*
X1522098Y-53062D01*
G01X1519650Y-52700D02*
Y-55800D01*
G01X1520532Y-52700D02*
X1518768D01*
G01X1517700Y-56833D02*
X1515400D01*
G01X1514178Y-53217D02*
X1513948Y-52907D01*
X1513680Y-52752D01*
X1513373Y-52700D01*
X1512990Y-52803D01*
X1512722Y-53062D01*
X1512645Y-53372D01*
X1512683Y-53682D01*
X1512837Y-53940D01*
X1513603Y-54457D01*
X1513948Y-54818D01*
X1514178Y-55335D01*
X1514255Y-55800D01*
X1512645D01*
G01X1510563Y879239D02*
X1511563Y880739D01*
G01X1509563D02*
X1510563Y879239D01*
G01X1503763Y880739D02*
Y871939D01*
G01D02*
X1517363D01*
G01X1502163Y874739D02*
Y877939D01*
G01X1520056Y885139D02*
Y882917D01*
X1519903Y882452D01*
X1519596Y882142D01*
X1519213Y882039D01*
X1518830Y882142D01*
X1518523Y882452D01*
X1518370Y882917D01*
Y885139D01*
G01X1516113Y882039D02*
Y885139D01*
X1516573Y884519D01*
G01Y882039D02*
X1515653D01*
G01X1513013Y885139D02*
X1513320Y885036D01*
X1513550Y884777D01*
X1513703Y884467D01*
X1513818Y884054D01*
X1513856Y883589D01*
X1513818Y883124D01*
X1513703Y882711D01*
X1513550Y882401D01*
X1513320Y882142D01*
X1513013Y882039D01*
X1512706Y882142D01*
X1512476Y882401D01*
X1512323Y882711D01*
X1512208Y883124D01*
X1512170Y883589D01*
X1512208Y884054D01*
X1512323Y884467D01*
X1512476Y884777D01*
X1512706Y885036D01*
X1513013Y885139D01*
G01X1509913D02*
X1510220Y885036D01*
X1510450Y884777D01*
X1510603Y884467D01*
X1510718Y884054D01*
X1510756Y883589D01*
X1510718Y883124D01*
X1510603Y882711D01*
X1510450Y882401D01*
X1510220Y882142D01*
X1509913Y882039D01*
X1509606Y882142D01*
X1509376Y882401D01*
X1509223Y882711D01*
X1509108Y883124D01*
X1509070Y883589D01*
X1509108Y884054D01*
X1509223Y884467D01*
X1509376Y884777D01*
X1509606Y885036D01*
X1509913Y885139D01*
G01X1503763Y880739D02*
X1509563D01*
G01X1511563D02*
X1517363D01*
G01X1504963Y933040D02*
Y928440D01*
G01X1505063Y922940D02*
Y927540D01*
G01X1503600Y918400D02*
Y921600D01*
G01X1508900Y924400D02*
X1512100D01*
G01X1508900Y930600D02*
Y924400D01*
G01X1512100D02*
Y930600D01*
G01D02*
X1508900D01*
G01X1517511Y952028D02*
X1515289D01*
X1514824Y952181D01*
X1514514Y952488D01*
X1514411Y952871D01*
X1514514Y953254D01*
X1514824Y953561D01*
X1515289Y953714D01*
X1517511D01*
G01X1514411Y955971D02*
X1517511D01*
X1516891Y955511D01*
G01X1514411D02*
Y956431D01*
G01X1517511Y959071D02*
X1517408Y958764D01*
X1517149Y958534D01*
X1516839Y958381D01*
X1516426Y958266D01*
X1515961Y958228D01*
X1515496Y958266D01*
X1515083Y958381D01*
X1514773Y958534D01*
X1514514Y958764D01*
X1514411Y959071D01*
X1514514Y959378D01*
X1514773Y959608D01*
X1515083Y959761D01*
X1515496Y959876D01*
X1515961Y959914D01*
X1516426Y959876D01*
X1516839Y959761D01*
X1517149Y959608D01*
X1517408Y959378D01*
X1517511Y959071D01*
G01X1516994Y961443D02*
X1517304Y961673D01*
X1517459Y961941D01*
X1517511Y962248D01*
X1517408Y962631D01*
X1517149Y962899D01*
X1516839Y962976D01*
X1516529Y962938D01*
X1516271Y962784D01*
X1515754Y962018D01*
X1515393Y961673D01*
X1514876Y961443D01*
X1514411Y961366D01*
Y962976D01*
G01X1510563Y961140D02*
Y964340D01*
G01X1504363Y961140D02*
X1510563D01*
G01X1504363Y964340D02*
Y961140D01*
G01X1510563Y956640D02*
Y959840D01*
G01X1504363Y956640D02*
X1510563D01*
G01X1504363Y959840D02*
Y956640D01*
G01X1510563Y959840D02*
X1504363D01*
G01X1500600Y948400D02*
Y954600D01*
G01X1498563Y956778D02*
Y959978D01*
G01X1510563Y964340D02*
X1504363D01*
G01X1515024Y976769D02*
X1511824D01*
G01Y970569D02*
X1515024D01*
G01X1511824Y976769D02*
Y970569D01*
G01X1498600Y961900D02*
Y965100D01*
G01Y966400D02*
Y969600D01*
G01X1498243Y975581D02*
Y978781D01*
G01X1518392Y-33758D02*
Y-50358D01*
X1527992D01*
Y-33758D01*
X1518392D01*
G01X1517363Y871939D02*
Y880739D01*
G01X1526600Y891400D02*
Y897600D01*
G01X1523400Y891400D02*
X1526600D01*
G01X1523400Y897600D02*
Y891400D01*
G01X1527400D02*
X1530600D01*
G01X1527400Y897600D02*
Y891400D01*
G01X1526600Y897600D02*
X1523400D01*
G01X1530600D02*
X1527400D01*
G01X1514363Y931040D02*
Y926440D01*
G01X1524563D02*
Y931040D01*
G01X1514363Y926440D02*
X1524563D01*
G01X1522533Y919866D02*
X1519333D01*
G01X1522533Y913666D02*
Y919866D01*
G01X1519333Y913666D02*
X1522533D01*
G01X1519333Y919866D02*
Y913666D01*
G01X1515363Y925340D02*
Y922140D01*
G01X1521563Y925340D02*
X1515363D01*
G01X1521563Y922140D02*
Y925340D01*
G01X1515363Y922140D02*
X1521563D01*
G01X1514463Y931940D02*
X1524463D01*
G01Y936540D02*
X1514463D01*
G01X1524463Y936440D02*
Y936540D01*
G01X1514463Y931940D02*
Y936540D01*
G01X1524463Y931940D02*
Y936540D01*
G01X1524563Y931040D02*
X1514363D01*
G01X1521400Y944600D02*
Y941400D01*
G01X1527600Y944600D02*
X1521400D01*
G01X1527600Y941400D02*
Y944600D01*
G01X1521400Y941400D02*
X1527600D01*
G01X1514400Y944600D02*
Y941400D01*
G01X1520600Y944600D02*
X1514400D01*
G01X1520600Y941400D02*
Y944600D01*
G01X1514400Y941400D02*
X1520600D01*
G01X1518600Y964300D02*
Y950700D01*
G01X1527400Y956500D02*
Y950700D01*
G01Y964300D02*
Y958500D01*
G01X1518600Y950700D02*
X1527400D01*
G01X1525900Y957500D02*
X1527400Y956500D01*
G01Y958500D02*
X1525900Y957500D01*
G01X1527400Y964300D02*
X1518600D01*
G01X1524600Y972600D02*
X1521400D01*
G01X1524600Y966400D02*
Y972600D01*
G01X1521400Y966400D02*
X1524600D01*
G01X1521400Y972600D02*
Y966400D01*
G01X1526757Y969991D02*
X1529957D01*
G01X1526757Y976191D02*
Y969991D01*
G01X1529957Y976191D02*
X1526757D01*
G01X1529957Y969991D02*
Y976191D01*
G01X1515824Y970569D02*
X1519024D01*
G01X1515824Y976769D02*
Y970569D01*
G01X1519024Y976769D02*
X1515824D01*
G01X1519024Y970569D02*
Y976769D01*
G01X1515024Y970569D02*
Y976769D01*
G01X1519487Y1066535D02*
G03X1519224Y1070599I-31496J2D01*
G01X1525959Y1133809D02*
X1529159D01*
G01X1525959Y1140009D02*
Y1133809D01*
G01X1529159Y1140009D02*
X1525959D01*
G01X1529159Y1133809D02*
Y1140009D01*
G01X1529699Y1133809D02*
X1532899D01*
G01X1529699Y1140009D02*
Y1133809D01*
G01X1532899Y1140009D02*
X1529699D01*
G01X1525865Y1150130D02*
Y1146930D01*
G01X1532065Y1150130D02*
X1525865D01*
G01Y1146930D02*
X1532065D01*
G01X1526109Y1162250D02*
Y1159050D01*
G01X1532309Y1162250D02*
X1526109D01*
G01Y1159050D02*
X1532309D01*
G01X1526324Y1170700D02*
Y1167500D01*
G01X1532524Y1170700D02*
X1526324D01*
G01Y1167500D02*
X1532524D01*
G01X1526324Y1166160D02*
Y1162960D01*
G01X1532524Y1166160D02*
X1526324D01*
G01Y1162960D02*
X1532524D01*
G01X1519445Y1261764D02*
G03X1519487Y1263386I-31453J1626D01*
G01X1553717Y70479D02*
Y73579D01*
G01X1552107D02*
Y70479D01*
G01Y72029D02*
X1553717D01*
G01X1549812Y70479D02*
Y73579D01*
X1550272Y72959D01*
G01Y70479D02*
X1549352D01*
G01X1547440Y73062D02*
X1547210Y73372D01*
X1546942Y73527D01*
X1546635Y73579D01*
X1546252Y73476D01*
X1545984Y73217D01*
X1545907Y72907D01*
X1545945Y72597D01*
X1546099Y72339D01*
X1546865Y71822D01*
X1547210Y71461D01*
X1547440Y70944D01*
X1547517Y70479D01*
X1545907D01*
G01X1544455Y70944D02*
X1544225Y70686D01*
X1543957Y70531D01*
X1543612Y70479D01*
X1543267Y70582D01*
X1542999Y70789D01*
X1542807Y71151D01*
X1542769Y71564D01*
X1542845Y71977D01*
X1543037Y72236D01*
X1543305Y72442D01*
X1543574Y72494D01*
X1543842Y72442D01*
X1544187Y72236D01*
X1544072Y73579D01*
X1543037D01*
G01X1538385Y540866D02*
Y462126D01*
G01X1530600Y891400D02*
Y897600D01*
G01X1533400Y928900D02*
X1536600D01*
G01X1533400Y935100D02*
Y928900D01*
G01X1536600D02*
Y935100D01*
G01D02*
X1533400D01*
G01Y950400D02*
X1536600D01*
G01X1533400Y956600D02*
Y950400D01*
G01X1536600Y956600D02*
X1533400D01*
G01X1536600Y950400D02*
Y956600D01*
G01X1534844Y976176D02*
X1531644D01*
G01X1534844Y969976D02*
Y976176D01*
G01X1531644Y969976D02*
X1534844D01*
G01X1531644Y976176D02*
Y969976D01*
G01X1545509Y1123108D02*
Y1127708D01*
G01X1535309D02*
Y1123108D01*
G01D02*
X1545509D01*
G01Y1127708D02*
X1535309D01*
G01X1536639Y1140009D02*
X1533439D01*
G01X1536639Y1133809D02*
Y1140009D01*
G01X1533439Y1133809D02*
X1536639D01*
G01X1533439Y1140009D02*
Y1133809D01*
G01X1532899D02*
Y1140009D01*
G01X1532065Y1146930D02*
Y1150130D01*
G01X1532309Y1159050D02*
Y1162250D01*
G01X1532524Y1167500D02*
Y1170700D01*
G01Y1162960D02*
Y1166160D01*
G01X1549760Y552000D02*
Y548800D01*
G01X1555960Y552000D02*
X1549760D01*
G01X1555960Y548800D02*
Y552000D01*
G01X1549760Y548800D02*
X1555960D01*
G01X1549760Y556000D02*
Y552800D01*
G01X1555960D02*
Y556000D01*
G01X1549760Y552800D02*
X1555960D01*
G01X1560546Y546567D02*
Y543367D01*
G01X1566746Y546567D02*
X1560546D01*
G01Y543367D02*
X1566746D01*
G01X1555960Y556000D02*
X1549760D01*
G01X1554429Y1191389D02*
Y1186789D01*
G01D02*
X1564629D01*
G01Y1191389D02*
X1554429D01*
G01X1546623Y1420447D02*
Y1417247D01*
G01X1552823Y1420447D02*
X1546623D01*
G01X1552823Y1417247D02*
Y1420447D01*
G01X1546623Y1417247D02*
X1552823D01*
G01X1555622Y1420406D02*
Y1417206D01*
G01X1561822Y1420406D02*
X1555622D01*
G01X1561822Y1417206D02*
Y1420406D01*
G01X1555622Y1417206D02*
X1561822D01*
G01X1596993Y-94600D02*
Y-91500D01*
X1596227D01*
X1595920Y-91655D01*
X1595690Y-91862D01*
X1595498Y-92172D01*
X1595345Y-92533D01*
X1595307Y-93050D01*
X1595345Y-93567D01*
X1595498Y-93928D01*
X1595690Y-94238D01*
X1595920Y-94445D01*
X1596227Y-94600D01*
X1596993D01*
G01X1592283D02*
X1593817D01*
Y-91500D01*
X1592283D01*
G01X1592897Y-92998D02*
X1593817D01*
G01X1589950Y-91500D02*
X1590257Y-91603D01*
X1590487Y-91862D01*
X1590640Y-92172D01*
X1590755Y-92585D01*
X1590793Y-93050D01*
X1590755Y-93515D01*
X1590640Y-93928D01*
X1590487Y-94238D01*
X1590257Y-94497D01*
X1589950Y-94600D01*
X1589643Y-94497D01*
X1589413Y-94238D01*
X1589260Y-93928D01*
X1589145Y-93515D01*
X1589107Y-93050D01*
X1589145Y-92585D01*
X1589260Y-92172D01*
X1589413Y-91862D01*
X1589643Y-91603D01*
X1589950Y-91500D01*
G01X1587693Y-94135D02*
X1587463Y-94393D01*
X1587195Y-94548D01*
X1586850Y-94600D01*
X1586505Y-94497D01*
X1586237Y-94290D01*
X1586045Y-93928D01*
X1586007Y-93515D01*
X1586083Y-93102D01*
X1586275Y-92843D01*
X1586543Y-92637D01*
X1586812Y-92585D01*
X1587080Y-92637D01*
X1587425Y-92843D01*
X1587310Y-91500D01*
X1586275D01*
G01X1584478Y-94600D02*
Y-91500D01*
X1583022D01*
G01X1583558Y-92998D02*
X1584478D01*
G01X1581800Y-95633D02*
X1579500D01*
G01X1577090Y-94600D02*
Y-91500D01*
X1578508Y-93722D01*
X1576592D01*
G01X1586293Y-56800D02*
Y-53700D01*
X1585527D01*
X1585220Y-53855D01*
X1584990Y-54062D01*
X1584798Y-54372D01*
X1584645Y-54733D01*
X1584607Y-55250D01*
X1584645Y-55767D01*
X1584798Y-56128D01*
X1584990Y-56438D01*
X1585220Y-56645D01*
X1585527Y-56800D01*
X1586293D01*
G01X1581583D02*
X1583117D01*
Y-53700D01*
X1581583D01*
G01X1582197Y-55198D02*
X1583117D01*
G01X1579250Y-56800D02*
Y-53700D01*
X1579710Y-54320D01*
G01Y-56800D02*
X1578790D01*
G01X1576993Y-56335D02*
X1576763Y-56593D01*
X1576495Y-56748D01*
X1576150Y-56800D01*
X1575805Y-56697D01*
X1575537Y-56490D01*
X1575345Y-56128D01*
X1575307Y-55715D01*
X1575383Y-55302D01*
X1575575Y-55043D01*
X1575843Y-54837D01*
X1576112Y-54785D01*
X1576380Y-54837D01*
X1576725Y-55043D01*
X1576610Y-53700D01*
X1575575D01*
G01X1573050D02*
Y-56800D01*
G01X1573932Y-53700D02*
X1572168D01*
G01X1571100Y-57833D02*
X1568800D01*
G01X1567693Y-56180D02*
X1567463Y-56542D01*
X1567157Y-56748D01*
X1566812Y-56800D01*
X1566505Y-56748D01*
X1566198Y-56490D01*
X1566007Y-56180D01*
X1565968Y-55870D01*
X1566045Y-55508D01*
X1566313Y-55250D01*
X1566582Y-55147D01*
X1566927D01*
G01X1566582D02*
X1566352Y-54992D01*
X1566160Y-54733D01*
X1566083Y-54423D01*
X1566160Y-54113D01*
X1566352Y-53855D01*
X1566697Y-53700D01*
X1567042Y-53752D01*
X1567387Y-53958D01*
G01X1581056Y-50386D02*
Y-33786D01*
X1571456D01*
Y-50386D01*
X1581056D01*
G01X1566866Y254685D02*
Y333425D01*
G01X1645606Y254685D02*
X1566866D01*
G01Y333425D02*
X1567038D01*
G01X1566950D02*
X1645606D01*
G01X1566746Y543367D02*
Y546567D01*
G01X1567546D02*
Y543367D01*
G01X1573746Y546567D02*
X1567546D01*
G01X1573746Y543367D02*
Y546567D01*
G01X1567546Y543367D02*
X1573746D01*
G01X1569460Y600800D02*
Y604000D01*
G01X1563260Y600800D02*
X1569460D01*
G01X1563260Y604000D02*
Y600800D01*
G01X1569460Y604000D02*
X1563260D01*
G01X1569460Y596800D02*
Y600000D01*
G01X1563260Y596800D02*
X1569460D01*
G01X1563260Y600000D02*
Y596800D01*
G01X1569460Y600000D02*
X1563260D01*
G01X1569460Y592800D02*
Y596000D01*
G01X1563260Y592800D02*
X1569460D01*
G01X1563260Y596000D02*
Y592800D01*
G01X1569460Y596000D02*
X1563260D01*
G01X1569460Y604800D02*
Y608000D01*
G01X1563260Y604800D02*
X1569460D01*
G01X1563260Y608000D02*
Y604800D01*
G01X1569460Y608000D02*
X1563260D01*
G01X1569460Y608800D02*
Y612000D01*
G01X1563260Y608800D02*
X1569460D01*
G01X1563260Y612000D02*
Y608800D01*
G01X1569460Y612000D02*
X1563260D01*
G01X1569460Y612800D02*
Y616000D01*
G01X1563260Y612800D02*
X1569460D01*
G01X1563260Y616000D02*
Y612800D01*
G01X1569460Y616000D02*
X1563260D01*
G01Y620000D02*
Y616800D01*
G01X1569460Y620000D02*
X1563260D01*
G01X1569460Y616800D02*
Y620000D01*
G01X1563260Y616800D02*
X1569460D01*
G01X1566625Y669567D02*
Y748307D01*
G01X1645365Y669567D02*
X1566625D01*
G01Y748307D02*
X1566797D01*
G01X1566709D02*
X1645365D01*
G01X1587502Y1164591D02*
X1577302D01*
G01D02*
Y1159991D01*
G01D02*
X1587502D01*
G01X1564629Y1186789D02*
Y1191389D01*
G01X1574567Y1689331D02*
Y1425158D01*
G01X1591056Y-89306D02*
Y-72706D01*
X1581456D01*
Y-89306D01*
X1591056D01*
G01X1583910Y343387D02*
Y340187D01*
G01X1590110Y343387D02*
X1583910D01*
G01X1590110Y340187D02*
Y343387D01*
G01X1583910Y340187D02*
X1590110D01*
G01X1583910Y339387D02*
Y336187D01*
G01X1590110Y339387D02*
X1583910D01*
G01X1590110Y336187D02*
Y339387D01*
G01X1583910Y336187D02*
X1590110D01*
G01X1590160Y534900D02*
X1593360D01*
G01X1590160Y541100D02*
Y534900D01*
G01X1593360D02*
Y541100D01*
G01Y548600D02*
X1590160D01*
G01X1593360Y542400D02*
Y548600D01*
G01X1590160Y542400D02*
X1593360D01*
G01X1590160Y548600D02*
Y542400D01*
G01X1593360Y541100D02*
X1590160D01*
G01X1581963Y550147D02*
Y559447D01*
G01X1592563Y550147D02*
X1581963D01*
G01X1592563Y559547D02*
Y550147D01*
G01X1592654Y563718D02*
Y561496D01*
X1592501Y561031D01*
X1592194Y560721D01*
X1591811Y560618D01*
X1591428Y560721D01*
X1591121Y561031D01*
X1590968Y561496D01*
Y563718D01*
G01X1589554Y561238D02*
X1589324Y560876D01*
X1589018Y560670D01*
X1588673Y560618D01*
X1588366Y560670D01*
X1588059Y560928D01*
X1587868Y561238D01*
X1587829Y561548D01*
X1587906Y561910D01*
X1588174Y562168D01*
X1588443Y562271D01*
X1588788D01*
G01X1588443D02*
X1588213Y562426D01*
X1588021Y562685D01*
X1587944Y562995D01*
X1588021Y563305D01*
X1588213Y563563D01*
X1588558Y563718D01*
X1588903Y563666D01*
X1589248Y563460D01*
G01X1585611Y560618D02*
X1585343Y560670D01*
X1585036Y560825D01*
X1584844Y561083D01*
X1584768Y561445D01*
X1584844Y561806D01*
X1585074Y562116D01*
X1585419Y562271D01*
X1585803D01*
X1586033Y562375D01*
X1586224Y562633D01*
X1586301Y562995D01*
X1586186Y563356D01*
X1585918Y563615D01*
X1585611Y563718D01*
X1585304Y563615D01*
X1585036Y563356D01*
X1584921Y562995D01*
X1584998Y562633D01*
X1585189Y562375D01*
X1585419Y562271D01*
X1585803D01*
X1586148Y562116D01*
X1586378Y561806D01*
X1586454Y561445D01*
X1586378Y561083D01*
X1586186Y560825D01*
X1585879Y560670D01*
X1585611Y560618D01*
G01X1581963Y559547D02*
X1592563D01*
G01X1602463Y1164591D02*
X1592263D01*
G01D02*
Y1159991D01*
G01D02*
X1602463D01*
G01X1587502D02*
Y1164591D01*
G01X1593612Y1212352D02*
X1596812D01*
G01X1593612Y1218552D02*
Y1212352D01*
G01X1596812Y1218552D02*
X1593612D01*
G01X1594438Y1479153D02*
X1597638D01*
G01X1594438Y1485353D02*
Y1479153D01*
G01X1597638Y1485353D02*
X1594438D01*
G01X1610355Y90491D02*
Y93591D01*
G01X1608745D02*
Y90491D01*
G01Y92041D02*
X1610355D01*
G01X1606450Y90491D02*
Y93591D01*
X1606910Y92971D01*
G01Y90491D02*
X1605990D01*
G01X1603350Y93591D02*
X1603657Y93488D01*
X1603887Y93229D01*
X1604040Y92919D01*
X1604155Y92506D01*
X1604193Y92041D01*
X1604155Y91576D01*
X1604040Y91163D01*
X1603887Y90853D01*
X1603657Y90594D01*
X1603350Y90491D01*
X1603043Y90594D01*
X1602813Y90853D01*
X1602660Y91163D01*
X1602545Y91576D01*
X1602507Y92041D01*
X1602545Y92506D01*
X1602660Y92919D01*
X1602813Y93229D01*
X1603043Y93488D01*
X1603350Y93591D01*
G01X1601093Y90956D02*
X1600863Y90698D01*
X1600595Y90543D01*
X1600250Y90491D01*
X1599905Y90594D01*
X1599637Y90801D01*
X1599445Y91163D01*
X1599407Y91576D01*
X1599483Y91989D01*
X1599675Y92248D01*
X1599943Y92454D01*
X1600212Y92506D01*
X1600480Y92454D01*
X1600825Y92248D01*
X1600710Y93591D01*
X1599675D01*
G01X1610669Y425429D02*
X1616869D01*
G01X1610669Y428629D02*
Y425429D01*
G01X1616869Y428629D02*
X1610669D01*
G01Y429429D02*
X1616869D01*
G01X1610669Y432629D02*
Y429429D01*
G01X1616869Y432629D02*
X1610669D01*
G01Y433429D02*
X1616869D01*
G01X1610669Y436629D02*
Y433429D01*
G01X1616869Y436629D02*
X1610669D01*
G01X1601904Y1131810D02*
Y1121610D01*
G01D02*
X1606504D01*
G01D02*
Y1131810D01*
G01D02*
X1601904D01*
G01X1621164Y1164591D02*
X1610964D01*
G01D02*
Y1159991D01*
G01D02*
X1621164D01*
G01X1602463D02*
Y1164591D01*
G01X1606476Y1197884D02*
Y1208084D01*
G01X1601876D02*
Y1197884D01*
G01D02*
X1606476D01*
G01Y1208084D02*
X1601876D01*
G01X1596812Y1212352D02*
Y1218552D01*
G01X1601608Y1479153D02*
Y1485353D01*
G01X1598408Y1479153D02*
X1601608D01*
G01X1598408Y1485353D02*
Y1479153D01*
G01X1597638D02*
Y1485353D01*
G01X1601608D02*
X1598408D01*
G01X1616869Y425429D02*
Y428629D01*
G01X1617701Y428617D02*
Y425417D01*
G01X1623901D02*
Y428617D01*
G01X1617701Y425417D02*
X1623901D01*
G01X1616869Y429429D02*
Y432629D01*
G01Y433429D02*
Y436629D01*
G01X1623901Y428617D02*
X1617701D01*
G01X1617669Y432629D02*
Y429429D01*
G01X1623869Y432629D02*
X1617669D01*
G01X1623869Y429429D02*
Y432629D01*
G01X1617669Y429429D02*
X1623869D01*
G01X1617669Y436629D02*
Y433429D01*
G01X1623869Y436629D02*
X1617669D01*
G01X1623869Y433429D02*
Y436629D01*
G01X1617669Y433429D02*
X1623869D01*
G01X1631681Y463407D02*
Y461185D01*
X1631528Y460720D01*
X1631221Y460410D01*
X1630838Y460307D01*
X1630455Y460410D01*
X1630148Y460720D01*
X1629995Y461185D01*
Y463407D01*
G01X1627278Y460307D02*
Y463407D01*
X1628696Y461185D01*
X1626780D01*
G01X1625481Y460927D02*
X1625251Y460565D01*
X1624945Y460359D01*
X1624600Y460307D01*
X1624293Y460359D01*
X1623986Y460617D01*
X1623795Y460927D01*
X1623756Y461237D01*
X1623833Y461599D01*
X1624101Y461857D01*
X1624370Y461960D01*
X1624715D01*
G01X1624370D02*
X1624140Y462115D01*
X1623948Y462374D01*
X1623871Y462684D01*
X1623948Y462994D01*
X1624140Y463252D01*
X1624485Y463407D01*
X1624830Y463355D01*
X1625175Y463149D01*
G01X1621164Y1159991D02*
Y1164591D01*
G01X1630493Y1496511D02*
X1622993D01*
Y1494271D01*
X1623368Y1493524D01*
X1624243Y1492964D01*
X1625243Y1492777D01*
X1626243Y1492964D01*
X1626993Y1493431D01*
X1627368Y1494271D01*
Y1496511D01*
G01X1630493Y1489011D02*
X1622993D01*
Y1486677D01*
X1623368Y1485931D01*
X1623868Y1485464D01*
X1624868Y1485277D01*
X1625868Y1485464D01*
X1626493Y1486024D01*
X1626868Y1486677D01*
Y1489011D01*
G01Y1486677D02*
X1630493Y1485277D01*
G01Y1477777D02*
Y1481511D01*
X1622993D01*
Y1477777D01*
G01X1626618Y1479271D02*
Y1481511D01*
G01X1629493Y1474104D02*
X1630118Y1473357D01*
X1630493Y1472517D01*
Y1471771D01*
X1630118Y1471024D01*
X1629493Y1470464D01*
X1628618Y1470184D01*
X1627743Y1470371D01*
X1626993Y1470837D01*
X1626493Y1471677D01*
X1626243Y1472797D01*
X1625743Y1473451D01*
X1624868Y1473731D01*
X1623993Y1473544D01*
X1623368Y1473077D01*
X1622993Y1472424D01*
Y1471771D01*
X1623243Y1471117D01*
X1623868Y1470557D01*
G01X1629493Y1466604D02*
X1630118Y1465857D01*
X1630493Y1465017D01*
Y1464271D01*
X1630118Y1463524D01*
X1629493Y1462964D01*
X1628618Y1462684D01*
X1627743Y1462871D01*
X1626993Y1463337D01*
X1626493Y1464177D01*
X1626243Y1465297D01*
X1625743Y1465951D01*
X1624868Y1466231D01*
X1623993Y1466044D01*
X1623368Y1465577D01*
X1622993Y1464924D01*
Y1464271D01*
X1623243Y1463617D01*
X1623868Y1463057D01*
G01X1627993Y1458357D02*
Y1455931D01*
G01X1630493Y1451417D02*
X1622993D01*
Y1447871D01*
G01X1626618Y1449177D02*
Y1451417D01*
G01X1622993Y1443264D02*
Y1441024D01*
G01Y1442144D02*
X1630493D01*
G01Y1443264D02*
Y1441024D01*
G01X1622993Y1434644D02*
X1630493D01*
G01X1622993Y1436791D02*
Y1432497D01*
G01X1628304Y439923D02*
Y436723D01*
G01X1634504Y439923D02*
X1628304D01*
G01X1634504Y436723D02*
Y439923D01*
G01X1628304Y436723D02*
X1634504D01*
G01X1638523Y441006D02*
X1644723D01*
G01X1638523Y444206D02*
Y441006D01*
G01X1644723Y444206D02*
X1638523D01*
G01Y445006D02*
X1644723D01*
G01Y448206D02*
X1638523D01*
G01D02*
Y445006D01*
G01X1648595Y449871D02*
X1639295D01*
G01X1639195D02*
Y460471D01*
G01X1639830Y461879D02*
X1646030D01*
G01X1639830Y465079D02*
Y461879D01*
G01X1646030Y465079D02*
X1639830D01*
G01X1639195Y460471D02*
X1648595D01*
G01X1634803Y1425158D02*
Y1689331D01*
G01X1747795Y1425158D02*
X1634803D01*
G01Y1689331D02*
X1747795D01*
G01X1671050Y61880D02*
Y64980D01*
G01X1669440D02*
Y61880D01*
G01Y63430D02*
X1671050D01*
G01X1667145Y61880D02*
Y64980D01*
X1667605Y64360D01*
G01Y61880D02*
X1666685D01*
G01X1664045D02*
Y64980D01*
X1664505Y64360D01*
G01Y61880D02*
X1663585D01*
G01X1660485D02*
Y64980D01*
X1661903Y62758D01*
X1659987D01*
G01X1645606Y333425D02*
Y254685D01*
G01X1650660Y386100D02*
Y382900D01*
G01X1656860Y386100D02*
X1650660D01*
G01X1656860Y382900D02*
Y386100D01*
G01X1650660Y382900D02*
X1656860D01*
G01Y386400D02*
Y389600D01*
G01X1650660Y386400D02*
X1656860D01*
G01X1650660Y389600D02*
Y386400D01*
G01X1656860Y389600D02*
X1650660D01*
G01X1650360Y386400D02*
Y389600D01*
G01X1644160Y386400D02*
X1650360D01*
G01X1644160Y389600D02*
Y386400D01*
G01X1650360Y389600D02*
X1644160D01*
G01X1650360Y382900D02*
Y386100D01*
G01X1644160Y382900D02*
X1650360D01*
G01X1644160Y386100D02*
Y382900D01*
G01X1650360Y386100D02*
X1644160D01*
G01X1644723Y441006D02*
Y444206D01*
G01X1656631Y453552D02*
X1662831D01*
G01X1656631Y456752D02*
Y453552D01*
G01X1662831Y456752D02*
X1656631D01*
G01Y449552D02*
X1662831D01*
G01X1656631Y452752D02*
Y449552D01*
G01X1662831Y452752D02*
X1656631D01*
G01X1644723Y445006D02*
Y448206D01*
G01X1648595Y460471D02*
Y449871D01*
G01X1646030Y461879D02*
Y465079D01*
G01X1648832Y468967D02*
Y465767D01*
G01X1655032Y468967D02*
X1648832D01*
G01X1655032Y465767D02*
Y468967D01*
G01X1648832Y465767D02*
X1655032D01*
G01X1655015Y461635D02*
Y464835D01*
G01X1648815Y461635D02*
X1655015D01*
G01X1648815Y464835D02*
Y461635D01*
G01X1655015Y464835D02*
X1648815D01*
G01X1645365Y748307D02*
Y669567D01*
G01X1673443Y379512D02*
Y376312D01*
G01D02*
X1679643D01*
G01Y379512D02*
X1673443D01*
G01Y391512D02*
Y388312D01*
G01X1679643Y391512D02*
X1673443D01*
G01Y388312D02*
X1679643D01*
G01X1673443Y383512D02*
Y380312D01*
G01X1679643Y383512D02*
X1673443D01*
G01Y380312D02*
X1679643D01*
G01X1673443Y395524D02*
Y392324D01*
G01D02*
X1679643D01*
G01X1673443Y387512D02*
Y384312D01*
G01X1679643Y387512D02*
X1673443D01*
G01Y384312D02*
X1679643D01*
G01Y395524D02*
X1673443D01*
G01Y399512D02*
Y396312D01*
G01X1679643Y399512D02*
X1673443D01*
G01Y396312D02*
X1679643D01*
G01X1673443Y403524D02*
Y400324D01*
G01X1679643Y403524D02*
X1673443D01*
G01Y400324D02*
X1679643D01*
G01X1673443Y407524D02*
Y404324D01*
G01X1679643Y407524D02*
X1673443D01*
G01Y404324D02*
X1679643D01*
G01X1673443Y411524D02*
Y408324D01*
G01D02*
X1679643D01*
G01Y411524D02*
X1673443D01*
G01X1671367Y453305D02*
X1668167D01*
G01X1671367Y447105D02*
Y453305D01*
G01X1668167Y447105D02*
X1671367D01*
G01X1668167Y453305D02*
Y447105D01*
G01X1675317Y453305D02*
X1672117D01*
G01X1675317Y447105D02*
Y453305D01*
G01X1672117Y447105D02*
X1675317D01*
G01X1672117Y453305D02*
Y447105D01*
G01X1662831Y453552D02*
Y456752D01*
G01Y449552D02*
Y452752D01*
G01X1674027Y462108D02*
Y540848D01*
G01X1752767Y462108D02*
X1674027D01*
G01Y540848D02*
X1674199D01*
G01X1674111D02*
X1752767D01*
G01X1670985Y1137549D02*
Y1143749D01*
G01X1667785Y1137549D02*
X1670985D01*
G01X1667785Y1143749D02*
Y1137549D01*
G01X1670985Y1143749D02*
X1667785D01*
G01X1670985Y1151229D02*
X1667785D01*
G01X1670985Y1145029D02*
Y1151229D01*
G01X1667785Y1145029D02*
X1670985D01*
G01X1667785Y1151229D02*
Y1145029D01*
G01X1674458Y1165390D02*
X1664258D01*
G01D02*
Y1160790D01*
G01D02*
X1674458D01*
G01D02*
Y1165390D01*
G01X1675222Y1160779D02*
X1685422D01*
G01Y1165379D02*
X1675222D01*
G01D02*
Y1160779D01*
G01X1661104Y1182431D02*
X1664304D01*
G01X1661104Y1188631D02*
Y1182431D01*
G01X1664304Y1188631D02*
X1661104D01*
G01X1664304Y1182431D02*
Y1188631D01*
G01Y1181150D02*
X1661104D01*
G01X1664304Y1174950D02*
Y1181150D01*
G01X1661104Y1174950D02*
X1664304D01*
G01X1661104Y1181150D02*
Y1174950D01*
G01X1679643Y376312D02*
Y379512D01*
G01Y388312D02*
Y391512D01*
G01Y380312D02*
Y383512D01*
G01Y392324D02*
Y395524D01*
G01Y384312D02*
Y387512D01*
G01Y396312D02*
Y399512D01*
G01Y400324D02*
Y403524D01*
G01Y404324D02*
Y407524D01*
G01Y408324D02*
Y411524D01*
G01X1685422Y1160779D02*
Y1165379D01*
G01X1712994Y90492D02*
Y93592D01*
G01X1711384D02*
Y90492D01*
G01Y92042D02*
X1712994D01*
G01X1709089Y90492D02*
Y93592D01*
X1709549Y92972D01*
G01Y90492D02*
X1708629D01*
G01X1705989Y93592D02*
X1706296Y93489D01*
X1706526Y93230D01*
X1706679Y92920D01*
X1706794Y92507D01*
X1706832Y92042D01*
X1706794Y91577D01*
X1706679Y91164D01*
X1706526Y90854D01*
X1706296Y90595D01*
X1705989Y90492D01*
X1705682Y90595D01*
X1705452Y90854D01*
X1705299Y91164D01*
X1705184Y91577D01*
X1705146Y92042D01*
X1705184Y92507D01*
X1705299Y92920D01*
X1705452Y93230D01*
X1705682Y93489D01*
X1705989Y93592D01*
G01X1703732Y91112D02*
X1703502Y90750D01*
X1703196Y90544D01*
X1702851Y90492D01*
X1702544Y90544D01*
X1702237Y90802D01*
X1702046Y91112D01*
X1702007Y91422D01*
X1702084Y91784D01*
X1702352Y92042D01*
X1702621Y92145D01*
X1702966D01*
G01X1702621D02*
X1702391Y92300D01*
X1702199Y92559D01*
X1702122Y92869D01*
X1702199Y93179D01*
X1702391Y93437D01*
X1702736Y93592D01*
X1703081Y93540D01*
X1703426Y93334D01*
G01X1692891Y1069851D02*
G03X1755708Y1066535I31321J-3316D01*
G01D02*
G03X1702856Y1089685I-31496J0D01*
G01X1703867Y1239343D02*
G03X1755708Y1263386I20345J24043D01*
G01D02*
G03X1692725Y1262652I-31496J0D01*
G01X1726166Y1816326D02*
X1726476Y1816134D01*
X1726683Y1815904D01*
X1726786Y1815636D01*
X1726683Y1815329D01*
X1726476Y1815099D01*
X1726166Y1814869D01*
X1725753Y1814792D01*
X1723686D01*
G01X1726786Y1811999D02*
X1723686D01*
X1725908Y1813417D01*
Y1811501D01*
G01X1726424Y1810011D02*
X1726683Y1809742D01*
X1726786Y1809436D01*
X1726683Y1809129D01*
X1726373Y1808861D01*
X1725908Y1808669D01*
X1725443Y1808592D01*
X1724874D01*
X1724409Y1808669D01*
X1723996Y1808861D01*
X1723789Y1809091D01*
X1723686Y1809359D01*
X1723789Y1809666D01*
X1723996Y1809896D01*
X1724306Y1810049D01*
X1724719Y1810126D01*
X1725081Y1810049D01*
X1725443Y1809857D01*
X1725649Y1809627D01*
X1725701Y1809359D01*
X1725598Y1809052D01*
X1725339Y1808822D01*
X1724874Y1808592D01*
G01X1751493Y-94400D02*
Y-91300D01*
X1750727D01*
X1750420Y-91455D01*
X1750190Y-91662D01*
X1749998Y-91972D01*
X1749845Y-92333D01*
X1749807Y-92850D01*
X1749845Y-93367D01*
X1749998Y-93728D01*
X1750190Y-94038D01*
X1750420Y-94245D01*
X1750727Y-94400D01*
X1751493D01*
G01X1746783D02*
X1748317D01*
Y-91300D01*
X1746783D01*
G01X1747397Y-92798D02*
X1748317D01*
G01X1744450Y-91300D02*
X1744757Y-91403D01*
X1744987Y-91662D01*
X1745140Y-91972D01*
X1745255Y-92385D01*
X1745293Y-92850D01*
X1745255Y-93315D01*
X1745140Y-93728D01*
X1744987Y-94038D01*
X1744757Y-94297D01*
X1744450Y-94400D01*
X1744143Y-94297D01*
X1743913Y-94038D01*
X1743760Y-93728D01*
X1743645Y-93315D01*
X1743607Y-92850D01*
X1743645Y-92385D01*
X1743760Y-91972D01*
X1743913Y-91662D01*
X1744143Y-91403D01*
X1744450Y-91300D01*
G01X1742193Y-93935D02*
X1741963Y-94193D01*
X1741695Y-94348D01*
X1741350Y-94400D01*
X1741005Y-94297D01*
X1740737Y-94090D01*
X1740545Y-93728D01*
X1740507Y-93315D01*
X1740583Y-92902D01*
X1740775Y-92643D01*
X1741043Y-92437D01*
X1741312Y-92385D01*
X1741580Y-92437D01*
X1741925Y-92643D01*
X1741810Y-91300D01*
X1740775D01*
G01X1738978Y-94400D02*
Y-91300D01*
X1737522D01*
G01X1738058Y-92798D02*
X1738978D01*
G01X1736300Y-95433D02*
X1734000D01*
G01X1732893Y-93780D02*
X1732663Y-94142D01*
X1732357Y-94348D01*
X1732012Y-94400D01*
X1731705Y-94348D01*
X1731398Y-94090D01*
X1731207Y-93780D01*
X1731168Y-93470D01*
X1731245Y-93108D01*
X1731513Y-92850D01*
X1731782Y-92747D01*
X1732127D01*
G01X1731782D02*
X1731552Y-92592D01*
X1731360Y-92333D01*
X1731283Y-92023D01*
X1731360Y-91713D01*
X1731552Y-91455D01*
X1731897Y-91300D01*
X1732242Y-91352D01*
X1732587Y-91558D01*
G01X1737536Y-72678D02*
Y-89278D01*
X1747136D01*
Y-72678D01*
X1737536D01*
G01X1728469Y1789796D02*
X1763045Y1802909D01*
G01X1728469Y1816022D02*
Y1789796D01*
G01X1763045Y1802909D02*
X1728469Y1816022D01*
G01X1756470Y71298D02*
Y74398D01*
G01X1754860D02*
Y71298D01*
G01Y72848D02*
X1756470D01*
G01X1752565Y71298D02*
Y74398D01*
X1753025Y73778D01*
G01Y71298D02*
X1752105D01*
G01X1750193Y73881D02*
X1749963Y74191D01*
X1749695Y74346D01*
X1749388Y74398D01*
X1749005Y74295D01*
X1748737Y74036D01*
X1748660Y73726D01*
X1748698Y73416D01*
X1748852Y73158D01*
X1749618Y72641D01*
X1749963Y72280D01*
X1750193Y71763D01*
X1750270Y71298D01*
X1748660D01*
G01X1747208Y71918D02*
X1746978Y71556D01*
X1746672Y71350D01*
X1746327Y71298D01*
X1746020Y71350D01*
X1745713Y71608D01*
X1745522Y71918D01*
X1745483Y72228D01*
X1745560Y72590D01*
X1745828Y72848D01*
X1746097Y72951D01*
X1746442D01*
G01X1746097D02*
X1745867Y73106D01*
X1745675Y73365D01*
X1745598Y73675D01*
X1745675Y73985D01*
X1745867Y74243D01*
X1746212Y74398D01*
X1746557Y74346D01*
X1746902Y74140D01*
G01X1752767Y540848D02*
Y462108D01*
G01X1747795Y1689331D02*
Y1425158D01*
G01X1767913Y1031518D02*
Y1042140D01*
G01X1785615Y1031518D02*
X1767913D01*
G01Y1058643D02*
Y1070818D01*
G01X1766621Y1046718D02*
X1786907D01*
G01X1766621Y1055618D02*
Y1046718D01*
G01X1786907Y1055618D02*
X1766621D01*
G01X1767913Y1070818D02*
X1785615D01*
G01X1776194Y1083174D02*
X1765994D01*
Y1078574D01*
X1776194D01*
Y1083174D01*
G01X1776115Y1088414D02*
X1765915D01*
Y1083814D01*
X1776115D01*
Y1088414D01*
G01Y1103459D02*
X1765915D01*
Y1098859D01*
X1776115D01*
Y1103459D01*
G01X1776217Y1098103D02*
X1766017D01*
Y1093503D01*
X1776217D01*
Y1098103D01*
G01X1822797Y1517889D02*
G02I-25950J0D01*
G01X1835833Y120792D02*
G02I-25950J0D01*
G01X1794074Y991190D02*
X1787874D01*
Y987990D01*
X1794074D01*
Y991190D01*
G01X1785615Y1042140D02*
Y1031518D01*
G01X1807348Y1031210D02*
X1789646D01*
G01D02*
Y1042140D01*
G01X1785615Y1070818D02*
Y1058643D01*
G01X1789646D02*
Y1070510D01*
G01X1786907Y1046718D02*
Y1055618D01*
G01X1788354D02*
Y1046718D01*
G01X1808640Y1055618D02*
X1788354D01*
G01Y1046718D02*
X1808640D01*
G01X1789646Y1070510D02*
X1807348D01*
G01X1786594Y1093329D02*
X1796794D01*
Y1097929D01*
X1786594D01*
Y1093329D01*
G01X1781336Y1098777D02*
X1791536D01*
Y1103377D01*
X1781336D01*
Y1098777D01*
G01X1785860Y1123122D02*
Y1129122D01*
G01X1773860Y1123122D02*
X1785860D01*
G01X1773860Y1129122D02*
Y1123122D01*
G01X1785860Y1129122D02*
X1773860D01*
G01X1785860Y1138122D02*
X1773860D01*
G01X1785860Y1132122D02*
Y1138122D01*
G01X1773860Y1132122D02*
X1785860D01*
G01X1773860Y1138122D02*
Y1132122D01*
G01X1785860Y1154822D02*
X1773860D01*
G01X1785860Y1148822D02*
Y1154822D01*
G01X1773860Y1148822D02*
X1785860D01*
G01X1773860Y1154822D02*
Y1148822D01*
G01X1785860Y1146822D02*
X1773860D01*
G01X1785860Y1140822D02*
Y1146822D01*
G01X1773860Y1140822D02*
X1785860D01*
G01X1773860Y1146822D02*
Y1140822D01*
G01X1818393Y-55500D02*
Y-52400D01*
X1817627D01*
X1817320Y-52555D01*
X1817090Y-52762D01*
X1816898Y-53072D01*
X1816745Y-53433D01*
X1816707Y-53950D01*
X1816745Y-54467D01*
X1816898Y-54828D01*
X1817090Y-55138D01*
X1817320Y-55345D01*
X1817627Y-55500D01*
X1818393D01*
G01X1813683D02*
X1815217D01*
Y-52400D01*
X1813683D01*
G01X1814297Y-53898D02*
X1815217D01*
G01X1811350Y-55500D02*
Y-52400D01*
X1811810Y-53020D01*
G01Y-55500D02*
X1810890D01*
G01X1809093Y-55035D02*
X1808863Y-55293D01*
X1808595Y-55448D01*
X1808250Y-55500D01*
X1807905Y-55397D01*
X1807637Y-55190D01*
X1807445Y-54828D01*
X1807407Y-54415D01*
X1807483Y-54002D01*
X1807675Y-53743D01*
X1807943Y-53537D01*
X1808212Y-53485D01*
X1808480Y-53537D01*
X1808825Y-53743D01*
X1808710Y-52400D01*
X1807675D01*
G01X1805150D02*
Y-55500D01*
G01X1806032Y-52400D02*
X1804268D01*
G01X1803200Y-56533D02*
X1800900D01*
G01X1798490Y-55500D02*
Y-52400D01*
X1799908Y-54622D01*
X1797992D01*
G01X1802892Y-33888D02*
Y-50488D01*
X1812492D01*
Y-33888D01*
X1802892D01*
G01X1803163Y966260D02*
X1796963D01*
Y963060D01*
X1803163D01*
Y966260D01*
G01X1806539Y986660D02*
X1800339D01*
Y983460D01*
X1806539D01*
Y986660D01*
G01X1800179Y1072180D02*
X1810379D01*
Y1076780D01*
X1800179D01*
Y1072180D01*
G01X1805689Y1116589D02*
X1817689D01*
G01X1805689Y1122589D02*
Y1116589D01*
G01X1817689Y1122589D02*
X1805689D01*
G01Y1125589D02*
X1817689D01*
G01X1805689Y1131589D02*
Y1125589D01*
G01X1817689Y1131589D02*
X1805689D01*
G01Y1137912D02*
X1817689D01*
G01X1805689Y1143912D02*
Y1137912D01*
G01Y1145912D02*
X1817689D01*
G01X1805689Y1151912D02*
Y1145912D01*
G01X1817689Y1151912D02*
X1805689D01*
G01X1817689Y1143912D02*
X1805689D01*
G01X1810442Y2091725D02*
X1810135Y2091467D01*
X1809790Y2091312D01*
X1809484D01*
X1809177Y2091467D01*
X1808947Y2091725D01*
X1808832Y2092087D01*
X1808909Y2092449D01*
X1809100Y2092759D01*
X1809445Y2092965D01*
X1809905Y2093069D01*
X1810174Y2093275D01*
X1810289Y2093637D01*
X1810212Y2093999D01*
X1810020Y2094257D01*
X1809752Y2094412D01*
X1809484D01*
X1809215Y2094309D01*
X1808985Y2094050D01*
G01X1805694Y2094154D02*
X1805924Y2094309D01*
X1806192Y2094412D01*
X1806499D01*
X1806844Y2094257D01*
X1807112Y2093999D01*
X1807304Y2093689D01*
X1807457Y2093172D01*
X1807495Y2092707D01*
X1807419Y2092242D01*
X1807304Y2091932D01*
X1807074Y2091622D01*
X1806805Y2091415D01*
X1806537Y2091312D01*
X1806269D01*
X1806000Y2091415D01*
X1805770Y2091570D01*
X1805579Y2091777D01*
G01X1804204Y2091312D02*
Y2094412D01*
X1803245D01*
X1802939Y2094257D01*
X1802747Y2094050D01*
X1802670Y2093637D01*
X1802747Y2093224D01*
X1802977Y2092965D01*
X1803245Y2092810D01*
X1804204D01*
G01X1803245D02*
X1802670Y2091312D01*
G01X1799570D02*
X1801104D01*
Y2094412D01*
X1799570D01*
G01X1800184Y2092914D02*
X1801104D01*
G01X1798387Y2094412D02*
X1797850Y2091312D01*
X1797237Y2094412D01*
X1796624Y2091312D01*
X1796087Y2094412D01*
G01X1795287Y2090279D02*
X1792987D01*
G01X1791037Y2091312D02*
X1790769Y2091364D01*
X1790462Y2091519D01*
X1790270Y2091777D01*
X1790194Y2092139D01*
X1790270Y2092500D01*
X1790500Y2092810D01*
X1790845Y2092965D01*
X1791229D01*
X1791459Y2093069D01*
X1791650Y2093327D01*
X1791727Y2093689D01*
X1791612Y2094050D01*
X1791344Y2094309D01*
X1791037Y2094412D01*
X1790730Y2094309D01*
X1790462Y2094050D01*
X1790347Y2093689D01*
X1790424Y2093327D01*
X1790615Y2093069D01*
X1790845Y2092965D01*
X1791229D01*
X1791574Y2092810D01*
X1791804Y2092500D01*
X1791880Y2092139D01*
X1791804Y2091777D01*
X1791612Y2091519D01*
X1791305Y2091364D01*
X1791037Y2091312D01*
G01X1807348Y1042140D02*
Y1031210D01*
G01Y1070510D02*
Y1058643D01*
G01X1808640Y1046718D02*
Y1055618D01*
G01X1817689Y1116589D02*
Y1122589D01*
G01Y1125589D02*
Y1131589D01*
G01Y1137912D02*
Y1143912D01*
G01Y1145912D02*
Y1151912D01*
G01X1816166Y1200800D02*
X1819366D01*
G01X1816166Y1207000D02*
Y1200800D01*
G01X1819366D02*
Y1207000D01*
G01X1819432Y1214082D02*
X1816232D01*
G01X1819432Y1207882D02*
Y1214082D01*
G01X1816232Y1207882D02*
X1819432D01*
G01X1816232Y1214082D02*
Y1207882D01*
G01X1819366Y1207000D02*
X1816166D01*
G01X1827673Y1567323D02*
G02I-10350J0D01*
G01X1835221Y2047606D02*
X1834914Y2047348D01*
X1834569Y2047193D01*
X1834263D01*
X1833956Y2047348D01*
X1833726Y2047606D01*
X1833611Y2047968D01*
X1833688Y2048330D01*
X1833879Y2048640D01*
X1834224Y2048846D01*
X1834684Y2048950D01*
X1834953Y2049156D01*
X1835068Y2049518D01*
X1834991Y2049880D01*
X1834799Y2050138D01*
X1834531Y2050293D01*
X1834263D01*
X1833994Y2050190D01*
X1833764Y2049931D01*
G01X1830473Y2050035D02*
X1830703Y2050190D01*
X1830971Y2050293D01*
X1831278D01*
X1831623Y2050138D01*
X1831891Y2049880D01*
X1832083Y2049570D01*
X1832236Y2049053D01*
X1832274Y2048588D01*
X1832198Y2048123D01*
X1832083Y2047813D01*
X1831853Y2047503D01*
X1831584Y2047296D01*
X1831316Y2047193D01*
X1831048D01*
X1830779Y2047296D01*
X1830549Y2047451D01*
X1830358Y2047658D01*
G01X1828983Y2047193D02*
Y2050293D01*
X1828024D01*
X1827718Y2050138D01*
X1827526Y2049931D01*
X1827449Y2049518D01*
X1827526Y2049105D01*
X1827756Y2048846D01*
X1828024Y2048691D01*
X1828983D01*
G01X1828024D02*
X1827449Y2047193D01*
G01X1824349D02*
X1825883D01*
Y2050293D01*
X1824349D01*
G01X1824963Y2048795D02*
X1825883D01*
G01X1823166Y2050293D02*
X1822629Y2047193D01*
X1822016Y2050293D01*
X1821403Y2047193D01*
X1820866Y2050293D01*
G01X1820066Y2046160D02*
X1817766D01*
G01X1815356Y2047193D02*
Y2050293D01*
X1816774Y2048071D01*
X1814858D01*
G01X1838321Y2056893D02*
Y2059993D01*
G01X1836711D02*
Y2056893D01*
G01Y2058443D02*
X1838321D01*
G01X1835374Y2056893D02*
X1834416Y2059993D01*
X1833458Y2056893D01*
G01X1833803Y2057978D02*
X1835029D01*
G01X1832198Y2056893D02*
Y2059993D01*
X1830434Y2056893D01*
Y2059993D01*
G01X1829059Y2056893D02*
Y2059993D01*
X1828293D01*
X1827986Y2059838D01*
X1827756Y2059631D01*
X1827564Y2059321D01*
X1827411Y2058960D01*
X1827373Y2058443D01*
X1827411Y2057926D01*
X1827564Y2057565D01*
X1827756Y2057255D01*
X1827986Y2057048D01*
X1828293Y2056893D01*
X1829059D01*
G01X1825883Y2059993D02*
Y2056893D01*
X1824349D01*
G01X1821249D02*
X1822783D01*
Y2059993D01*
X1821249D01*
G01X1821863Y2058495D02*
X1822783D01*
G01X1820066Y2055860D02*
X1817766D01*
G01X1815816Y2059993D02*
X1816123Y2059890D01*
X1816353Y2059631D01*
X1816506Y2059321D01*
X1816621Y2058908D01*
X1816659Y2058443D01*
X1816621Y2057978D01*
X1816506Y2057565D01*
X1816353Y2057255D01*
X1816123Y2056996D01*
X1815816Y2056893D01*
X1815509Y2056996D01*
X1815279Y2057255D01*
X1815126Y2057565D01*
X1815011Y2057978D01*
X1814973Y2058443D01*
X1815011Y2058908D01*
X1815126Y2059321D01*
X1815279Y2059631D01*
X1815509Y2059890D01*
X1815816Y2059993D01*
G01X1858833Y2159268D02*
X1858526Y2159010D01*
X1858181Y2158855D01*
X1857875D01*
X1857568Y2159010D01*
X1857338Y2159268D01*
X1857223Y2159630D01*
X1857300Y2159992D01*
X1857491Y2160302D01*
X1857836Y2160508D01*
X1858296Y2160612D01*
X1858565Y2160818D01*
X1858680Y2161180D01*
X1858603Y2161542D01*
X1858411Y2161800D01*
X1858143Y2161955D01*
X1857875D01*
X1857606Y2161852D01*
X1857376Y2161593D01*
G01X1854085Y2161697D02*
X1854315Y2161852D01*
X1854583Y2161955D01*
X1854890D01*
X1855235Y2161800D01*
X1855503Y2161542D01*
X1855695Y2161232D01*
X1855848Y2160715D01*
X1855886Y2160250D01*
X1855810Y2159785D01*
X1855695Y2159475D01*
X1855465Y2159165D01*
X1855196Y2158958D01*
X1854928Y2158855D01*
X1854660D01*
X1854391Y2158958D01*
X1854161Y2159113D01*
X1853970Y2159320D01*
G01X1852595Y2158855D02*
Y2161955D01*
X1851636D01*
X1851330Y2161800D01*
X1851138Y2161593D01*
X1851061Y2161180D01*
X1851138Y2160767D01*
X1851368Y2160508D01*
X1851636Y2160353D01*
X1852595D01*
G01X1851636D02*
X1851061Y2158855D01*
G01X1847961D02*
X1849495D01*
Y2161955D01*
X1847961D01*
G01X1848575Y2160457D02*
X1849495D01*
G01X1846778Y2161955D02*
X1846241Y2158855D01*
X1845628Y2161955D01*
X1845015Y2158855D01*
X1844478Y2161955D01*
G01X1843678Y2157822D02*
X1841378D01*
G01X1840233Y2159268D02*
X1839926Y2159010D01*
X1839581Y2158855D01*
X1839275D01*
X1838968Y2159010D01*
X1838738Y2159268D01*
X1838623Y2159630D01*
X1838700Y2159992D01*
X1838891Y2160302D01*
X1839236Y2160508D01*
X1839696Y2160612D01*
X1839965Y2160818D01*
X1840080Y2161180D01*
X1840003Y2161542D01*
X1839811Y2161800D01*
X1839543Y2161955D01*
X1839275D01*
X1839006Y2161852D01*
X1838776Y2161593D01*
G01X1837133Y2159268D02*
X1836826Y2159010D01*
X1836481Y2158855D01*
X1836175D01*
X1835868Y2159010D01*
X1835638Y2159268D01*
X1835523Y2159630D01*
X1835600Y2159992D01*
X1835791Y2160302D01*
X1836136Y2160508D01*
X1836596Y2160612D01*
X1836865Y2160818D01*
X1836980Y2161180D01*
X1836903Y2161542D01*
X1836711Y2161800D01*
X1836443Y2161955D01*
X1836175D01*
X1835906Y2161852D01*
X1835676Y2161593D01*
G01X1834071Y2158855D02*
Y2161955D01*
X1833305D01*
X1832998Y2161800D01*
X1832768Y2161593D01*
X1832576Y2161283D01*
X1832423Y2160922D01*
X1832385Y2160405D01*
X1832423Y2159888D01*
X1832576Y2159527D01*
X1832768Y2159217D01*
X1832998Y2159010D01*
X1833305Y2158855D01*
X1834071D01*
G01X1830128D02*
Y2161955D01*
X1830588Y2161335D01*
G01Y2158855D02*
X1829668D01*
G01X1827871Y2159475D02*
X1827641Y2159113D01*
X1827335Y2158907D01*
X1826990Y2158855D01*
X1826683Y2158907D01*
X1826376Y2159165D01*
X1826185Y2159475D01*
X1826146Y2159785D01*
X1826223Y2160147D01*
X1826491Y2160405D01*
X1826760Y2160508D01*
X1827105D01*
G01X1826760D02*
X1826530Y2160663D01*
X1826338Y2160922D01*
X1826261Y2161232D01*
X1826338Y2161542D01*
X1826530Y2161800D01*
X1826875Y2161955D01*
X1827220Y2161903D01*
X1827565Y2161697D01*
G01X1825078Y2157822D02*
X1822778D01*
G01X1820828Y2158855D02*
Y2161955D01*
X1821288Y2161335D01*
G01Y2158855D02*
X1820368D01*
G01X1850533Y2159268D02*
X1850226Y2159010D01*
X1849881Y2158855D01*
X1849575D01*
X1849268Y2159010D01*
X1849038Y2159268D01*
X1848923Y2159630D01*
X1849000Y2159992D01*
X1849191Y2160302D01*
X1849536Y2160508D01*
X1849996Y2160612D01*
X1850265Y2160818D01*
X1850380Y2161180D01*
X1850303Y2161542D01*
X1850111Y2161800D01*
X1849843Y2161955D01*
X1849575D01*
X1849306Y2161852D01*
X1849076Y2161593D01*
G01X1845785Y2161697D02*
X1846015Y2161852D01*
X1846283Y2161955D01*
X1846590D01*
X1846935Y2161800D01*
X1847203Y2161542D01*
X1847395Y2161232D01*
X1847548Y2160715D01*
X1847586Y2160250D01*
X1847510Y2159785D01*
X1847395Y2159475D01*
X1847165Y2159165D01*
X1846896Y2158958D01*
X1846628Y2158855D01*
X1846360D01*
X1846091Y2158958D01*
X1845861Y2159113D01*
X1845670Y2159320D01*
G01X1844295Y2158855D02*
Y2161955D01*
X1843336D01*
X1843030Y2161800D01*
X1842838Y2161593D01*
X1842761Y2161180D01*
X1842838Y2160767D01*
X1843068Y2160508D01*
X1843336Y2160353D01*
X1844295D01*
G01X1843336D02*
X1842761Y2158855D01*
G01X1839661D02*
X1841195D01*
Y2161955D01*
X1839661D01*
G01X1840275Y2160457D02*
X1841195D01*
G01X1838478Y2161955D02*
X1837941Y2158855D01*
X1837328Y2161955D01*
X1836715Y2158855D01*
X1836178Y2161955D01*
G01X1835378Y2157822D02*
X1833078D01*
G01X1831933Y2159268D02*
X1831626Y2159010D01*
X1831281Y2158855D01*
X1830975D01*
X1830668Y2159010D01*
X1830438Y2159268D01*
X1830323Y2159630D01*
X1830400Y2159992D01*
X1830591Y2160302D01*
X1830936Y2160508D01*
X1831396Y2160612D01*
X1831665Y2160818D01*
X1831780Y2161180D01*
X1831703Y2161542D01*
X1831511Y2161800D01*
X1831243Y2161955D01*
X1830975D01*
X1830706Y2161852D01*
X1830476Y2161593D01*
G01X1828833Y2159268D02*
X1828526Y2159010D01*
X1828181Y2158855D01*
X1827875D01*
X1827568Y2159010D01*
X1827338Y2159268D01*
X1827223Y2159630D01*
X1827300Y2159992D01*
X1827491Y2160302D01*
X1827836Y2160508D01*
X1828296Y2160612D01*
X1828565Y2160818D01*
X1828680Y2161180D01*
X1828603Y2161542D01*
X1828411Y2161800D01*
X1828143Y2161955D01*
X1827875D01*
X1827606Y2161852D01*
X1827376Y2161593D01*
G01X1825771Y2158855D02*
Y2161955D01*
X1825005D01*
X1824698Y2161800D01*
X1824468Y2161593D01*
X1824276Y2161283D01*
X1824123Y2160922D01*
X1824085Y2160405D01*
X1824123Y2159888D01*
X1824276Y2159527D01*
X1824468Y2159217D01*
X1824698Y2159010D01*
X1825005Y2158855D01*
X1825771D01*
G01X1821828D02*
Y2161955D01*
X1822288Y2161335D01*
G01Y2158855D02*
X1821368D01*
G01X1819571Y2159475D02*
X1819341Y2159113D01*
X1819035Y2158907D01*
X1818690Y2158855D01*
X1818383Y2158907D01*
X1818076Y2159165D01*
X1817885Y2159475D01*
X1817846Y2159785D01*
X1817923Y2160147D01*
X1818191Y2160405D01*
X1818460Y2160508D01*
X1818805D01*
G01X1818460D02*
X1818230Y2160663D01*
X1818038Y2160922D01*
X1817961Y2161232D01*
X1818038Y2161542D01*
X1818230Y2161800D01*
X1818575Y2161955D01*
X1818920Y2161903D01*
X1819265Y2161697D01*
G01X1816778Y2157822D02*
X1814478D01*
G01X1813256Y2161438D02*
X1813026Y2161748D01*
X1812758Y2161903D01*
X1812451Y2161955D01*
X1812068Y2161852D01*
X1811800Y2161593D01*
X1811723Y2161283D01*
X1811761Y2160973D01*
X1811915Y2160715D01*
X1812681Y2160198D01*
X1813026Y2159837D01*
X1813256Y2159320D01*
X1813333Y2158855D01*
X1811723D01*
G01X1856461Y2174257D02*
X1856154Y2173999D01*
X1855809Y2173844D01*
X1855503D01*
X1855196Y2173999D01*
X1854966Y2174257D01*
X1854851Y2174619D01*
X1854928Y2174981D01*
X1855119Y2175291D01*
X1855464Y2175497D01*
X1855924Y2175601D01*
X1856193Y2175807D01*
X1856308Y2176169D01*
X1856231Y2176531D01*
X1856039Y2176789D01*
X1855771Y2176944D01*
X1855503D01*
X1855234Y2176841D01*
X1855004Y2176582D01*
G01X1851713Y2176686D02*
X1851943Y2176841D01*
X1852211Y2176944D01*
X1852518D01*
X1852863Y2176789D01*
X1853131Y2176531D01*
X1853323Y2176221D01*
X1853476Y2175704D01*
X1853514Y2175239D01*
X1853438Y2174774D01*
X1853323Y2174464D01*
X1853093Y2174154D01*
X1852824Y2173947D01*
X1852556Y2173844D01*
X1852288D01*
X1852019Y2173947D01*
X1851789Y2174102D01*
X1851598Y2174309D01*
G01X1850223Y2173844D02*
Y2176944D01*
X1849264D01*
X1848958Y2176789D01*
X1848766Y2176582D01*
X1848689Y2176169D01*
X1848766Y2175756D01*
X1848996Y2175497D01*
X1849264Y2175342D01*
X1850223D01*
G01X1849264D02*
X1848689Y2173844D01*
G01X1845589D02*
X1847123D01*
Y2176944D01*
X1845589D01*
G01X1846203Y2175446D02*
X1847123D01*
G01X1844406Y2176944D02*
X1843869Y2173844D01*
X1843256Y2176944D01*
X1842643Y2173844D01*
X1842106Y2176944D01*
G01X1841306Y2172811D02*
X1839006D01*
G01X1837861Y2174257D02*
X1837554Y2173999D01*
X1837209Y2173844D01*
X1836903D01*
X1836596Y2173999D01*
X1836366Y2174257D01*
X1836251Y2174619D01*
X1836328Y2174981D01*
X1836519Y2175291D01*
X1836864Y2175497D01*
X1837324Y2175601D01*
X1837593Y2175807D01*
X1837708Y2176169D01*
X1837631Y2176531D01*
X1837439Y2176789D01*
X1837171Y2176944D01*
X1836903D01*
X1836634Y2176841D01*
X1836404Y2176582D01*
G01X1834761Y2174257D02*
X1834454Y2173999D01*
X1834109Y2173844D01*
X1833803D01*
X1833496Y2173999D01*
X1833266Y2174257D01*
X1833151Y2174619D01*
X1833228Y2174981D01*
X1833419Y2175291D01*
X1833764Y2175497D01*
X1834224Y2175601D01*
X1834493Y2175807D01*
X1834608Y2176169D01*
X1834531Y2176531D01*
X1834339Y2176789D01*
X1834071Y2176944D01*
X1833803D01*
X1833534Y2176841D01*
X1833304Y2176582D01*
G01X1831699Y2173844D02*
Y2176944D01*
X1830933D01*
X1830626Y2176789D01*
X1830396Y2176582D01*
X1830204Y2176272D01*
X1830051Y2175911D01*
X1830013Y2175394D01*
X1830051Y2174877D01*
X1830204Y2174516D01*
X1830396Y2174206D01*
X1830626Y2173999D01*
X1830933Y2173844D01*
X1831699D01*
G01X1827756D02*
Y2176944D01*
X1828216Y2176324D01*
G01Y2173844D02*
X1827296D01*
G01X1824196D02*
Y2176944D01*
X1825614Y2174722D01*
X1823698D01*
G01X1822706Y2172811D02*
X1820406D01*
G01X1818456Y2173844D02*
Y2176944D01*
X1818916Y2176324D01*
G01Y2173844D02*
X1817996D01*
G01X1848161Y2174257D02*
X1847854Y2173999D01*
X1847509Y2173844D01*
X1847203D01*
X1846896Y2173999D01*
X1846666Y2174257D01*
X1846551Y2174619D01*
X1846628Y2174981D01*
X1846819Y2175291D01*
X1847164Y2175497D01*
X1847624Y2175601D01*
X1847893Y2175807D01*
X1848008Y2176169D01*
X1847931Y2176531D01*
X1847739Y2176789D01*
X1847471Y2176944D01*
X1847203D01*
X1846934Y2176841D01*
X1846704Y2176582D01*
G01X1843413Y2176686D02*
X1843643Y2176841D01*
X1843911Y2176944D01*
X1844218D01*
X1844563Y2176789D01*
X1844831Y2176531D01*
X1845023Y2176221D01*
X1845176Y2175704D01*
X1845214Y2175239D01*
X1845138Y2174774D01*
X1845023Y2174464D01*
X1844793Y2174154D01*
X1844524Y2173947D01*
X1844256Y2173844D01*
X1843988D01*
X1843719Y2173947D01*
X1843489Y2174102D01*
X1843298Y2174309D01*
G01X1841923Y2173844D02*
Y2176944D01*
X1840964D01*
X1840658Y2176789D01*
X1840466Y2176582D01*
X1840389Y2176169D01*
X1840466Y2175756D01*
X1840696Y2175497D01*
X1840964Y2175342D01*
X1841923D01*
G01X1840964D02*
X1840389Y2173844D01*
G01X1837289D02*
X1838823D01*
Y2176944D01*
X1837289D01*
G01X1837903Y2175446D02*
X1838823D01*
G01X1836106Y2176944D02*
X1835569Y2173844D01*
X1834956Y2176944D01*
X1834343Y2173844D01*
X1833806Y2176944D01*
G01X1833006Y2172811D02*
X1830706D01*
G01X1829561Y2174257D02*
X1829254Y2173999D01*
X1828909Y2173844D01*
X1828603D01*
X1828296Y2173999D01*
X1828066Y2174257D01*
X1827951Y2174619D01*
X1828028Y2174981D01*
X1828219Y2175291D01*
X1828564Y2175497D01*
X1829024Y2175601D01*
X1829293Y2175807D01*
X1829408Y2176169D01*
X1829331Y2176531D01*
X1829139Y2176789D01*
X1828871Y2176944D01*
X1828603D01*
X1828334Y2176841D01*
X1828104Y2176582D01*
G01X1826461Y2174257D02*
X1826154Y2173999D01*
X1825809Y2173844D01*
X1825503D01*
X1825196Y2173999D01*
X1824966Y2174257D01*
X1824851Y2174619D01*
X1824928Y2174981D01*
X1825119Y2175291D01*
X1825464Y2175497D01*
X1825924Y2175601D01*
X1826193Y2175807D01*
X1826308Y2176169D01*
X1826231Y2176531D01*
X1826039Y2176789D01*
X1825771Y2176944D01*
X1825503D01*
X1825234Y2176841D01*
X1825004Y2176582D01*
G01X1823399Y2173844D02*
Y2176944D01*
X1822633D01*
X1822326Y2176789D01*
X1822096Y2176582D01*
X1821904Y2176272D01*
X1821751Y2175911D01*
X1821713Y2175394D01*
X1821751Y2174877D01*
X1821904Y2174516D01*
X1822096Y2174206D01*
X1822326Y2173999D01*
X1822633Y2173844D01*
X1823399D01*
G01X1819456D02*
Y2176944D01*
X1819916Y2176324D01*
G01Y2173844D02*
X1818996D01*
G01X1815896D02*
Y2176944D01*
X1817314Y2174722D01*
X1815398D01*
G01X1814406Y2172811D02*
X1812106D01*
G01X1810884Y2176427D02*
X1810654Y2176737D01*
X1810386Y2176892D01*
X1810079Y2176944D01*
X1809696Y2176841D01*
X1809428Y2176582D01*
X1809351Y2176272D01*
X1809389Y2175962D01*
X1809543Y2175704D01*
X1810309Y2175187D01*
X1810654Y2174826D01*
X1810884Y2174309D01*
X1810961Y2173844D01*
X1809351D01*
G01X1872004Y2051004D02*
X1871697Y2050746D01*
X1871352Y2050591D01*
X1871046D01*
X1870739Y2050746D01*
X1870509Y2051004D01*
X1870394Y2051366D01*
X1870471Y2051728D01*
X1870662Y2052038D01*
X1871007Y2052244D01*
X1871467Y2052348D01*
X1871736Y2052554D01*
X1871851Y2052916D01*
X1871774Y2053278D01*
X1871582Y2053536D01*
X1871314Y2053691D01*
X1871046D01*
X1870777Y2053588D01*
X1870547Y2053329D01*
G01X1867256Y2053433D02*
X1867486Y2053588D01*
X1867754Y2053691D01*
X1868061D01*
X1868406Y2053536D01*
X1868674Y2053278D01*
X1868866Y2052968D01*
X1869019Y2052451D01*
X1869057Y2051986D01*
X1868981Y2051521D01*
X1868866Y2051211D01*
X1868636Y2050901D01*
X1868367Y2050694D01*
X1868099Y2050591D01*
X1867831D01*
X1867562Y2050694D01*
X1867332Y2050849D01*
X1867141Y2051056D01*
G01X1865766Y2050591D02*
Y2053691D01*
X1864807D01*
X1864501Y2053536D01*
X1864309Y2053329D01*
X1864232Y2052916D01*
X1864309Y2052503D01*
X1864539Y2052244D01*
X1864807Y2052089D01*
X1865766D01*
G01X1864807D02*
X1864232Y2050591D01*
G01X1861132D02*
X1862666D01*
Y2053691D01*
X1861132D01*
G01X1861746Y2052193D02*
X1862666D01*
G01X1859949Y2053691D02*
X1859412Y2050591D01*
X1858799Y2053691D01*
X1858186Y2050591D01*
X1857649Y2053691D01*
G01X1856849Y2049558D02*
X1854549D01*
G01X1853404Y2051004D02*
X1853097Y2050746D01*
X1852752Y2050591D01*
X1852446D01*
X1852139Y2050746D01*
X1851909Y2051004D01*
X1851794Y2051366D01*
X1851871Y2051728D01*
X1852062Y2052038D01*
X1852407Y2052244D01*
X1852867Y2052348D01*
X1853136Y2052554D01*
X1853251Y2052916D01*
X1853174Y2053278D01*
X1852982Y2053536D01*
X1852714Y2053691D01*
X1852446D01*
X1852177Y2053588D01*
X1851947Y2053329D01*
G01X1850304Y2051004D02*
X1849997Y2050746D01*
X1849652Y2050591D01*
X1849346D01*
X1849039Y2050746D01*
X1848809Y2051004D01*
X1848694Y2051366D01*
X1848771Y2051728D01*
X1848962Y2052038D01*
X1849307Y2052244D01*
X1849767Y2052348D01*
X1850036Y2052554D01*
X1850151Y2052916D01*
X1850074Y2053278D01*
X1849882Y2053536D01*
X1849614Y2053691D01*
X1849346D01*
X1849077Y2053588D01*
X1848847Y2053329D01*
G01X1847242Y2050591D02*
Y2053691D01*
X1846476D01*
X1846169Y2053536D01*
X1845939Y2053329D01*
X1845747Y2053019D01*
X1845594Y2052658D01*
X1845556Y2052141D01*
X1845594Y2051624D01*
X1845747Y2051263D01*
X1845939Y2050953D01*
X1846169Y2050746D01*
X1846476Y2050591D01*
X1847242D01*
G01X1843376D02*
X1843299Y2051263D01*
X1843184Y2051831D01*
X1843031Y2052348D01*
X1842839Y2052916D01*
X1842532Y2053691D01*
X1844066D01*
G01X1841349Y2049558D02*
X1839049D01*
G01X1837099Y2050591D02*
Y2053691D01*
X1837559Y2053071D01*
G01Y2050591D02*
X1836639D01*
G01X1844921Y2047606D02*
X1844614Y2047348D01*
X1844269Y2047193D01*
X1843963D01*
X1843656Y2047348D01*
X1843426Y2047606D01*
X1843311Y2047968D01*
X1843388Y2048330D01*
X1843579Y2048640D01*
X1843924Y2048846D01*
X1844384Y2048950D01*
X1844653Y2049156D01*
X1844768Y2049518D01*
X1844691Y2049880D01*
X1844499Y2050138D01*
X1844231Y2050293D01*
X1843963D01*
X1843694Y2050190D01*
X1843464Y2049931D01*
G01X1840173Y2050035D02*
X1840403Y2050190D01*
X1840671Y2050293D01*
X1840978D01*
X1841323Y2050138D01*
X1841591Y2049880D01*
X1841783Y2049570D01*
X1841936Y2049053D01*
X1841974Y2048588D01*
X1841898Y2048123D01*
X1841783Y2047813D01*
X1841553Y2047503D01*
X1841284Y2047296D01*
X1841016Y2047193D01*
X1840748D01*
X1840479Y2047296D01*
X1840249Y2047451D01*
X1840058Y2047658D01*
G01X1838683Y2047193D02*
Y2050293D01*
X1837724D01*
X1837418Y2050138D01*
X1837226Y2049931D01*
X1837149Y2049518D01*
X1837226Y2049105D01*
X1837456Y2048846D01*
X1837724Y2048691D01*
X1838683D01*
G01X1837724D02*
X1837149Y2047193D01*
G01X1834049D02*
X1835583D01*
Y2050293D01*
X1834049D01*
G01X1834663Y2048795D02*
X1835583D01*
G01X1832866Y2050293D02*
X1832329Y2047193D01*
X1831716Y2050293D01*
X1831103Y2047193D01*
X1830566Y2050293D01*
G01X1829766Y2046160D02*
X1827466D01*
G01X1826359Y2047813D02*
X1826129Y2047451D01*
X1825823Y2047245D01*
X1825478Y2047193D01*
X1825171Y2047245D01*
X1824864Y2047503D01*
X1824673Y2047813D01*
X1824634Y2048123D01*
X1824711Y2048485D01*
X1824979Y2048743D01*
X1825248Y2048846D01*
X1825593D01*
G01X1825248D02*
X1825018Y2049001D01*
X1824826Y2049260D01*
X1824749Y2049570D01*
X1824826Y2049880D01*
X1825018Y2050138D01*
X1825363Y2050293D01*
X1825708Y2050241D01*
X1826053Y2050035D01*
G01X1871350Y2058619D02*
X1871043Y2058361D01*
X1870698Y2058206D01*
X1870392D01*
X1870085Y2058361D01*
X1869855Y2058619D01*
X1869740Y2058981D01*
X1869817Y2059343D01*
X1870008Y2059653D01*
X1870353Y2059859D01*
X1870813Y2059963D01*
X1871082Y2060169D01*
X1871197Y2060531D01*
X1871120Y2060893D01*
X1870928Y2061151D01*
X1870660Y2061306D01*
X1870392D01*
X1870123Y2061203D01*
X1869893Y2060944D01*
G01X1866602Y2061048D02*
X1866832Y2061203D01*
X1867100Y2061306D01*
X1867407D01*
X1867752Y2061151D01*
X1868020Y2060893D01*
X1868212Y2060583D01*
X1868365Y2060066D01*
X1868403Y2059601D01*
X1868327Y2059136D01*
X1868212Y2058826D01*
X1867982Y2058516D01*
X1867713Y2058309D01*
X1867445Y2058206D01*
X1867177D01*
X1866908Y2058309D01*
X1866678Y2058464D01*
X1866487Y2058671D01*
G01X1865112Y2058206D02*
Y2061306D01*
X1864153D01*
X1863847Y2061151D01*
X1863655Y2060944D01*
X1863578Y2060531D01*
X1863655Y2060118D01*
X1863885Y2059859D01*
X1864153Y2059704D01*
X1865112D01*
G01X1864153D02*
X1863578Y2058206D01*
G01X1860478D02*
X1862012D01*
Y2061306D01*
X1860478D01*
G01X1861092Y2059808D02*
X1862012D01*
G01X1859295Y2061306D02*
X1858758Y2058206D01*
X1858145Y2061306D01*
X1857532Y2058206D01*
X1856995Y2061306D01*
G01X1856195Y2057173D02*
X1853895D01*
G01X1852750Y2058619D02*
X1852443Y2058361D01*
X1852098Y2058206D01*
X1851792D01*
X1851485Y2058361D01*
X1851255Y2058619D01*
X1851140Y2058981D01*
X1851217Y2059343D01*
X1851408Y2059653D01*
X1851753Y2059859D01*
X1852213Y2059963D01*
X1852482Y2060169D01*
X1852597Y2060531D01*
X1852520Y2060893D01*
X1852328Y2061151D01*
X1852060Y2061306D01*
X1851792D01*
X1851523Y2061203D01*
X1851293Y2060944D01*
G01X1849650Y2058619D02*
X1849343Y2058361D01*
X1848998Y2058206D01*
X1848692D01*
X1848385Y2058361D01*
X1848155Y2058619D01*
X1848040Y2058981D01*
X1848117Y2059343D01*
X1848308Y2059653D01*
X1848653Y2059859D01*
X1849113Y2059963D01*
X1849382Y2060169D01*
X1849497Y2060531D01*
X1849420Y2060893D01*
X1849228Y2061151D01*
X1848960Y2061306D01*
X1848692D01*
X1848423Y2061203D01*
X1848193Y2060944D01*
G01X1846588Y2058206D02*
Y2061306D01*
X1845822D01*
X1845515Y2061151D01*
X1845285Y2060944D01*
X1845093Y2060634D01*
X1844940Y2060273D01*
X1844902Y2059756D01*
X1844940Y2059239D01*
X1845093Y2058878D01*
X1845285Y2058568D01*
X1845515Y2058361D01*
X1845822Y2058206D01*
X1846588D01*
G01X1842645D02*
Y2061306D01*
X1843105Y2060686D01*
G01Y2058206D02*
X1842185D01*
G01X1840695Y2057173D02*
X1838395D01*
G01X1837173Y2060789D02*
X1836943Y2061099D01*
X1836675Y2061254D01*
X1836368Y2061306D01*
X1835985Y2061203D01*
X1835717Y2060944D01*
X1835640Y2060634D01*
X1835678Y2060324D01*
X1835832Y2060066D01*
X1836598Y2059549D01*
X1836943Y2059188D01*
X1837173Y2058671D01*
X1837250Y2058206D01*
X1835640D01*
G01X1867704Y2065821D02*
X1867397Y2065563D01*
X1867052Y2065408D01*
X1866746D01*
X1866439Y2065563D01*
X1866209Y2065821D01*
X1866094Y2066183D01*
X1866171Y2066545D01*
X1866362Y2066855D01*
X1866707Y2067061D01*
X1867167Y2067165D01*
X1867436Y2067371D01*
X1867551Y2067733D01*
X1867474Y2068095D01*
X1867282Y2068353D01*
X1867014Y2068508D01*
X1866746D01*
X1866477Y2068405D01*
X1866247Y2068146D01*
G01X1862956Y2068250D02*
X1863186Y2068405D01*
X1863454Y2068508D01*
X1863761D01*
X1864106Y2068353D01*
X1864374Y2068095D01*
X1864566Y2067785D01*
X1864719Y2067268D01*
X1864757Y2066803D01*
X1864681Y2066338D01*
X1864566Y2066028D01*
X1864336Y2065718D01*
X1864067Y2065511D01*
X1863799Y2065408D01*
X1863531D01*
X1863262Y2065511D01*
X1863032Y2065666D01*
X1862841Y2065873D01*
G01X1861466Y2065408D02*
Y2068508D01*
X1860507D01*
X1860201Y2068353D01*
X1860009Y2068146D01*
X1859932Y2067733D01*
X1860009Y2067320D01*
X1860239Y2067061D01*
X1860507Y2066906D01*
X1861466D01*
G01X1860507D02*
X1859932Y2065408D01*
G01X1856832D02*
X1858366D01*
Y2068508D01*
X1856832D01*
G01X1857446Y2067010D02*
X1858366D01*
G01X1855649Y2068508D02*
X1855112Y2065408D01*
X1854499Y2068508D01*
X1853886Y2065408D01*
X1853349Y2068508D01*
G01X1852549Y2064375D02*
X1850249D01*
G01X1849104Y2065821D02*
X1848797Y2065563D01*
X1848452Y2065408D01*
X1848146D01*
X1847839Y2065563D01*
X1847609Y2065821D01*
X1847494Y2066183D01*
X1847571Y2066545D01*
X1847762Y2066855D01*
X1848107Y2067061D01*
X1848567Y2067165D01*
X1848836Y2067371D01*
X1848951Y2067733D01*
X1848874Y2068095D01*
X1848682Y2068353D01*
X1848414Y2068508D01*
X1848146D01*
X1847877Y2068405D01*
X1847647Y2068146D01*
G01X1846004Y2065821D02*
X1845697Y2065563D01*
X1845352Y2065408D01*
X1845046D01*
X1844739Y2065563D01*
X1844509Y2065821D01*
X1844394Y2066183D01*
X1844471Y2066545D01*
X1844662Y2066855D01*
X1845007Y2067061D01*
X1845467Y2067165D01*
X1845736Y2067371D01*
X1845851Y2067733D01*
X1845774Y2068095D01*
X1845582Y2068353D01*
X1845314Y2068508D01*
X1845046D01*
X1844777Y2068405D01*
X1844547Y2068146D01*
G01X1842942Y2065408D02*
Y2068508D01*
X1842176D01*
X1841869Y2068353D01*
X1841639Y2068146D01*
X1841447Y2067836D01*
X1841294Y2067475D01*
X1841256Y2066958D01*
X1841294Y2066441D01*
X1841447Y2066080D01*
X1841639Y2065770D01*
X1841869Y2065563D01*
X1842176Y2065408D01*
X1842942D01*
G01X1839842Y2065873D02*
X1839612Y2065615D01*
X1839344Y2065460D01*
X1838999Y2065408D01*
X1838654Y2065511D01*
X1838386Y2065718D01*
X1838194Y2066080D01*
X1838156Y2066493D01*
X1838232Y2066906D01*
X1838424Y2067165D01*
X1838692Y2067371D01*
X1838961Y2067423D01*
X1839229Y2067371D01*
X1839574Y2067165D01*
X1839459Y2068508D01*
X1838424D01*
G01X1837049Y2064375D02*
X1834749D01*
G01X1833527Y2067991D02*
X1833297Y2068301D01*
X1833029Y2068456D01*
X1832722Y2068508D01*
X1832339Y2068405D01*
X1832071Y2068146D01*
X1831994Y2067836D01*
X1832032Y2067526D01*
X1832186Y2067268D01*
X1832952Y2066751D01*
X1833297Y2066390D01*
X1833527Y2065873D01*
X1833604Y2065408D01*
X1831994D01*
G01X1853689Y2077207D02*
X1853497Y2076897D01*
X1853267Y2076690D01*
X1852999Y2076587D01*
X1852692Y2076690D01*
X1852462Y2076897D01*
X1852232Y2077207D01*
X1852155Y2077620D01*
Y2079687D01*
G01X1850665Y2077207D02*
X1850435Y2076845D01*
X1850129Y2076639D01*
X1849784Y2076587D01*
X1849477Y2076639D01*
X1849170Y2076897D01*
X1848979Y2077207D01*
X1848940Y2077517D01*
X1849017Y2077879D01*
X1849285Y2078137D01*
X1849554Y2078240D01*
X1849899D01*
G01X1849554D02*
X1849324Y2078395D01*
X1849132Y2078654D01*
X1849055Y2078964D01*
X1849132Y2079274D01*
X1849324Y2079532D01*
X1849669Y2079687D01*
X1850014Y2079635D01*
X1850359Y2079429D01*
G01X1847565Y2077207D02*
X1847335Y2076845D01*
X1847029Y2076639D01*
X1846684Y2076587D01*
X1846377Y2076639D01*
X1846070Y2076897D01*
X1845879Y2077207D01*
X1845840Y2077517D01*
X1845917Y2077879D01*
X1846185Y2078137D01*
X1846454Y2078240D01*
X1846799D01*
G01X1846454D02*
X1846224Y2078395D01*
X1846032Y2078654D01*
X1845955Y2078964D01*
X1846032Y2079274D01*
X1846224Y2079532D01*
X1846569Y2079687D01*
X1846914Y2079635D01*
X1847259Y2079429D01*
G01X1844772Y2075554D02*
X1842472D01*
G01X1840522Y2076587D02*
X1840829Y2076639D01*
X1841097Y2076845D01*
X1841327Y2077155D01*
X1841480Y2077517D01*
X1841557Y2077930D01*
Y2078344D01*
X1841480Y2078757D01*
X1841327Y2079119D01*
X1841097Y2079429D01*
X1840829Y2079635D01*
X1840522Y2079687D01*
X1840215Y2079635D01*
X1839947Y2079429D01*
X1839717Y2079119D01*
X1839564Y2078757D01*
X1839487Y2078344D01*
Y2077930D01*
X1839564Y2077517D01*
X1839717Y2077155D01*
X1839947Y2076845D01*
X1840215Y2076639D01*
X1840522Y2076587D01*
G01X1837422Y2079687D02*
Y2076587D01*
G01X1838304Y2079687D02*
X1836540D01*
G01X1835127Y2076587D02*
Y2079687D01*
G01X1833517D02*
Y2076587D01*
G01Y2078137D02*
X1835127D01*
G01X1875182Y2098350D02*
X1874875Y2098092D01*
X1874530Y2097937D01*
X1874224D01*
X1873917Y2098092D01*
X1873687Y2098350D01*
X1873572Y2098712D01*
X1873649Y2099074D01*
X1873840Y2099384D01*
X1874185Y2099590D01*
X1874645Y2099694D01*
X1874914Y2099900D01*
X1875029Y2100262D01*
X1874952Y2100624D01*
X1874760Y2100882D01*
X1874492Y2101037D01*
X1874224D01*
X1873955Y2100934D01*
X1873725Y2100675D01*
G01X1870434Y2100779D02*
X1870664Y2100934D01*
X1870932Y2101037D01*
X1871239D01*
X1871584Y2100882D01*
X1871852Y2100624D01*
X1872044Y2100314D01*
X1872197Y2099797D01*
X1872235Y2099332D01*
X1872159Y2098867D01*
X1872044Y2098557D01*
X1871814Y2098247D01*
X1871545Y2098040D01*
X1871277Y2097937D01*
X1871009D01*
X1870740Y2098040D01*
X1870510Y2098195D01*
X1870319Y2098402D01*
G01X1868944Y2097937D02*
Y2101037D01*
X1867985D01*
X1867679Y2100882D01*
X1867487Y2100675D01*
X1867410Y2100262D01*
X1867487Y2099849D01*
X1867717Y2099590D01*
X1867985Y2099435D01*
X1868944D01*
G01X1867985D02*
X1867410Y2097937D01*
G01X1864310D02*
X1865844D01*
Y2101037D01*
X1864310D01*
G01X1864924Y2099539D02*
X1865844D01*
G01X1863127Y2101037D02*
X1862590Y2097937D01*
X1861977Y2101037D01*
X1861364Y2097937D01*
X1860827Y2101037D01*
G01X1860027Y2096904D02*
X1857727D01*
G01X1856582Y2098350D02*
X1856275Y2098092D01*
X1855930Y2097937D01*
X1855624D01*
X1855317Y2098092D01*
X1855087Y2098350D01*
X1854972Y2098712D01*
X1855049Y2099074D01*
X1855240Y2099384D01*
X1855585Y2099590D01*
X1856045Y2099694D01*
X1856314Y2099900D01*
X1856429Y2100262D01*
X1856352Y2100624D01*
X1856160Y2100882D01*
X1855892Y2101037D01*
X1855624D01*
X1855355Y2100934D01*
X1855125Y2100675D01*
G01X1853482Y2098350D02*
X1853175Y2098092D01*
X1852830Y2097937D01*
X1852524D01*
X1852217Y2098092D01*
X1851987Y2098350D01*
X1851872Y2098712D01*
X1851949Y2099074D01*
X1852140Y2099384D01*
X1852485Y2099590D01*
X1852945Y2099694D01*
X1853214Y2099900D01*
X1853329Y2100262D01*
X1853252Y2100624D01*
X1853060Y2100882D01*
X1852792Y2101037D01*
X1852524D01*
X1852255Y2100934D01*
X1852025Y2100675D01*
G01X1850420Y2097937D02*
Y2101037D01*
X1849654D01*
X1849347Y2100882D01*
X1849117Y2100675D01*
X1848925Y2100365D01*
X1848772Y2100004D01*
X1848734Y2099487D01*
X1848772Y2098970D01*
X1848925Y2098609D01*
X1849117Y2098299D01*
X1849347Y2098092D01*
X1849654Y2097937D01*
X1850420D01*
G01X1846477D02*
Y2101037D01*
X1846937Y2100417D01*
G01Y2097937D02*
X1846017D01*
G01X1843377Y2101037D02*
X1843684Y2100934D01*
X1843914Y2100675D01*
X1844067Y2100365D01*
X1844182Y2099952D01*
X1844220Y2099487D01*
X1844182Y2099022D01*
X1844067Y2098609D01*
X1843914Y2098299D01*
X1843684Y2098040D01*
X1843377Y2097937D01*
X1843070Y2098040D01*
X1842840Y2098299D01*
X1842687Y2098609D01*
X1842572Y2099022D01*
X1842534Y2099487D01*
X1842572Y2099952D01*
X1842687Y2100365D01*
X1842840Y2100675D01*
X1843070Y2100934D01*
X1843377Y2101037D01*
G01X1841427Y2096904D02*
X1839127D01*
G01X1837177Y2097937D02*
Y2101037D01*
X1837637Y2100417D01*
G01Y2097937D02*
X1836717D01*
G01X1866882Y2098350D02*
X1866575Y2098092D01*
X1866230Y2097937D01*
X1865924D01*
X1865617Y2098092D01*
X1865387Y2098350D01*
X1865272Y2098712D01*
X1865349Y2099074D01*
X1865540Y2099384D01*
X1865885Y2099590D01*
X1866345Y2099694D01*
X1866614Y2099900D01*
X1866729Y2100262D01*
X1866652Y2100624D01*
X1866460Y2100882D01*
X1866192Y2101037D01*
X1865924D01*
X1865655Y2100934D01*
X1865425Y2100675D01*
G01X1862134Y2100779D02*
X1862364Y2100934D01*
X1862632Y2101037D01*
X1862939D01*
X1863284Y2100882D01*
X1863552Y2100624D01*
X1863744Y2100314D01*
X1863897Y2099797D01*
X1863935Y2099332D01*
X1863859Y2098867D01*
X1863744Y2098557D01*
X1863514Y2098247D01*
X1863245Y2098040D01*
X1862977Y2097937D01*
X1862709D01*
X1862440Y2098040D01*
X1862210Y2098195D01*
X1862019Y2098402D01*
G01X1860644Y2097937D02*
Y2101037D01*
X1859685D01*
X1859379Y2100882D01*
X1859187Y2100675D01*
X1859110Y2100262D01*
X1859187Y2099849D01*
X1859417Y2099590D01*
X1859685Y2099435D01*
X1860644D01*
G01X1859685D02*
X1859110Y2097937D01*
G01X1856010D02*
X1857544D01*
Y2101037D01*
X1856010D01*
G01X1856624Y2099539D02*
X1857544D01*
G01X1854827Y2101037D02*
X1854290Y2097937D01*
X1853677Y2101037D01*
X1853064Y2097937D01*
X1852527Y2101037D01*
G01X1851727Y2096904D02*
X1849427D01*
G01X1848282Y2098350D02*
X1847975Y2098092D01*
X1847630Y2097937D01*
X1847324D01*
X1847017Y2098092D01*
X1846787Y2098350D01*
X1846672Y2098712D01*
X1846749Y2099074D01*
X1846940Y2099384D01*
X1847285Y2099590D01*
X1847745Y2099694D01*
X1848014Y2099900D01*
X1848129Y2100262D01*
X1848052Y2100624D01*
X1847860Y2100882D01*
X1847592Y2101037D01*
X1847324D01*
X1847055Y2100934D01*
X1846825Y2100675D01*
G01X1845182Y2098350D02*
X1844875Y2098092D01*
X1844530Y2097937D01*
X1844224D01*
X1843917Y2098092D01*
X1843687Y2098350D01*
X1843572Y2098712D01*
X1843649Y2099074D01*
X1843840Y2099384D01*
X1844185Y2099590D01*
X1844645Y2099694D01*
X1844914Y2099900D01*
X1845029Y2100262D01*
X1844952Y2100624D01*
X1844760Y2100882D01*
X1844492Y2101037D01*
X1844224D01*
X1843955Y2100934D01*
X1843725Y2100675D01*
G01X1842120Y2097937D02*
Y2101037D01*
X1841354D01*
X1841047Y2100882D01*
X1840817Y2100675D01*
X1840625Y2100365D01*
X1840472Y2100004D01*
X1840434Y2099487D01*
X1840472Y2098970D01*
X1840625Y2098609D01*
X1840817Y2098299D01*
X1841047Y2098092D01*
X1841354Y2097937D01*
X1842120D01*
G01X1838177D02*
Y2101037D01*
X1838637Y2100417D01*
G01Y2097937D02*
X1837717D01*
G01X1835077Y2101037D02*
X1835384Y2100934D01*
X1835614Y2100675D01*
X1835767Y2100365D01*
X1835882Y2099952D01*
X1835920Y2099487D01*
X1835882Y2099022D01*
X1835767Y2098609D01*
X1835614Y2098299D01*
X1835384Y2098040D01*
X1835077Y2097937D01*
X1834770Y2098040D01*
X1834540Y2098299D01*
X1834387Y2098609D01*
X1834272Y2099022D01*
X1834234Y2099487D01*
X1834272Y2099952D01*
X1834387Y2100365D01*
X1834540Y2100675D01*
X1834770Y2100934D01*
X1835077Y2101037D01*
G01X1833127Y2096904D02*
X1830827D01*
G01X1829605Y2100520D02*
X1829375Y2100830D01*
X1829107Y2100985D01*
X1828800Y2101037D01*
X1828417Y2100934D01*
X1828149Y2100675D01*
X1828072Y2100365D01*
X1828110Y2100055D01*
X1828264Y2099797D01*
X1829030Y2099280D01*
X1829375Y2098919D01*
X1829605Y2098402D01*
X1829682Y2097937D01*
X1828072D01*
G01X1858679Y2114744D02*
X1858487Y2114434D01*
X1858257Y2114227D01*
X1857989Y2114124D01*
X1857682Y2114227D01*
X1857452Y2114434D01*
X1857222Y2114744D01*
X1857145Y2115157D01*
Y2117224D01*
G01X1854352Y2114124D02*
Y2117224D01*
X1855770Y2115002D01*
X1853854D01*
G01X1852555Y2114589D02*
X1852325Y2114331D01*
X1852057Y2114176D01*
X1851712Y2114124D01*
X1851367Y2114227D01*
X1851099Y2114434D01*
X1850907Y2114796D01*
X1850869Y2115209D01*
X1850945Y2115622D01*
X1851137Y2115881D01*
X1851405Y2116087D01*
X1851674Y2116139D01*
X1851942Y2116087D01*
X1852287Y2115881D01*
X1852172Y2117224D01*
X1851137D01*
G01X1849762Y2113091D02*
X1847462D01*
G01X1845512Y2114124D02*
X1845819Y2114176D01*
X1846087Y2114382D01*
X1846317Y2114692D01*
X1846470Y2115054D01*
X1846547Y2115467D01*
Y2115881D01*
X1846470Y2116294D01*
X1846317Y2116656D01*
X1846087Y2116966D01*
X1845819Y2117172D01*
X1845512Y2117224D01*
X1845205Y2117172D01*
X1844937Y2116966D01*
X1844707Y2116656D01*
X1844554Y2116294D01*
X1844477Y2115881D01*
Y2115467D01*
X1844554Y2115054D01*
X1844707Y2114692D01*
X1844937Y2114382D01*
X1845205Y2114176D01*
X1845512Y2114124D01*
G01X1842412Y2117224D02*
Y2114124D01*
G01X1843294Y2117224D02*
X1841530D01*
G01X1840117Y2114124D02*
Y2117224D01*
G01X1838507D02*
Y2114124D01*
G01Y2115674D02*
X1840117D01*
G01X1829706Y2182607D02*
X1826606D01*
G01Y2180997D02*
X1829706D01*
G01X1828156D02*
Y2182607D01*
G01X1829293Y2179507D02*
X1829551Y2179200D01*
X1829706Y2178855D01*
Y2178549D01*
X1829551Y2178242D01*
X1829293Y2178012D01*
X1828931Y2177897D01*
X1828569Y2177974D01*
X1828259Y2178165D01*
X1828053Y2178510D01*
X1827949Y2178970D01*
X1827743Y2179239D01*
X1827381Y2179354D01*
X1827019Y2179277D01*
X1826761Y2179085D01*
X1826606Y2178817D01*
Y2178549D01*
X1826709Y2178280D01*
X1826968Y2178050D01*
G01X1830739Y2176752D02*
Y2174452D01*
G01X1828053Y2172195D02*
X1827898Y2172042D01*
X1827639Y2171927D01*
X1827278Y2171850D01*
X1826968Y2171927D01*
X1826761Y2172080D01*
X1826606Y2172349D01*
Y2173384D01*
X1829706D01*
Y2172119D01*
X1829499Y2171850D01*
X1829189Y2171697D01*
X1828828Y2171620D01*
X1828466Y2171697D01*
X1828156Y2171927D01*
X1828053Y2172195D01*
Y2173384D01*
G01X1829706Y2170169D02*
X1826606D01*
Y2169249D01*
X1826761Y2168942D01*
X1827123Y2168712D01*
X1827536Y2168635D01*
X1827949Y2168712D01*
X1828259Y2168904D01*
X1828414Y2169249D01*
Y2170169D01*
G01X1826606Y2166302D02*
X1826709Y2166609D01*
X1826968Y2166839D01*
X1827278Y2166992D01*
X1827691Y2167107D01*
X1828156Y2167145D01*
X1828621Y2167107D01*
X1829034Y2166992D01*
X1829344Y2166839D01*
X1829603Y2166609D01*
X1829706Y2166302D01*
X1829603Y2165995D01*
X1829344Y2165765D01*
X1829034Y2165612D01*
X1828621Y2165497D01*
X1828156Y2165459D01*
X1827691Y2165497D01*
X1827278Y2165612D01*
X1826968Y2165765D01*
X1826709Y2165995D01*
X1826606Y2166302D01*
G01X1871749Y2046280D02*
X1871557Y2045970D01*
X1871327Y2045763D01*
X1871059Y2045660D01*
X1870752Y2045763D01*
X1870522Y2045970D01*
X1870292Y2046280D01*
X1870215Y2046693D01*
Y2048760D01*
G01X1868610Y2046952D02*
X1868342Y2047313D01*
X1868112Y2047520D01*
X1867805Y2047623D01*
X1867537Y2047520D01*
X1867345Y2047313D01*
X1867192Y2047003D01*
X1867154Y2046642D01*
X1867192Y2046332D01*
X1867345Y2046022D01*
X1867575Y2045763D01*
X1867844Y2045660D01*
X1868150Y2045763D01*
X1868419Y2046073D01*
X1868572Y2046538D01*
X1868610Y2047055D01*
X1868534Y2047727D01*
X1868419Y2048088D01*
X1868227Y2048450D01*
X1867959Y2048708D01*
X1867690Y2048760D01*
X1867422Y2048657D01*
X1867230Y2048398D01*
G01X1864782Y2048760D02*
X1865089Y2048657D01*
X1865319Y2048398D01*
X1865472Y2048088D01*
X1865587Y2047675D01*
X1865625Y2047210D01*
X1865587Y2046745D01*
X1865472Y2046332D01*
X1865319Y2046022D01*
X1865089Y2045763D01*
X1864782Y2045660D01*
X1864475Y2045763D01*
X1864245Y2046022D01*
X1864092Y2046332D01*
X1863977Y2046745D01*
X1863939Y2047210D01*
X1863977Y2047675D01*
X1864092Y2048088D01*
X1864245Y2048398D01*
X1864475Y2048657D01*
X1864782Y2048760D01*
G01X1862832Y2044627D02*
X1860532D01*
G01X1858582Y2045660D02*
Y2048760D01*
X1859042Y2048140D01*
G01Y2045660D02*
X1858122D01*
G01X1856210Y2048243D02*
X1855980Y2048553D01*
X1855712Y2048708D01*
X1855405Y2048760D01*
X1855022Y2048657D01*
X1854754Y2048398D01*
X1854677Y2048088D01*
X1854715Y2047778D01*
X1854869Y2047520D01*
X1855635Y2047003D01*
X1855980Y2046642D01*
X1856210Y2046125D01*
X1856287Y2045660D01*
X1854677D01*
G01X1879650Y2058619D02*
X1879343Y2058361D01*
X1878998Y2058206D01*
X1878692D01*
X1878385Y2058361D01*
X1878155Y2058619D01*
X1878040Y2058981D01*
X1878117Y2059343D01*
X1878308Y2059653D01*
X1878653Y2059859D01*
X1879113Y2059963D01*
X1879382Y2060169D01*
X1879497Y2060531D01*
X1879420Y2060893D01*
X1879228Y2061151D01*
X1878960Y2061306D01*
X1878692D01*
X1878423Y2061203D01*
X1878193Y2060944D01*
G01X1874902Y2061048D02*
X1875132Y2061203D01*
X1875400Y2061306D01*
X1875707D01*
X1876052Y2061151D01*
X1876320Y2060893D01*
X1876512Y2060583D01*
X1876665Y2060066D01*
X1876703Y2059601D01*
X1876627Y2059136D01*
X1876512Y2058826D01*
X1876282Y2058516D01*
X1876013Y2058309D01*
X1875745Y2058206D01*
X1875477D01*
X1875208Y2058309D01*
X1874978Y2058464D01*
X1874787Y2058671D01*
G01X1873412Y2058206D02*
Y2061306D01*
X1872453D01*
X1872147Y2061151D01*
X1871955Y2060944D01*
X1871878Y2060531D01*
X1871955Y2060118D01*
X1872185Y2059859D01*
X1872453Y2059704D01*
X1873412D01*
G01X1872453D02*
X1871878Y2058206D01*
G01X1868778D02*
X1870312D01*
Y2061306D01*
X1868778D01*
G01X1869392Y2059808D02*
X1870312D01*
G01X1867595Y2061306D02*
X1867058Y2058206D01*
X1866445Y2061306D01*
X1865832Y2058206D01*
X1865295Y2061306D01*
G01X1864495Y2057173D02*
X1862195D01*
G01X1861050Y2058619D02*
X1860743Y2058361D01*
X1860398Y2058206D01*
X1860092D01*
X1859785Y2058361D01*
X1859555Y2058619D01*
X1859440Y2058981D01*
X1859517Y2059343D01*
X1859708Y2059653D01*
X1860053Y2059859D01*
X1860513Y2059963D01*
X1860782Y2060169D01*
X1860897Y2060531D01*
X1860820Y2060893D01*
X1860628Y2061151D01*
X1860360Y2061306D01*
X1860092D01*
X1859823Y2061203D01*
X1859593Y2060944D01*
G01X1857950Y2058619D02*
X1857643Y2058361D01*
X1857298Y2058206D01*
X1856992D01*
X1856685Y2058361D01*
X1856455Y2058619D01*
X1856340Y2058981D01*
X1856417Y2059343D01*
X1856608Y2059653D01*
X1856953Y2059859D01*
X1857413Y2059963D01*
X1857682Y2060169D01*
X1857797Y2060531D01*
X1857720Y2060893D01*
X1857528Y2061151D01*
X1857260Y2061306D01*
X1856992D01*
X1856723Y2061203D01*
X1856493Y2060944D01*
G01X1854888Y2058206D02*
Y2061306D01*
X1854122D01*
X1853815Y2061151D01*
X1853585Y2060944D01*
X1853393Y2060634D01*
X1853240Y2060273D01*
X1853202Y2059756D01*
X1853240Y2059239D01*
X1853393Y2058878D01*
X1853585Y2058568D01*
X1853815Y2058361D01*
X1854122Y2058206D01*
X1854888D01*
G01X1850945D02*
Y2061306D01*
X1851405Y2060686D01*
G01Y2058206D02*
X1850485D01*
G01X1848995Y2057173D02*
X1846695D01*
G01X1844745Y2058206D02*
Y2061306D01*
X1845205Y2060686D01*
G01Y2058206D02*
X1844285D01*
G01X1876004Y2065821D02*
X1875697Y2065563D01*
X1875352Y2065408D01*
X1875046D01*
X1874739Y2065563D01*
X1874509Y2065821D01*
X1874394Y2066183D01*
X1874471Y2066545D01*
X1874662Y2066855D01*
X1875007Y2067061D01*
X1875467Y2067165D01*
X1875736Y2067371D01*
X1875851Y2067733D01*
X1875774Y2068095D01*
X1875582Y2068353D01*
X1875314Y2068508D01*
X1875046D01*
X1874777Y2068405D01*
X1874547Y2068146D01*
G01X1871256Y2068250D02*
X1871486Y2068405D01*
X1871754Y2068508D01*
X1872061D01*
X1872406Y2068353D01*
X1872674Y2068095D01*
X1872866Y2067785D01*
X1873019Y2067268D01*
X1873057Y2066803D01*
X1872981Y2066338D01*
X1872866Y2066028D01*
X1872636Y2065718D01*
X1872367Y2065511D01*
X1872099Y2065408D01*
X1871831D01*
X1871562Y2065511D01*
X1871332Y2065666D01*
X1871141Y2065873D01*
G01X1869766Y2065408D02*
Y2068508D01*
X1868807D01*
X1868501Y2068353D01*
X1868309Y2068146D01*
X1868232Y2067733D01*
X1868309Y2067320D01*
X1868539Y2067061D01*
X1868807Y2066906D01*
X1869766D01*
G01X1868807D02*
X1868232Y2065408D01*
G01X1865132D02*
X1866666D01*
Y2068508D01*
X1865132D01*
G01X1865746Y2067010D02*
X1866666D01*
G01X1863949Y2068508D02*
X1863412Y2065408D01*
X1862799Y2068508D01*
X1862186Y2065408D01*
X1861649Y2068508D01*
G01X1860849Y2064375D02*
X1858549D01*
G01X1857404Y2065821D02*
X1857097Y2065563D01*
X1856752Y2065408D01*
X1856446D01*
X1856139Y2065563D01*
X1855909Y2065821D01*
X1855794Y2066183D01*
X1855871Y2066545D01*
X1856062Y2066855D01*
X1856407Y2067061D01*
X1856867Y2067165D01*
X1857136Y2067371D01*
X1857251Y2067733D01*
X1857174Y2068095D01*
X1856982Y2068353D01*
X1856714Y2068508D01*
X1856446D01*
X1856177Y2068405D01*
X1855947Y2068146D01*
G01X1854304Y2065821D02*
X1853997Y2065563D01*
X1853652Y2065408D01*
X1853346D01*
X1853039Y2065563D01*
X1852809Y2065821D01*
X1852694Y2066183D01*
X1852771Y2066545D01*
X1852962Y2066855D01*
X1853307Y2067061D01*
X1853767Y2067165D01*
X1854036Y2067371D01*
X1854151Y2067733D01*
X1854074Y2068095D01*
X1853882Y2068353D01*
X1853614Y2068508D01*
X1853346D01*
X1853077Y2068405D01*
X1852847Y2068146D01*
G01X1851242Y2065408D02*
Y2068508D01*
X1850476D01*
X1850169Y2068353D01*
X1849939Y2068146D01*
X1849747Y2067836D01*
X1849594Y2067475D01*
X1849556Y2066958D01*
X1849594Y2066441D01*
X1849747Y2066080D01*
X1849939Y2065770D01*
X1850169Y2065563D01*
X1850476Y2065408D01*
X1851242D01*
G01X1848142Y2065873D02*
X1847912Y2065615D01*
X1847644Y2065460D01*
X1847299Y2065408D01*
X1846954Y2065511D01*
X1846686Y2065718D01*
X1846494Y2066080D01*
X1846456Y2066493D01*
X1846532Y2066906D01*
X1846724Y2067165D01*
X1846992Y2067371D01*
X1847261Y2067423D01*
X1847529Y2067371D01*
X1847874Y2067165D01*
X1847759Y2068508D01*
X1846724D01*
G01X1845349Y2064375D02*
X1843049D01*
G01X1841099Y2065408D02*
Y2068508D01*
X1841559Y2067888D01*
G01Y2065408D02*
X1840639D01*
G01X1863692Y2076919D02*
X1863500Y2076609D01*
X1863270Y2076402D01*
X1863002Y2076299D01*
X1862695Y2076402D01*
X1862465Y2076609D01*
X1862235Y2076919D01*
X1862158Y2077332D01*
Y2079399D01*
G01X1860668Y2076919D02*
X1860438Y2076557D01*
X1860132Y2076351D01*
X1859787Y2076299D01*
X1859480Y2076351D01*
X1859173Y2076609D01*
X1858982Y2076919D01*
X1858943Y2077229D01*
X1859020Y2077591D01*
X1859288Y2077849D01*
X1859557Y2077952D01*
X1859902D01*
G01X1859557D02*
X1859327Y2078107D01*
X1859135Y2078366D01*
X1859058Y2078676D01*
X1859135Y2078986D01*
X1859327Y2079244D01*
X1859672Y2079399D01*
X1860017Y2079347D01*
X1860362Y2079141D01*
G01X1857453Y2078882D02*
X1857223Y2079192D01*
X1856955Y2079347D01*
X1856648Y2079399D01*
X1856265Y2079296D01*
X1855997Y2079037D01*
X1855920Y2078727D01*
X1855958Y2078417D01*
X1856112Y2078159D01*
X1856878Y2077642D01*
X1857223Y2077281D01*
X1857453Y2076764D01*
X1857530Y2076299D01*
X1855920D01*
G01X1854775Y2075266D02*
X1852475D01*
G01X1850525Y2076299D02*
X1850832Y2076351D01*
X1851100Y2076557D01*
X1851330Y2076867D01*
X1851483Y2077229D01*
X1851560Y2077642D01*
Y2078056D01*
X1851483Y2078469D01*
X1851330Y2078831D01*
X1851100Y2079141D01*
X1850832Y2079347D01*
X1850525Y2079399D01*
X1850218Y2079347D01*
X1849950Y2079141D01*
X1849720Y2078831D01*
X1849567Y2078469D01*
X1849490Y2078056D01*
Y2077642D01*
X1849567Y2077229D01*
X1849720Y2076867D01*
X1849950Y2076557D01*
X1850218Y2076351D01*
X1850525Y2076299D01*
G01X1847425Y2079399D02*
Y2076299D01*
G01X1848307Y2079399D02*
X1846543D01*
G01X1845130Y2076299D02*
Y2079399D01*
G01X1843520D02*
Y2076299D01*
G01Y2077849D02*
X1845130D01*
G01X1874579Y2114744D02*
X1874387Y2114434D01*
X1874157Y2114227D01*
X1873889Y2114124D01*
X1873582Y2114227D01*
X1873352Y2114434D01*
X1873122Y2114744D01*
X1873045Y2115157D01*
Y2117224D01*
G01X1870252Y2114124D02*
Y2117224D01*
X1871670Y2115002D01*
X1869754D01*
G01X1867152Y2114124D02*
Y2117224D01*
X1868570Y2115002D01*
X1866654D01*
G01X1865662Y2113091D02*
X1863362D01*
G01X1861412Y2114124D02*
X1861719Y2114176D01*
X1861987Y2114382D01*
X1862217Y2114692D01*
X1862370Y2115054D01*
X1862447Y2115467D01*
Y2115881D01*
X1862370Y2116294D01*
X1862217Y2116656D01*
X1861987Y2116966D01*
X1861719Y2117172D01*
X1861412Y2117224D01*
X1861105Y2117172D01*
X1860837Y2116966D01*
X1860607Y2116656D01*
X1860454Y2116294D01*
X1860377Y2115881D01*
Y2115467D01*
X1860454Y2115054D01*
X1860607Y2114692D01*
X1860837Y2114382D01*
X1861105Y2114176D01*
X1861412Y2114124D01*
G01X1858312Y2117224D02*
Y2114124D01*
G01X1859194Y2117224D02*
X1857430D01*
G01X1856017Y2114124D02*
Y2117224D01*
G01X1854407D02*
Y2114124D01*
G01Y2115674D02*
X1856017D01*
G01X1884851Y2164045D02*
X1884544Y2163787D01*
X1884199Y2163632D01*
X1883893D01*
X1883586Y2163787D01*
X1883356Y2164045D01*
X1883241Y2164407D01*
X1883318Y2164769D01*
X1883509Y2165079D01*
X1883854Y2165285D01*
X1884314Y2165389D01*
X1884583Y2165595D01*
X1884698Y2165957D01*
X1884621Y2166319D01*
X1884429Y2166577D01*
X1884161Y2166732D01*
X1883893D01*
X1883624Y2166629D01*
X1883394Y2166370D01*
G01X1880103Y2166474D02*
X1880333Y2166629D01*
X1880601Y2166732D01*
X1880908D01*
X1881253Y2166577D01*
X1881521Y2166319D01*
X1881713Y2166009D01*
X1881866Y2165492D01*
X1881904Y2165027D01*
X1881828Y2164562D01*
X1881713Y2164252D01*
X1881483Y2163942D01*
X1881214Y2163735D01*
X1880946Y2163632D01*
X1880678D01*
X1880409Y2163735D01*
X1880179Y2163890D01*
X1879988Y2164097D01*
G01X1878613Y2163632D02*
Y2166732D01*
X1877654D01*
X1877348Y2166577D01*
X1877156Y2166370D01*
X1877079Y2165957D01*
X1877156Y2165544D01*
X1877386Y2165285D01*
X1877654Y2165130D01*
X1878613D01*
G01X1877654D02*
X1877079Y2163632D01*
G01X1873979D02*
X1875513D01*
Y2166732D01*
X1873979D01*
G01X1874593Y2165234D02*
X1875513D01*
G01X1872796Y2166732D02*
X1872259Y2163632D01*
X1871646Y2166732D01*
X1871033Y2163632D01*
X1870496Y2166732D01*
G01X1869696Y2162599D02*
X1867396D01*
G01X1866251Y2164045D02*
X1865944Y2163787D01*
X1865599Y2163632D01*
X1865293D01*
X1864986Y2163787D01*
X1864756Y2164045D01*
X1864641Y2164407D01*
X1864718Y2164769D01*
X1864909Y2165079D01*
X1865254Y2165285D01*
X1865714Y2165389D01*
X1865983Y2165595D01*
X1866098Y2165957D01*
X1866021Y2166319D01*
X1865829Y2166577D01*
X1865561Y2166732D01*
X1865293D01*
X1865024Y2166629D01*
X1864794Y2166370D01*
G01X1863151Y2164045D02*
X1862844Y2163787D01*
X1862499Y2163632D01*
X1862193D01*
X1861886Y2163787D01*
X1861656Y2164045D01*
X1861541Y2164407D01*
X1861618Y2164769D01*
X1861809Y2165079D01*
X1862154Y2165285D01*
X1862614Y2165389D01*
X1862883Y2165595D01*
X1862998Y2165957D01*
X1862921Y2166319D01*
X1862729Y2166577D01*
X1862461Y2166732D01*
X1862193D01*
X1861924Y2166629D01*
X1861694Y2166370D01*
G01X1860089Y2163632D02*
Y2166732D01*
X1859323D01*
X1859016Y2166577D01*
X1858786Y2166370D01*
X1858594Y2166060D01*
X1858441Y2165699D01*
X1858403Y2165182D01*
X1858441Y2164665D01*
X1858594Y2164304D01*
X1858786Y2163994D01*
X1859016Y2163787D01*
X1859323Y2163632D01*
X1860089D01*
G01X1856146D02*
X1855878Y2163684D01*
X1855571Y2163839D01*
X1855379Y2164097D01*
X1855303Y2164459D01*
X1855379Y2164820D01*
X1855609Y2165130D01*
X1855954Y2165285D01*
X1856338D01*
X1856568Y2165389D01*
X1856759Y2165647D01*
X1856836Y2166009D01*
X1856721Y2166370D01*
X1856453Y2166629D01*
X1856146Y2166732D01*
X1855839Y2166629D01*
X1855571Y2166370D01*
X1855456Y2166009D01*
X1855533Y2165647D01*
X1855724Y2165389D01*
X1855954Y2165285D01*
X1856338D01*
X1856683Y2165130D01*
X1856913Y2164820D01*
X1856989Y2164459D01*
X1856913Y2164097D01*
X1856721Y2163839D01*
X1856414Y2163684D01*
X1856146Y2163632D01*
G01X1854196Y2162599D02*
X1851896D01*
G01X1850674Y2166215D02*
X1850444Y2166525D01*
X1850176Y2166680D01*
X1849869Y2166732D01*
X1849486Y2166629D01*
X1849218Y2166370D01*
X1849141Y2166060D01*
X1849179Y2165750D01*
X1849333Y2165492D01*
X1850099Y2164975D01*
X1850444Y2164614D01*
X1850674Y2164097D01*
X1850751Y2163632D01*
X1849141D01*
G01X1889133Y2178615D02*
X1888826Y2178357D01*
X1888481Y2178202D01*
X1888175D01*
X1887868Y2178357D01*
X1887638Y2178615D01*
X1887523Y2178977D01*
X1887600Y2179339D01*
X1887791Y2179649D01*
X1888136Y2179855D01*
X1888596Y2179959D01*
X1888865Y2180165D01*
X1888980Y2180527D01*
X1888903Y2180889D01*
X1888711Y2181147D01*
X1888443Y2181302D01*
X1888175D01*
X1887906Y2181199D01*
X1887676Y2180940D01*
G01X1884385Y2181044D02*
X1884615Y2181199D01*
X1884883Y2181302D01*
X1885190D01*
X1885535Y2181147D01*
X1885803Y2180889D01*
X1885995Y2180579D01*
X1886148Y2180062D01*
X1886186Y2179597D01*
X1886110Y2179132D01*
X1885995Y2178822D01*
X1885765Y2178512D01*
X1885496Y2178305D01*
X1885228Y2178202D01*
X1884960D01*
X1884691Y2178305D01*
X1884461Y2178460D01*
X1884270Y2178667D01*
G01X1882895Y2178202D02*
Y2181302D01*
X1881936D01*
X1881630Y2181147D01*
X1881438Y2180940D01*
X1881361Y2180527D01*
X1881438Y2180114D01*
X1881668Y2179855D01*
X1881936Y2179700D01*
X1882895D01*
G01X1881936D02*
X1881361Y2178202D01*
G01X1878261D02*
X1879795D01*
Y2181302D01*
X1878261D01*
G01X1878875Y2179804D02*
X1879795D01*
G01X1877078Y2181302D02*
X1876541Y2178202D01*
X1875928Y2181302D01*
X1875315Y2178202D01*
X1874778Y2181302D01*
G01X1873978Y2177169D02*
X1871678D01*
G01X1870533Y2178615D02*
X1870226Y2178357D01*
X1869881Y2178202D01*
X1869575D01*
X1869268Y2178357D01*
X1869038Y2178615D01*
X1868923Y2178977D01*
X1869000Y2179339D01*
X1869191Y2179649D01*
X1869536Y2179855D01*
X1869996Y2179959D01*
X1870265Y2180165D01*
X1870380Y2180527D01*
X1870303Y2180889D01*
X1870111Y2181147D01*
X1869843Y2181302D01*
X1869575D01*
X1869306Y2181199D01*
X1869076Y2180940D01*
G01X1867433Y2178615D02*
X1867126Y2178357D01*
X1866781Y2178202D01*
X1866475D01*
X1866168Y2178357D01*
X1865938Y2178615D01*
X1865823Y2178977D01*
X1865900Y2179339D01*
X1866091Y2179649D01*
X1866436Y2179855D01*
X1866896Y2179959D01*
X1867165Y2180165D01*
X1867280Y2180527D01*
X1867203Y2180889D01*
X1867011Y2181147D01*
X1866743Y2181302D01*
X1866475D01*
X1866206Y2181199D01*
X1865976Y2180940D01*
G01X1864371Y2178202D02*
Y2181302D01*
X1863605D01*
X1863298Y2181147D01*
X1863068Y2180940D01*
X1862876Y2180630D01*
X1862723Y2180269D01*
X1862685Y2179752D01*
X1862723Y2179235D01*
X1862876Y2178874D01*
X1863068Y2178564D01*
X1863298Y2178357D01*
X1863605Y2178202D01*
X1864371D01*
G01X1860428D02*
Y2181302D01*
X1860888Y2180682D01*
G01Y2178202D02*
X1859968D01*
G01X1857328D02*
Y2181302D01*
X1857788Y2180682D01*
G01Y2178202D02*
X1856868D01*
G01X1855378Y2177169D02*
X1853078D01*
G01X1851856Y2180785D02*
X1851626Y2181095D01*
X1851358Y2181250D01*
X1851051Y2181302D01*
X1850668Y2181199D01*
X1850400Y2180940D01*
X1850323Y2180630D01*
X1850361Y2180320D01*
X1850515Y2180062D01*
X1851281Y2179545D01*
X1851626Y2179184D01*
X1851856Y2178667D01*
X1851933Y2178202D01*
X1850323D01*
G01X1878749Y2046280D02*
X1878557Y2045970D01*
X1878327Y2045763D01*
X1878059Y2045660D01*
X1877752Y2045763D01*
X1877522Y2045970D01*
X1877292Y2046280D01*
X1877215Y2046693D01*
Y2048760D01*
G01X1875725Y2046125D02*
X1875495Y2045867D01*
X1875227Y2045712D01*
X1874882Y2045660D01*
X1874537Y2045763D01*
X1874269Y2045970D01*
X1874077Y2046332D01*
X1874039Y2046745D01*
X1874115Y2047158D01*
X1874307Y2047417D01*
X1874575Y2047623D01*
X1874844Y2047675D01*
X1875112Y2047623D01*
X1875457Y2047417D01*
X1875342Y2048760D01*
X1874307D01*
G01X1872434Y2046022D02*
X1872165Y2045763D01*
X1871859Y2045660D01*
X1871552Y2045763D01*
X1871284Y2046073D01*
X1871092Y2046538D01*
X1871015Y2047003D01*
Y2047572D01*
X1871092Y2048037D01*
X1871284Y2048450D01*
X1871514Y2048657D01*
X1871782Y2048760D01*
X1872089Y2048657D01*
X1872319Y2048450D01*
X1872472Y2048140D01*
X1872549Y2047727D01*
X1872472Y2047365D01*
X1872280Y2047003D01*
X1872050Y2046797D01*
X1871782Y2046745D01*
X1871475Y2046848D01*
X1871245Y2047107D01*
X1871015Y2047572D01*
G01X1869832Y2044627D02*
X1867532D01*
G01X1865582Y2045660D02*
Y2048760D01*
X1866042Y2048140D01*
G01Y2045660D02*
X1865122D01*
G01X1863210Y2048243D02*
X1862980Y2048553D01*
X1862712Y2048708D01*
X1862405Y2048760D01*
X1862022Y2048657D01*
X1861754Y2048398D01*
X1861677Y2048088D01*
X1861715Y2047778D01*
X1861869Y2047520D01*
X1862635Y2047003D01*
X1862980Y2046642D01*
X1863210Y2046125D01*
X1863287Y2045660D01*
X1861677D01*
G01X1883155Y2065088D02*
X1882963Y2064778D01*
X1882733Y2064571D01*
X1882465Y2064468D01*
X1882158Y2064571D01*
X1881928Y2064778D01*
X1881698Y2065088D01*
X1881621Y2065501D01*
Y2067568D01*
G01X1878828Y2064468D02*
Y2067568D01*
X1880246Y2065346D01*
X1878330D01*
G01X1876188Y2067568D02*
X1876495Y2067465D01*
X1876725Y2067206D01*
X1876878Y2066896D01*
X1876993Y2066483D01*
X1877031Y2066018D01*
X1876993Y2065553D01*
X1876878Y2065140D01*
X1876725Y2064830D01*
X1876495Y2064571D01*
X1876188Y2064468D01*
X1875881Y2064571D01*
X1875651Y2064830D01*
X1875498Y2065140D01*
X1875383Y2065553D01*
X1875345Y2066018D01*
X1875383Y2066483D01*
X1875498Y2066896D01*
X1875651Y2067206D01*
X1875881Y2067465D01*
X1876188Y2067568D01*
G01X1874238Y2063435D02*
X1871938D01*
G01X1869988Y2064468D02*
X1870295Y2064520D01*
X1870563Y2064726D01*
X1870793Y2065036D01*
X1870946Y2065398D01*
X1871023Y2065811D01*
Y2066225D01*
X1870946Y2066638D01*
X1870793Y2067000D01*
X1870563Y2067310D01*
X1870295Y2067516D01*
X1869988Y2067568D01*
X1869681Y2067516D01*
X1869413Y2067310D01*
X1869183Y2067000D01*
X1869030Y2066638D01*
X1868953Y2066225D01*
Y2065811D01*
X1869030Y2065398D01*
X1869183Y2065036D01*
X1869413Y2064726D01*
X1869681Y2064520D01*
X1869988Y2064468D01*
G01X1866888Y2067568D02*
Y2064468D01*
G01X1867770Y2067568D02*
X1866006D01*
G01X1864593Y2064468D02*
Y2067568D01*
G01X1862983D02*
Y2064468D01*
G01Y2066018D02*
X1864593D01*
G01X1874276Y2071635D02*
X1874084Y2071325D01*
X1873854Y2071118D01*
X1873586Y2071015D01*
X1873279Y2071118D01*
X1873049Y2071325D01*
X1872819Y2071635D01*
X1872742Y2072048D01*
Y2074115D01*
G01X1871252Y2071480D02*
X1871022Y2071222D01*
X1870754Y2071067D01*
X1870409Y2071015D01*
X1870064Y2071118D01*
X1869796Y2071325D01*
X1869604Y2071687D01*
X1869566Y2072100D01*
X1869642Y2072513D01*
X1869834Y2072772D01*
X1870102Y2072978D01*
X1870371Y2073030D01*
X1870639Y2072978D01*
X1870984Y2072772D01*
X1870869Y2074115D01*
X1869834D01*
G01X1867386Y2071015D02*
X1867309Y2071687D01*
X1867194Y2072255D01*
X1867041Y2072772D01*
X1866849Y2073340D01*
X1866542Y2074115D01*
X1868076D01*
G01X1865359Y2069982D02*
X1863059D01*
G01X1861109Y2071015D02*
Y2074115D01*
X1861569Y2073495D01*
G01Y2071015D02*
X1860649D01*
G01X1858737Y2073598D02*
X1858507Y2073908D01*
X1858239Y2074063D01*
X1857932Y2074115D01*
X1857549Y2074012D01*
X1857281Y2073753D01*
X1857204Y2073443D01*
X1857242Y2073133D01*
X1857396Y2072875D01*
X1858162Y2072358D01*
X1858507Y2071997D01*
X1858737Y2071480D01*
X1858814Y2071015D01*
X1857204D01*
G01X1883445Y2080339D02*
X1883253Y2080029D01*
X1883023Y2079822D01*
X1882755Y2079719D01*
X1882448Y2079822D01*
X1882218Y2080029D01*
X1881988Y2080339D01*
X1881911Y2080752D01*
Y2082819D01*
G01X1880421Y2080184D02*
X1880191Y2079926D01*
X1879923Y2079771D01*
X1879578Y2079719D01*
X1879233Y2079822D01*
X1878965Y2080029D01*
X1878773Y2080391D01*
X1878735Y2080804D01*
X1878811Y2081217D01*
X1879003Y2081476D01*
X1879271Y2081682D01*
X1879540Y2081734D01*
X1879808Y2081682D01*
X1880153Y2081476D01*
X1880038Y2082819D01*
X1879003D01*
G01X1876478Y2079719D02*
X1876210Y2079771D01*
X1875903Y2079926D01*
X1875711Y2080184D01*
X1875635Y2080546D01*
X1875711Y2080907D01*
X1875941Y2081217D01*
X1876286Y2081372D01*
X1876670D01*
X1876900Y2081476D01*
X1877091Y2081734D01*
X1877168Y2082096D01*
X1877053Y2082457D01*
X1876785Y2082716D01*
X1876478Y2082819D01*
X1876171Y2082716D01*
X1875903Y2082457D01*
X1875788Y2082096D01*
X1875865Y2081734D01*
X1876056Y2081476D01*
X1876286Y2081372D01*
X1876670D01*
X1877015Y2081217D01*
X1877245Y2080907D01*
X1877321Y2080546D01*
X1877245Y2080184D01*
X1877053Y2079926D01*
X1876746Y2079771D01*
X1876478Y2079719D01*
G01X1874528Y2078686D02*
X1872228D01*
G01X1870278Y2079719D02*
Y2082819D01*
X1870738Y2082199D01*
G01Y2079719D02*
X1869818D01*
G01X1867906Y2082302D02*
X1867676Y2082612D01*
X1867408Y2082767D01*
X1867101Y2082819D01*
X1866718Y2082716D01*
X1866450Y2082457D01*
X1866373Y2082147D01*
X1866411Y2081837D01*
X1866565Y2081579D01*
X1867331Y2081062D01*
X1867676Y2080701D01*
X1867906Y2080184D01*
X1867983Y2079719D01*
X1866373D01*
G01X1873814Y2075104D02*
X1873622Y2074794D01*
X1873392Y2074587D01*
X1873124Y2074484D01*
X1872817Y2074587D01*
X1872587Y2074794D01*
X1872357Y2075104D01*
X1872280Y2075517D01*
Y2077584D01*
G01X1869947Y2074484D02*
Y2077584D01*
X1870407Y2076964D01*
G01Y2074484D02*
X1869487D01*
G01X1867499Y2074846D02*
X1867230Y2074587D01*
X1866924Y2074484D01*
X1866617Y2074587D01*
X1866349Y2074897D01*
X1866157Y2075362D01*
X1866080Y2075827D01*
Y2076396D01*
X1866157Y2076861D01*
X1866349Y2077274D01*
X1866579Y2077481D01*
X1866847Y2077584D01*
X1867154Y2077481D01*
X1867384Y2077274D01*
X1867537Y2076964D01*
X1867614Y2076551D01*
X1867537Y2076189D01*
X1867345Y2075827D01*
X1867115Y2075621D01*
X1866847Y2075569D01*
X1866540Y2075672D01*
X1866310Y2075931D01*
X1866080Y2076396D01*
G01X1864897Y2073451D02*
X1862597D01*
G01X1860647Y2074484D02*
Y2077584D01*
X1861107Y2076964D01*
G01Y2074484D02*
X1860187D01*
G01X1858275Y2077067D02*
X1858045Y2077377D01*
X1857777Y2077532D01*
X1857470Y2077584D01*
X1857087Y2077481D01*
X1856819Y2077222D01*
X1856742Y2076912D01*
X1856780Y2076602D01*
X1856934Y2076344D01*
X1857700Y2075827D01*
X1858045Y2075466D01*
X1858275Y2074949D01*
X1858352Y2074484D01*
X1856742D01*
G01X1883051Y2151405D02*
X1882859Y2151095D01*
X1882629Y2150888D01*
X1882361Y2150785D01*
X1882054Y2150888D01*
X1881824Y2151095D01*
X1881594Y2151405D01*
X1881517Y2151818D01*
Y2153885D01*
G01X1878724Y2150785D02*
Y2153885D01*
X1880142Y2151663D01*
X1878226D01*
G01X1876084Y2150785D02*
Y2153885D01*
X1876544Y2153265D01*
G01Y2150785D02*
X1875624D01*
G01X1874134Y2149752D02*
X1871834D01*
G01X1869884Y2150785D02*
X1870191Y2150837D01*
X1870459Y2151043D01*
X1870689Y2151353D01*
X1870842Y2151715D01*
X1870919Y2152128D01*
Y2152542D01*
X1870842Y2152955D01*
X1870689Y2153317D01*
X1870459Y2153627D01*
X1870191Y2153833D01*
X1869884Y2153885D01*
X1869577Y2153833D01*
X1869309Y2153627D01*
X1869079Y2153317D01*
X1868926Y2152955D01*
X1868849Y2152542D01*
Y2152128D01*
X1868926Y2151715D01*
X1869079Y2151353D01*
X1869309Y2151043D01*
X1869577Y2150837D01*
X1869884Y2150785D01*
G01X1866784Y2153885D02*
Y2150785D01*
G01X1867666Y2153885D02*
X1865902D01*
G01X1864489Y2150785D02*
Y2153885D01*
G01X1862879D02*
Y2150785D01*
G01Y2152335D02*
X1864489D01*
G01X1893151Y2164045D02*
X1892844Y2163787D01*
X1892499Y2163632D01*
X1892193D01*
X1891886Y2163787D01*
X1891656Y2164045D01*
X1891541Y2164407D01*
X1891618Y2164769D01*
X1891809Y2165079D01*
X1892154Y2165285D01*
X1892614Y2165389D01*
X1892883Y2165595D01*
X1892998Y2165957D01*
X1892921Y2166319D01*
X1892729Y2166577D01*
X1892461Y2166732D01*
X1892193D01*
X1891924Y2166629D01*
X1891694Y2166370D01*
G01X1888403Y2166474D02*
X1888633Y2166629D01*
X1888901Y2166732D01*
X1889208D01*
X1889553Y2166577D01*
X1889821Y2166319D01*
X1890013Y2166009D01*
X1890166Y2165492D01*
X1890204Y2165027D01*
X1890128Y2164562D01*
X1890013Y2164252D01*
X1889783Y2163942D01*
X1889514Y2163735D01*
X1889246Y2163632D01*
X1888978D01*
X1888709Y2163735D01*
X1888479Y2163890D01*
X1888288Y2164097D01*
G01X1886913Y2163632D02*
Y2166732D01*
X1885954D01*
X1885648Y2166577D01*
X1885456Y2166370D01*
X1885379Y2165957D01*
X1885456Y2165544D01*
X1885686Y2165285D01*
X1885954Y2165130D01*
X1886913D01*
G01X1885954D02*
X1885379Y2163632D01*
G01X1882279D02*
X1883813D01*
Y2166732D01*
X1882279D01*
G01X1882893Y2165234D02*
X1883813D01*
G01X1881096Y2166732D02*
X1880559Y2163632D01*
X1879946Y2166732D01*
X1879333Y2163632D01*
X1878796Y2166732D01*
G01X1877996Y2162599D02*
X1875696D01*
G01X1874551Y2164045D02*
X1874244Y2163787D01*
X1873899Y2163632D01*
X1873593D01*
X1873286Y2163787D01*
X1873056Y2164045D01*
X1872941Y2164407D01*
X1873018Y2164769D01*
X1873209Y2165079D01*
X1873554Y2165285D01*
X1874014Y2165389D01*
X1874283Y2165595D01*
X1874398Y2165957D01*
X1874321Y2166319D01*
X1874129Y2166577D01*
X1873861Y2166732D01*
X1873593D01*
X1873324Y2166629D01*
X1873094Y2166370D01*
G01X1871451Y2164045D02*
X1871144Y2163787D01*
X1870799Y2163632D01*
X1870493D01*
X1870186Y2163787D01*
X1869956Y2164045D01*
X1869841Y2164407D01*
X1869918Y2164769D01*
X1870109Y2165079D01*
X1870454Y2165285D01*
X1870914Y2165389D01*
X1871183Y2165595D01*
X1871298Y2165957D01*
X1871221Y2166319D01*
X1871029Y2166577D01*
X1870761Y2166732D01*
X1870493D01*
X1870224Y2166629D01*
X1869994Y2166370D01*
G01X1868389Y2163632D02*
Y2166732D01*
X1867623D01*
X1867316Y2166577D01*
X1867086Y2166370D01*
X1866894Y2166060D01*
X1866741Y2165699D01*
X1866703Y2165182D01*
X1866741Y2164665D01*
X1866894Y2164304D01*
X1867086Y2163994D01*
X1867316Y2163787D01*
X1867623Y2163632D01*
X1868389D01*
G01X1864446D02*
X1864178Y2163684D01*
X1863871Y2163839D01*
X1863679Y2164097D01*
X1863603Y2164459D01*
X1863679Y2164820D01*
X1863909Y2165130D01*
X1864254Y2165285D01*
X1864638D01*
X1864868Y2165389D01*
X1865059Y2165647D01*
X1865136Y2166009D01*
X1865021Y2166370D01*
X1864753Y2166629D01*
X1864446Y2166732D01*
X1864139Y2166629D01*
X1863871Y2166370D01*
X1863756Y2166009D01*
X1863833Y2165647D01*
X1864024Y2165389D01*
X1864254Y2165285D01*
X1864638D01*
X1864983Y2165130D01*
X1865213Y2164820D01*
X1865289Y2164459D01*
X1865213Y2164097D01*
X1865021Y2163839D01*
X1864714Y2163684D01*
X1864446Y2163632D01*
G01X1862496Y2162599D02*
X1860196D01*
G01X1858246Y2163632D02*
Y2166732D01*
X1858706Y2166112D01*
G01Y2163632D02*
X1857786D01*
G01X1871132Y2177940D02*
X1868032D01*
G01Y2176330D02*
X1871132D01*
G01X1869582D02*
Y2177940D01*
G01X1870719Y2174840D02*
X1870977Y2174533D01*
X1871132Y2174188D01*
Y2173882D01*
X1870977Y2173575D01*
X1870719Y2173345D01*
X1870357Y2173230D01*
X1869995Y2173307D01*
X1869685Y2173498D01*
X1869479Y2173843D01*
X1869375Y2174303D01*
X1869169Y2174572D01*
X1868807Y2174687D01*
X1868445Y2174610D01*
X1868187Y2174418D01*
X1868032Y2174150D01*
Y2173882D01*
X1868135Y2173613D01*
X1868394Y2173383D01*
G01X1872165Y2172085D02*
Y2169785D01*
G01X1869479Y2167528D02*
X1869324Y2167375D01*
X1869065Y2167260D01*
X1868704Y2167183D01*
X1868394Y2167260D01*
X1868187Y2167413D01*
X1868032Y2167682D01*
Y2168717D01*
X1871132D01*
Y2167452D01*
X1870925Y2167183D01*
X1870615Y2167030D01*
X1870254Y2166953D01*
X1869892Y2167030D01*
X1869582Y2167260D01*
X1869479Y2167528D01*
Y2168717D01*
G01X1871132Y2165502D02*
X1868032D01*
Y2164582D01*
X1868187Y2164275D01*
X1868549Y2164045D01*
X1868962Y2163968D01*
X1869375Y2164045D01*
X1869685Y2164237D01*
X1869840Y2164582D01*
Y2165502D01*
G01X1868549Y2162363D02*
X1868239Y2162133D01*
X1868084Y2161865D01*
X1868032Y2161558D01*
X1868135Y2161175D01*
X1868394Y2160907D01*
X1868704Y2160830D01*
X1869014Y2160868D01*
X1869272Y2161022D01*
X1869789Y2161788D01*
X1870150Y2162133D01*
X1870667Y2162363D01*
X1871132Y2162440D01*
Y2160830D01*
G01X1889889Y2168666D02*
X1889697Y2168356D01*
X1889467Y2168149D01*
X1889199Y2168046D01*
X1888892Y2168149D01*
X1888662Y2168356D01*
X1888432Y2168666D01*
X1888355Y2169079D01*
Y2171146D01*
G01X1885562Y2168046D02*
Y2171146D01*
X1886980Y2168924D01*
X1885064D01*
G01X1883765Y2168666D02*
X1883535Y2168304D01*
X1883229Y2168098D01*
X1882884Y2168046D01*
X1882577Y2168098D01*
X1882270Y2168356D01*
X1882079Y2168666D01*
X1882040Y2168976D01*
X1882117Y2169338D01*
X1882385Y2169596D01*
X1882654Y2169699D01*
X1882999D01*
G01X1882654D02*
X1882424Y2169854D01*
X1882232Y2170113D01*
X1882155Y2170423D01*
X1882232Y2170733D01*
X1882424Y2170991D01*
X1882769Y2171146D01*
X1883114Y2171094D01*
X1883459Y2170888D01*
G01X1880972Y2167013D02*
X1878672D01*
G01X1876722Y2168046D02*
X1877029Y2168098D01*
X1877297Y2168304D01*
X1877527Y2168614D01*
X1877680Y2168976D01*
X1877757Y2169389D01*
Y2169803D01*
X1877680Y2170216D01*
X1877527Y2170578D01*
X1877297Y2170888D01*
X1877029Y2171094D01*
X1876722Y2171146D01*
X1876415Y2171094D01*
X1876147Y2170888D01*
X1875917Y2170578D01*
X1875764Y2170216D01*
X1875687Y2169803D01*
Y2169389D01*
X1875764Y2168976D01*
X1875917Y2168614D01*
X1876147Y2168304D01*
X1876415Y2168098D01*
X1876722Y2168046D01*
G01X1873622Y2171146D02*
Y2168046D01*
G01X1874504Y2171146D02*
X1872740D01*
G01X1871327Y2168046D02*
Y2171146D01*
G01X1869717D02*
Y2168046D01*
G01Y2169596D02*
X1871327D01*
G01X1897433Y2178615D02*
X1897126Y2178357D01*
X1896781Y2178202D01*
X1896475D01*
X1896168Y2178357D01*
X1895938Y2178615D01*
X1895823Y2178977D01*
X1895900Y2179339D01*
X1896091Y2179649D01*
X1896436Y2179855D01*
X1896896Y2179959D01*
X1897165Y2180165D01*
X1897280Y2180527D01*
X1897203Y2180889D01*
X1897011Y2181147D01*
X1896743Y2181302D01*
X1896475D01*
X1896206Y2181199D01*
X1895976Y2180940D01*
G01X1892685Y2181044D02*
X1892915Y2181199D01*
X1893183Y2181302D01*
X1893490D01*
X1893835Y2181147D01*
X1894103Y2180889D01*
X1894295Y2180579D01*
X1894448Y2180062D01*
X1894486Y2179597D01*
X1894410Y2179132D01*
X1894295Y2178822D01*
X1894065Y2178512D01*
X1893796Y2178305D01*
X1893528Y2178202D01*
X1893260D01*
X1892991Y2178305D01*
X1892761Y2178460D01*
X1892570Y2178667D01*
G01X1891195Y2178202D02*
Y2181302D01*
X1890236D01*
X1889930Y2181147D01*
X1889738Y2180940D01*
X1889661Y2180527D01*
X1889738Y2180114D01*
X1889968Y2179855D01*
X1890236Y2179700D01*
X1891195D01*
G01X1890236D02*
X1889661Y2178202D01*
G01X1886561D02*
X1888095D01*
Y2181302D01*
X1886561D01*
G01X1887175Y2179804D02*
X1888095D01*
G01X1885378Y2181302D02*
X1884841Y2178202D01*
X1884228Y2181302D01*
X1883615Y2178202D01*
X1883078Y2181302D01*
G01X1882278Y2177169D02*
X1879978D01*
G01X1878833Y2178615D02*
X1878526Y2178357D01*
X1878181Y2178202D01*
X1877875D01*
X1877568Y2178357D01*
X1877338Y2178615D01*
X1877223Y2178977D01*
X1877300Y2179339D01*
X1877491Y2179649D01*
X1877836Y2179855D01*
X1878296Y2179959D01*
X1878565Y2180165D01*
X1878680Y2180527D01*
X1878603Y2180889D01*
X1878411Y2181147D01*
X1878143Y2181302D01*
X1877875D01*
X1877606Y2181199D01*
X1877376Y2180940D01*
G01X1875733Y2178615D02*
X1875426Y2178357D01*
X1875081Y2178202D01*
X1874775D01*
X1874468Y2178357D01*
X1874238Y2178615D01*
X1874123Y2178977D01*
X1874200Y2179339D01*
X1874391Y2179649D01*
X1874736Y2179855D01*
X1875196Y2179959D01*
X1875465Y2180165D01*
X1875580Y2180527D01*
X1875503Y2180889D01*
X1875311Y2181147D01*
X1875043Y2181302D01*
X1874775D01*
X1874506Y2181199D01*
X1874276Y2180940D01*
G01X1872671Y2178202D02*
Y2181302D01*
X1871905D01*
X1871598Y2181147D01*
X1871368Y2180940D01*
X1871176Y2180630D01*
X1871023Y2180269D01*
X1870985Y2179752D01*
X1871023Y2179235D01*
X1871176Y2178874D01*
X1871368Y2178564D01*
X1871598Y2178357D01*
X1871905Y2178202D01*
X1872671D01*
G01X1868728D02*
Y2181302D01*
X1869188Y2180682D01*
G01Y2178202D02*
X1868268D01*
G01X1865628D02*
Y2181302D01*
X1866088Y2180682D01*
G01Y2178202D02*
X1865168D01*
G01X1863678Y2177169D02*
X1861378D01*
G01X1859428Y2178202D02*
Y2181302D01*
X1859888Y2180682D01*
G01Y2178202D02*
X1858968D01*
G01X1860747Y2182375D02*
X1857647D01*
G01Y2180765D02*
X1860747D01*
G01X1859197D02*
Y2182375D01*
G01X1860334Y2179275D02*
X1860592Y2178968D01*
X1860747Y2178623D01*
Y2178317D01*
X1860592Y2178010D01*
X1860334Y2177780D01*
X1859972Y2177665D01*
X1859610Y2177742D01*
X1859300Y2177933D01*
X1859094Y2178278D01*
X1858990Y2178738D01*
X1858784Y2179007D01*
X1858422Y2179122D01*
X1858060Y2179045D01*
X1857802Y2178853D01*
X1857647Y2178585D01*
Y2178317D01*
X1857750Y2178048D01*
X1858009Y2177818D01*
G01X1861780Y2176520D02*
Y2174220D01*
G01X1859094Y2171963D02*
X1858939Y2171810D01*
X1858680Y2171695D01*
X1858319Y2171618D01*
X1858009Y2171695D01*
X1857802Y2171848D01*
X1857647Y2172117D01*
Y2173152D01*
X1860747D01*
Y2171887D01*
X1860540Y2171618D01*
X1860230Y2171465D01*
X1859869Y2171388D01*
X1859507Y2171465D01*
X1859197Y2171695D01*
X1859094Y2171963D01*
Y2173152D01*
G01X1860747Y2169937D02*
X1857647D01*
Y2169017D01*
X1857802Y2168710D01*
X1858164Y2168480D01*
X1858577Y2168403D01*
X1858990Y2168480D01*
X1859300Y2168672D01*
X1859455Y2169017D01*
Y2169937D01*
G01X1860747Y2166070D02*
X1857647D01*
X1858267Y2166530D01*
G01X1860747D02*
Y2165610D01*
G01X1917160Y2057653D02*
X1916853Y2057395D01*
X1916508Y2057240D01*
X1916202D01*
X1915895Y2057395D01*
X1915665Y2057653D01*
X1915550Y2058015D01*
X1915627Y2058377D01*
X1915818Y2058687D01*
X1916163Y2058893D01*
X1916623Y2058997D01*
X1916892Y2059203D01*
X1917007Y2059565D01*
X1916930Y2059927D01*
X1916738Y2060185D01*
X1916470Y2060340D01*
X1916202D01*
X1915933Y2060237D01*
X1915703Y2059978D01*
G01X1912412Y2060082D02*
X1912642Y2060237D01*
X1912910Y2060340D01*
X1913217D01*
X1913562Y2060185D01*
X1913830Y2059927D01*
X1914022Y2059617D01*
X1914175Y2059100D01*
X1914213Y2058635D01*
X1914137Y2058170D01*
X1914022Y2057860D01*
X1913792Y2057550D01*
X1913523Y2057343D01*
X1913255Y2057240D01*
X1912987D01*
X1912718Y2057343D01*
X1912488Y2057498D01*
X1912297Y2057705D01*
G01X1910922Y2057240D02*
Y2060340D01*
X1909963D01*
X1909657Y2060185D01*
X1909465Y2059978D01*
X1909388Y2059565D01*
X1909465Y2059152D01*
X1909695Y2058893D01*
X1909963Y2058738D01*
X1910922D01*
G01X1909963D02*
X1909388Y2057240D01*
G01X1906288D02*
X1907822D01*
Y2060340D01*
X1906288D01*
G01X1906902Y2058842D02*
X1907822D01*
G01X1905105Y2060340D02*
X1904568Y2057240D01*
X1903955Y2060340D01*
X1903342Y2057240D01*
X1902805Y2060340D01*
G01X1902005Y2056207D02*
X1899705D01*
G01X1898560Y2057653D02*
X1898253Y2057395D01*
X1897908Y2057240D01*
X1897602D01*
X1897295Y2057395D01*
X1897065Y2057653D01*
X1896950Y2058015D01*
X1897027Y2058377D01*
X1897218Y2058687D01*
X1897563Y2058893D01*
X1898023Y2058997D01*
X1898292Y2059203D01*
X1898407Y2059565D01*
X1898330Y2059927D01*
X1898138Y2060185D01*
X1897870Y2060340D01*
X1897602D01*
X1897333Y2060237D01*
X1897103Y2059978D01*
G01X1895460Y2057653D02*
X1895153Y2057395D01*
X1894808Y2057240D01*
X1894502D01*
X1894195Y2057395D01*
X1893965Y2057653D01*
X1893850Y2058015D01*
X1893927Y2058377D01*
X1894118Y2058687D01*
X1894463Y2058893D01*
X1894923Y2058997D01*
X1895192Y2059203D01*
X1895307Y2059565D01*
X1895230Y2059927D01*
X1895038Y2060185D01*
X1894770Y2060340D01*
X1894502D01*
X1894233Y2060237D01*
X1894003Y2059978D01*
G01X1892398Y2057240D02*
Y2060340D01*
X1891632D01*
X1891325Y2060185D01*
X1891095Y2059978D01*
X1890903Y2059668D01*
X1890750Y2059307D01*
X1890712Y2058790D01*
X1890750Y2058273D01*
X1890903Y2057912D01*
X1891095Y2057602D01*
X1891325Y2057395D01*
X1891632Y2057240D01*
X1892398D01*
G01X1887995D02*
Y2060340D01*
X1889413Y2058118D01*
X1887497D01*
G01X1886505Y2056207D02*
X1884205D01*
G01X1882255Y2057240D02*
Y2060340D01*
X1882715Y2059720D01*
G01Y2057240D02*
X1881795D01*
G01X1908860Y2057653D02*
X1908553Y2057395D01*
X1908208Y2057240D01*
X1907902D01*
X1907595Y2057395D01*
X1907365Y2057653D01*
X1907250Y2058015D01*
X1907327Y2058377D01*
X1907518Y2058687D01*
X1907863Y2058893D01*
X1908323Y2058997D01*
X1908592Y2059203D01*
X1908707Y2059565D01*
X1908630Y2059927D01*
X1908438Y2060185D01*
X1908170Y2060340D01*
X1907902D01*
X1907633Y2060237D01*
X1907403Y2059978D01*
G01X1904112Y2060082D02*
X1904342Y2060237D01*
X1904610Y2060340D01*
X1904917D01*
X1905262Y2060185D01*
X1905530Y2059927D01*
X1905722Y2059617D01*
X1905875Y2059100D01*
X1905913Y2058635D01*
X1905837Y2058170D01*
X1905722Y2057860D01*
X1905492Y2057550D01*
X1905223Y2057343D01*
X1904955Y2057240D01*
X1904687D01*
X1904418Y2057343D01*
X1904188Y2057498D01*
X1903997Y2057705D01*
G01X1902622Y2057240D02*
Y2060340D01*
X1901663D01*
X1901357Y2060185D01*
X1901165Y2059978D01*
X1901088Y2059565D01*
X1901165Y2059152D01*
X1901395Y2058893D01*
X1901663Y2058738D01*
X1902622D01*
G01X1901663D02*
X1901088Y2057240D01*
G01X1897988D02*
X1899522D01*
Y2060340D01*
X1897988D01*
G01X1898602Y2058842D02*
X1899522D01*
G01X1896805Y2060340D02*
X1896268Y2057240D01*
X1895655Y2060340D01*
X1895042Y2057240D01*
X1894505Y2060340D01*
G01X1893705Y2056207D02*
X1891405D01*
G01X1890260Y2057653D02*
X1889953Y2057395D01*
X1889608Y2057240D01*
X1889302D01*
X1888995Y2057395D01*
X1888765Y2057653D01*
X1888650Y2058015D01*
X1888727Y2058377D01*
X1888918Y2058687D01*
X1889263Y2058893D01*
X1889723Y2058997D01*
X1889992Y2059203D01*
X1890107Y2059565D01*
X1890030Y2059927D01*
X1889838Y2060185D01*
X1889570Y2060340D01*
X1889302D01*
X1889033Y2060237D01*
X1888803Y2059978D01*
G01X1887160Y2057653D02*
X1886853Y2057395D01*
X1886508Y2057240D01*
X1886202D01*
X1885895Y2057395D01*
X1885665Y2057653D01*
X1885550Y2058015D01*
X1885627Y2058377D01*
X1885818Y2058687D01*
X1886163Y2058893D01*
X1886623Y2058997D01*
X1886892Y2059203D01*
X1887007Y2059565D01*
X1886930Y2059927D01*
X1886738Y2060185D01*
X1886470Y2060340D01*
X1886202D01*
X1885933Y2060237D01*
X1885703Y2059978D01*
G01X1884098Y2057240D02*
Y2060340D01*
X1883332D01*
X1883025Y2060185D01*
X1882795Y2059978D01*
X1882603Y2059668D01*
X1882450Y2059307D01*
X1882412Y2058790D01*
X1882450Y2058273D01*
X1882603Y2057912D01*
X1882795Y2057602D01*
X1883025Y2057395D01*
X1883332Y2057240D01*
X1884098D01*
G01X1879695D02*
Y2060340D01*
X1881113Y2058118D01*
X1879197D01*
G01X1878205Y2056207D02*
X1875905D01*
G01X1874683Y2059823D02*
X1874453Y2060133D01*
X1874185Y2060288D01*
X1873878Y2060340D01*
X1873495Y2060237D01*
X1873227Y2059978D01*
X1873150Y2059668D01*
X1873188Y2059358D01*
X1873342Y2059100D01*
X1874108Y2058583D01*
X1874453Y2058222D01*
X1874683Y2057705D01*
X1874760Y2057240D01*
X1873150D01*
G01X1921160Y2072470D02*
X1920853Y2072212D01*
X1920508Y2072057D01*
X1920202D01*
X1919895Y2072212D01*
X1919665Y2072470D01*
X1919550Y2072832D01*
X1919627Y2073194D01*
X1919818Y2073504D01*
X1920163Y2073710D01*
X1920623Y2073814D01*
X1920892Y2074020D01*
X1921007Y2074382D01*
X1920930Y2074744D01*
X1920738Y2075002D01*
X1920470Y2075157D01*
X1920202D01*
X1919933Y2075054D01*
X1919703Y2074795D01*
G01X1916412Y2074899D02*
X1916642Y2075054D01*
X1916910Y2075157D01*
X1917217D01*
X1917562Y2075002D01*
X1917830Y2074744D01*
X1918022Y2074434D01*
X1918175Y2073917D01*
X1918213Y2073452D01*
X1918137Y2072987D01*
X1918022Y2072677D01*
X1917792Y2072367D01*
X1917523Y2072160D01*
X1917255Y2072057D01*
X1916987D01*
X1916718Y2072160D01*
X1916488Y2072315D01*
X1916297Y2072522D01*
G01X1914922Y2072057D02*
Y2075157D01*
X1913963D01*
X1913657Y2075002D01*
X1913465Y2074795D01*
X1913388Y2074382D01*
X1913465Y2073969D01*
X1913695Y2073710D01*
X1913963Y2073555D01*
X1914922D01*
G01X1913963D02*
X1913388Y2072057D01*
G01X1910288D02*
X1911822D01*
Y2075157D01*
X1910288D01*
G01X1910902Y2073659D02*
X1911822D01*
G01X1909105Y2075157D02*
X1908568Y2072057D01*
X1907955Y2075157D01*
X1907342Y2072057D01*
X1906805Y2075157D01*
G01X1906005Y2071024D02*
X1903705D01*
G01X1902560Y2072470D02*
X1902253Y2072212D01*
X1901908Y2072057D01*
X1901602D01*
X1901295Y2072212D01*
X1901065Y2072470D01*
X1900950Y2072832D01*
X1901027Y2073194D01*
X1901218Y2073504D01*
X1901563Y2073710D01*
X1902023Y2073814D01*
X1902292Y2074020D01*
X1902407Y2074382D01*
X1902330Y2074744D01*
X1902138Y2075002D01*
X1901870Y2075157D01*
X1901602D01*
X1901333Y2075054D01*
X1901103Y2074795D01*
G01X1899460Y2072470D02*
X1899153Y2072212D01*
X1898808Y2072057D01*
X1898502D01*
X1898195Y2072212D01*
X1897965Y2072470D01*
X1897850Y2072832D01*
X1897927Y2073194D01*
X1898118Y2073504D01*
X1898463Y2073710D01*
X1898923Y2073814D01*
X1899192Y2074020D01*
X1899307Y2074382D01*
X1899230Y2074744D01*
X1899038Y2075002D01*
X1898770Y2075157D01*
X1898502D01*
X1898233Y2075054D01*
X1898003Y2074795D01*
G01X1896398Y2072057D02*
Y2075157D01*
X1895632D01*
X1895325Y2075002D01*
X1895095Y2074795D01*
X1894903Y2074485D01*
X1894750Y2074124D01*
X1894712Y2073607D01*
X1894750Y2073090D01*
X1894903Y2072729D01*
X1895095Y2072419D01*
X1895325Y2072212D01*
X1895632Y2072057D01*
X1896398D01*
G01X1893183Y2074640D02*
X1892953Y2074950D01*
X1892685Y2075105D01*
X1892378Y2075157D01*
X1891995Y2075054D01*
X1891727Y2074795D01*
X1891650Y2074485D01*
X1891688Y2074175D01*
X1891842Y2073917D01*
X1892608Y2073400D01*
X1892953Y2073039D01*
X1893183Y2072522D01*
X1893260Y2072057D01*
X1891650D01*
G01X1890505Y2071024D02*
X1888205D01*
G01X1886255Y2072057D02*
Y2075157D01*
X1886715Y2074537D01*
G01Y2072057D02*
X1885795D01*
G01X1912860Y2072470D02*
X1912553Y2072212D01*
X1912208Y2072057D01*
X1911902D01*
X1911595Y2072212D01*
X1911365Y2072470D01*
X1911250Y2072832D01*
X1911327Y2073194D01*
X1911518Y2073504D01*
X1911863Y2073710D01*
X1912323Y2073814D01*
X1912592Y2074020D01*
X1912707Y2074382D01*
X1912630Y2074744D01*
X1912438Y2075002D01*
X1912170Y2075157D01*
X1911902D01*
X1911633Y2075054D01*
X1911403Y2074795D01*
G01X1908112Y2074899D02*
X1908342Y2075054D01*
X1908610Y2075157D01*
X1908917D01*
X1909262Y2075002D01*
X1909530Y2074744D01*
X1909722Y2074434D01*
X1909875Y2073917D01*
X1909913Y2073452D01*
X1909837Y2072987D01*
X1909722Y2072677D01*
X1909492Y2072367D01*
X1909223Y2072160D01*
X1908955Y2072057D01*
X1908687D01*
X1908418Y2072160D01*
X1908188Y2072315D01*
X1907997Y2072522D01*
G01X1906622Y2072057D02*
Y2075157D01*
X1905663D01*
X1905357Y2075002D01*
X1905165Y2074795D01*
X1905088Y2074382D01*
X1905165Y2073969D01*
X1905395Y2073710D01*
X1905663Y2073555D01*
X1906622D01*
G01X1905663D02*
X1905088Y2072057D01*
G01X1901988D02*
X1903522D01*
Y2075157D01*
X1901988D01*
G01X1902602Y2073659D02*
X1903522D01*
G01X1900805Y2075157D02*
X1900268Y2072057D01*
X1899655Y2075157D01*
X1899042Y2072057D01*
X1898505Y2075157D01*
G01X1897705Y2071024D02*
X1895405D01*
G01X1894260Y2072470D02*
X1893953Y2072212D01*
X1893608Y2072057D01*
X1893302D01*
X1892995Y2072212D01*
X1892765Y2072470D01*
X1892650Y2072832D01*
X1892727Y2073194D01*
X1892918Y2073504D01*
X1893263Y2073710D01*
X1893723Y2073814D01*
X1893992Y2074020D01*
X1894107Y2074382D01*
X1894030Y2074744D01*
X1893838Y2075002D01*
X1893570Y2075157D01*
X1893302D01*
X1893033Y2075054D01*
X1892803Y2074795D01*
G01X1891160Y2072470D02*
X1890853Y2072212D01*
X1890508Y2072057D01*
X1890202D01*
X1889895Y2072212D01*
X1889665Y2072470D01*
X1889550Y2072832D01*
X1889627Y2073194D01*
X1889818Y2073504D01*
X1890163Y2073710D01*
X1890623Y2073814D01*
X1890892Y2074020D01*
X1891007Y2074382D01*
X1890930Y2074744D01*
X1890738Y2075002D01*
X1890470Y2075157D01*
X1890202D01*
X1889933Y2075054D01*
X1889703Y2074795D01*
G01X1888098Y2072057D02*
Y2075157D01*
X1887332D01*
X1887025Y2075002D01*
X1886795Y2074795D01*
X1886603Y2074485D01*
X1886450Y2074124D01*
X1886412Y2073607D01*
X1886450Y2073090D01*
X1886603Y2072729D01*
X1886795Y2072419D01*
X1887025Y2072212D01*
X1887332Y2072057D01*
X1888098D01*
G01X1884883Y2074640D02*
X1884653Y2074950D01*
X1884385Y2075105D01*
X1884078Y2075157D01*
X1883695Y2075054D01*
X1883427Y2074795D01*
X1883350Y2074485D01*
X1883388Y2074175D01*
X1883542Y2073917D01*
X1884308Y2073400D01*
X1884653Y2073039D01*
X1884883Y2072522D01*
X1884960Y2072057D01*
X1883350D01*
G01X1882205Y2071024D02*
X1879905D01*
G01X1878683Y2074640D02*
X1878453Y2074950D01*
X1878185Y2075105D01*
X1877878Y2075157D01*
X1877495Y2075054D01*
X1877227Y2074795D01*
X1877150Y2074485D01*
X1877188Y2074175D01*
X1877342Y2073917D01*
X1878108Y2073400D01*
X1878453Y2073039D01*
X1878683Y2072522D01*
X1878760Y2072057D01*
X1877150D01*
G01X1925990Y2148912D02*
X1925683Y2148654D01*
X1925338Y2148499D01*
X1925032D01*
X1924725Y2148654D01*
X1924495Y2148912D01*
X1924380Y2149274D01*
X1924457Y2149636D01*
X1924648Y2149946D01*
X1924993Y2150152D01*
X1925453Y2150256D01*
X1925722Y2150462D01*
X1925837Y2150824D01*
X1925760Y2151186D01*
X1925568Y2151444D01*
X1925300Y2151599D01*
X1925032D01*
X1924763Y2151496D01*
X1924533Y2151237D01*
G01X1921242Y2151341D02*
X1921472Y2151496D01*
X1921740Y2151599D01*
X1922047D01*
X1922392Y2151444D01*
X1922660Y2151186D01*
X1922852Y2150876D01*
X1923005Y2150359D01*
X1923043Y2149894D01*
X1922967Y2149429D01*
X1922852Y2149119D01*
X1922622Y2148809D01*
X1922353Y2148602D01*
X1922085Y2148499D01*
X1921817D01*
X1921548Y2148602D01*
X1921318Y2148757D01*
X1921127Y2148964D01*
G01X1919752Y2148499D02*
Y2151599D01*
X1918793D01*
X1918487Y2151444D01*
X1918295Y2151237D01*
X1918218Y2150824D01*
X1918295Y2150411D01*
X1918525Y2150152D01*
X1918793Y2149997D01*
X1919752D01*
G01X1918793D02*
X1918218Y2148499D01*
G01X1915118D02*
X1916652D01*
Y2151599D01*
X1915118D01*
G01X1915732Y2150101D02*
X1916652D01*
G01X1913935Y2151599D02*
X1913398Y2148499D01*
X1912785Y2151599D01*
X1912172Y2148499D01*
X1911635Y2151599D01*
G01X1910835Y2147466D02*
X1908535D01*
G01X1907390Y2148912D02*
X1907083Y2148654D01*
X1906738Y2148499D01*
X1906432D01*
X1906125Y2148654D01*
X1905895Y2148912D01*
X1905780Y2149274D01*
X1905857Y2149636D01*
X1906048Y2149946D01*
X1906393Y2150152D01*
X1906853Y2150256D01*
X1907122Y2150462D01*
X1907237Y2150824D01*
X1907160Y2151186D01*
X1906968Y2151444D01*
X1906700Y2151599D01*
X1906432D01*
X1906163Y2151496D01*
X1905933Y2151237D01*
G01X1904290Y2148912D02*
X1903983Y2148654D01*
X1903638Y2148499D01*
X1903332D01*
X1903025Y2148654D01*
X1902795Y2148912D01*
X1902680Y2149274D01*
X1902757Y2149636D01*
X1902948Y2149946D01*
X1903293Y2150152D01*
X1903753Y2150256D01*
X1904022Y2150462D01*
X1904137Y2150824D01*
X1904060Y2151186D01*
X1903868Y2151444D01*
X1903600Y2151599D01*
X1903332D01*
X1903063Y2151496D01*
X1902833Y2151237D01*
G01X1901228Y2148499D02*
Y2151599D01*
X1900462D01*
X1900155Y2151444D01*
X1899925Y2151237D01*
X1899733Y2150927D01*
X1899580Y2150566D01*
X1899542Y2150049D01*
X1899580Y2149532D01*
X1899733Y2149171D01*
X1899925Y2148861D01*
X1900155Y2148654D01*
X1900462Y2148499D01*
X1901228D01*
G01X1897285D02*
Y2151599D01*
X1897745Y2150979D01*
G01Y2148499D02*
X1896825D01*
G01X1895028Y2148964D02*
X1894798Y2148706D01*
X1894530Y2148551D01*
X1894185Y2148499D01*
X1893840Y2148602D01*
X1893572Y2148809D01*
X1893380Y2149171D01*
X1893342Y2149584D01*
X1893418Y2149997D01*
X1893610Y2150256D01*
X1893878Y2150462D01*
X1894147Y2150514D01*
X1894415Y2150462D01*
X1894760Y2150256D01*
X1894645Y2151599D01*
X1893610D01*
G01X1892235Y2147466D02*
X1889935D01*
G01X1888713Y2151082D02*
X1888483Y2151392D01*
X1888215Y2151547D01*
X1887908Y2151599D01*
X1887525Y2151496D01*
X1887257Y2151237D01*
X1887180Y2150927D01*
X1887218Y2150617D01*
X1887372Y2150359D01*
X1888138Y2149842D01*
X1888483Y2149481D01*
X1888713Y2148964D01*
X1888790Y2148499D01*
X1887180D01*
G01X1905789Y2168666D02*
X1905597Y2168356D01*
X1905367Y2168149D01*
X1905099Y2168046D01*
X1904792Y2168149D01*
X1904562Y2168356D01*
X1904332Y2168666D01*
X1904255Y2169079D01*
Y2171146D01*
G01X1901462Y2168046D02*
Y2171146D01*
X1902880Y2168924D01*
X1900964D01*
G01X1899550Y2170629D02*
X1899320Y2170939D01*
X1899052Y2171094D01*
X1898745Y2171146D01*
X1898362Y2171043D01*
X1898094Y2170784D01*
X1898017Y2170474D01*
X1898055Y2170164D01*
X1898209Y2169906D01*
X1898975Y2169389D01*
X1899320Y2169028D01*
X1899550Y2168511D01*
X1899627Y2168046D01*
X1898017D01*
G01X1896872Y2167013D02*
X1894572D01*
G01X1892622Y2168046D02*
X1892929Y2168098D01*
X1893197Y2168304D01*
X1893427Y2168614D01*
X1893580Y2168976D01*
X1893657Y2169389D01*
Y2169803D01*
X1893580Y2170216D01*
X1893427Y2170578D01*
X1893197Y2170888D01*
X1892929Y2171094D01*
X1892622Y2171146D01*
X1892315Y2171094D01*
X1892047Y2170888D01*
X1891817Y2170578D01*
X1891664Y2170216D01*
X1891587Y2169803D01*
Y2169389D01*
X1891664Y2168976D01*
X1891817Y2168614D01*
X1892047Y2168304D01*
X1892315Y2168098D01*
X1892622Y2168046D01*
G01X1889522Y2171146D02*
Y2168046D01*
G01X1890404Y2171146D02*
X1888640D01*
G01X1887227Y2168046D02*
Y2171146D01*
G01X1885617D02*
Y2168046D01*
G01Y2169596D02*
X1887227D01*
G01X1896414Y2176874D02*
X1896222Y2176564D01*
X1895992Y2176357D01*
X1895724Y2176254D01*
X1895417Y2176357D01*
X1895187Y2176564D01*
X1894957Y2176874D01*
X1894880Y2177287D01*
Y2179354D01*
G01X1893390Y2176719D02*
X1893160Y2176461D01*
X1892892Y2176306D01*
X1892547Y2176254D01*
X1892202Y2176357D01*
X1891934Y2176564D01*
X1891742Y2176926D01*
X1891704Y2177339D01*
X1891780Y2177752D01*
X1891972Y2178011D01*
X1892240Y2178217D01*
X1892509Y2178269D01*
X1892777Y2178217D01*
X1893122Y2178011D01*
X1893007Y2179354D01*
X1891972D01*
G01X1890290Y2176719D02*
X1890060Y2176461D01*
X1889792Y2176306D01*
X1889447Y2176254D01*
X1889102Y2176357D01*
X1888834Y2176564D01*
X1888642Y2176926D01*
X1888604Y2177339D01*
X1888680Y2177752D01*
X1888872Y2178011D01*
X1889140Y2178217D01*
X1889409Y2178269D01*
X1889677Y2178217D01*
X1890022Y2178011D01*
X1889907Y2179354D01*
X1888872D01*
G01X1887497Y2175221D02*
X1885197D01*
G01X1883247Y2176254D02*
Y2179354D01*
X1883707Y2178734D01*
G01Y2176254D02*
X1882787D01*
G01X1880875Y2178837D02*
X1880645Y2179147D01*
X1880377Y2179302D01*
X1880070Y2179354D01*
X1879687Y2179251D01*
X1879419Y2178992D01*
X1879342Y2178682D01*
X1879380Y2178372D01*
X1879534Y2178114D01*
X1880300Y2177597D01*
X1880645Y2177236D01*
X1880875Y2176719D01*
X1880952Y2176254D01*
X1879342D01*
G01X1911128Y2172778D02*
X1910936Y2172468D01*
X1910706Y2172261D01*
X1910438Y2172158D01*
X1910131Y2172261D01*
X1909901Y2172468D01*
X1909671Y2172778D01*
X1909594Y2173191D01*
Y2175258D01*
G01X1908028Y2172158D02*
Y2175258D01*
X1907108D01*
X1906801Y2175103D01*
X1906571Y2174741D01*
X1906494Y2174328D01*
X1906571Y2173915D01*
X1906763Y2173605D01*
X1907108Y2173450D01*
X1908028D01*
G01X1903394Y2172158D02*
X1904928D01*
Y2175258D01*
X1903394D01*
G01X1904008Y2173760D02*
X1904928D01*
G01X1901866Y2172158D02*
X1900256Y2175258D01*
G01X1901866D02*
X1900256Y2172158D01*
G01X1897961Y2175258D02*
X1898268Y2175155D01*
X1898498Y2174896D01*
X1898651Y2174586D01*
X1898766Y2174173D01*
X1898804Y2173708D01*
X1898766Y2173243D01*
X1898651Y2172830D01*
X1898498Y2172520D01*
X1898268Y2172261D01*
X1897961Y2172158D01*
X1897654Y2172261D01*
X1897424Y2172520D01*
X1897271Y2172830D01*
X1897156Y2173243D01*
X1897118Y2173708D01*
X1897156Y2174173D01*
X1897271Y2174586D01*
X1897424Y2174896D01*
X1897654Y2175155D01*
X1897961Y2175258D01*
G01X1896011Y2171125D02*
X1893711D01*
G01X1892489Y2172158D02*
Y2175258D01*
X1891033D01*
G01X1891569Y2173760D02*
X1892489D01*
G01X1889811Y2175258D02*
X1889274Y2172158D01*
X1888661Y2175258D01*
X1888048Y2172158D01*
X1887511Y2175258D01*
G01X1885561Y2172158D02*
Y2175258D01*
X1886021Y2174638D01*
G01Y2172158D02*
X1885101D01*
G01X1910869Y2190304D02*
X1910677Y2189994D01*
X1910447Y2189787D01*
X1910179Y2189684D01*
X1909872Y2189787D01*
X1909642Y2189994D01*
X1909412Y2190304D01*
X1909335Y2190717D01*
Y2192784D01*
G01X1907769Y2189684D02*
Y2192784D01*
X1906849D01*
X1906542Y2192629D01*
X1906312Y2192267D01*
X1906235Y2191854D01*
X1906312Y2191441D01*
X1906504Y2191131D01*
X1906849Y2190976D01*
X1907769D01*
G01X1903135Y2189684D02*
X1904669D01*
Y2192784D01*
X1903135D01*
G01X1903749Y2191286D02*
X1904669D01*
G01X1901607Y2189684D02*
X1899997Y2192784D01*
G01X1901607D02*
X1899997Y2189684D01*
G01X1898545Y2190304D02*
X1898315Y2189942D01*
X1898009Y2189736D01*
X1897664Y2189684D01*
X1897357Y2189736D01*
X1897050Y2189994D01*
X1896859Y2190304D01*
X1896820Y2190614D01*
X1896897Y2190976D01*
X1897165Y2191234D01*
X1897434Y2191337D01*
X1897779D01*
G01X1897434D02*
X1897204Y2191492D01*
X1897012Y2191751D01*
X1896935Y2192061D01*
X1897012Y2192371D01*
X1897204Y2192629D01*
X1897549Y2192784D01*
X1897894Y2192732D01*
X1898239Y2192526D01*
G01X1895752Y2188651D02*
X1893452D01*
G01X1892230Y2189684D02*
Y2192784D01*
X1890774D01*
G01X1891310Y2191286D02*
X1892230D01*
G01X1889552Y2192784D02*
X1889015Y2189684D01*
X1888402Y2192784D01*
X1887789Y2189684D01*
X1887252Y2192784D01*
G01X1885302Y2189684D02*
Y2192784D01*
X1885762Y2192164D01*
G01Y2189684D02*
X1884842D01*
G01X1915935Y2048289D02*
X1915743Y2047979D01*
X1915513Y2047772D01*
X1915245Y2047669D01*
X1914938Y2047772D01*
X1914708Y2047979D01*
X1914478Y2048289D01*
X1914401Y2048702D01*
Y2050769D01*
G01X1912911Y2048289D02*
X1912681Y2047927D01*
X1912375Y2047721D01*
X1912030Y2047669D01*
X1911723Y2047721D01*
X1911416Y2047979D01*
X1911225Y2048289D01*
X1911186Y2048599D01*
X1911263Y2048961D01*
X1911531Y2049219D01*
X1911800Y2049322D01*
X1912145D01*
G01X1911800D02*
X1911570Y2049477D01*
X1911378Y2049736D01*
X1911301Y2050046D01*
X1911378Y2050356D01*
X1911570Y2050614D01*
X1911915Y2050769D01*
X1912260Y2050717D01*
X1912605Y2050511D01*
G01X1908968Y2050769D02*
X1909275Y2050666D01*
X1909505Y2050407D01*
X1909658Y2050097D01*
X1909773Y2049684D01*
X1909811Y2049219D01*
X1909773Y2048754D01*
X1909658Y2048341D01*
X1909505Y2048031D01*
X1909275Y2047772D01*
X1908968Y2047669D01*
X1908661Y2047772D01*
X1908431Y2048031D01*
X1908278Y2048341D01*
X1908163Y2048754D01*
X1908125Y2049219D01*
X1908163Y2049684D01*
X1908278Y2050097D01*
X1908431Y2050407D01*
X1908661Y2050666D01*
X1908968Y2050769D01*
G01X1907018Y2046636D02*
X1904718D01*
G01X1902768Y2047669D02*
X1903075Y2047721D01*
X1903343Y2047927D01*
X1903573Y2048237D01*
X1903726Y2048599D01*
X1903803Y2049012D01*
Y2049426D01*
X1903726Y2049839D01*
X1903573Y2050201D01*
X1903343Y2050511D01*
X1903075Y2050717D01*
X1902768Y2050769D01*
X1902461Y2050717D01*
X1902193Y2050511D01*
X1901963Y2050201D01*
X1901810Y2049839D01*
X1901733Y2049426D01*
Y2049012D01*
X1901810Y2048599D01*
X1901963Y2048237D01*
X1902193Y2047927D01*
X1902461Y2047721D01*
X1902768Y2047669D01*
G01X1899668Y2050769D02*
Y2047669D01*
G01X1900550Y2050769D02*
X1898786D01*
G01X1897373Y2047669D02*
Y2050769D01*
G01X1895763D02*
Y2047669D01*
G01Y2049219D02*
X1897373D01*
G01X1912856Y2059796D02*
X1912664Y2059486D01*
X1912434Y2059279D01*
X1912166Y2059176D01*
X1911859Y2059279D01*
X1911629Y2059486D01*
X1911399Y2059796D01*
X1911322Y2060209D01*
Y2062276D01*
G01X1909832Y2059796D02*
X1909602Y2059434D01*
X1909296Y2059228D01*
X1908951Y2059176D01*
X1908644Y2059228D01*
X1908337Y2059486D01*
X1908146Y2059796D01*
X1908107Y2060106D01*
X1908184Y2060468D01*
X1908452Y2060726D01*
X1908721Y2060829D01*
X1909066D01*
G01X1908721D02*
X1908491Y2060984D01*
X1908299Y2061243D01*
X1908222Y2061553D01*
X1908299Y2061863D01*
X1908491Y2062121D01*
X1908836Y2062276D01*
X1909181Y2062224D01*
X1909526Y2062018D01*
G01X1906732Y2059641D02*
X1906502Y2059383D01*
X1906234Y2059228D01*
X1905889Y2059176D01*
X1905544Y2059279D01*
X1905276Y2059486D01*
X1905084Y2059848D01*
X1905046Y2060261D01*
X1905122Y2060674D01*
X1905314Y2060933D01*
X1905582Y2061139D01*
X1905851Y2061191D01*
X1906119Y2061139D01*
X1906464Y2060933D01*
X1906349Y2062276D01*
X1905314D01*
G01X1903939Y2058143D02*
X1901639D01*
G01X1899689Y2059176D02*
X1899996Y2059228D01*
X1900264Y2059434D01*
X1900494Y2059744D01*
X1900647Y2060106D01*
X1900724Y2060519D01*
Y2060933D01*
X1900647Y2061346D01*
X1900494Y2061708D01*
X1900264Y2062018D01*
X1899996Y2062224D01*
X1899689Y2062276D01*
X1899382Y2062224D01*
X1899114Y2062018D01*
X1898884Y2061708D01*
X1898731Y2061346D01*
X1898654Y2060933D01*
Y2060519D01*
X1898731Y2060106D01*
X1898884Y2059744D01*
X1899114Y2059434D01*
X1899382Y2059228D01*
X1899689Y2059176D01*
G01X1896589Y2062276D02*
Y2059176D01*
G01X1897471Y2062276D02*
X1895707D01*
G01X1894294Y2059176D02*
Y2062276D01*
G01X1892684D02*
Y2059176D01*
G01Y2060726D02*
X1894294D01*
G01X1921197Y2055640D02*
X1920890Y2055382D01*
X1920545Y2055227D01*
X1920239D01*
X1919932Y2055382D01*
X1919702Y2055640D01*
X1919587Y2056002D01*
X1919664Y2056364D01*
X1919855Y2056674D01*
X1920200Y2056880D01*
X1920660Y2056984D01*
X1920929Y2057190D01*
X1921044Y2057552D01*
X1920967Y2057914D01*
X1920775Y2058172D01*
X1920507Y2058327D01*
X1920239D01*
X1919970Y2058224D01*
X1919740Y2057965D01*
G01X1916449Y2058069D02*
X1916679Y2058224D01*
X1916947Y2058327D01*
X1917254D01*
X1917599Y2058172D01*
X1917867Y2057914D01*
X1918059Y2057604D01*
X1918212Y2057087D01*
X1918250Y2056622D01*
X1918174Y2056157D01*
X1918059Y2055847D01*
X1917829Y2055537D01*
X1917560Y2055330D01*
X1917292Y2055227D01*
X1917024D01*
X1916755Y2055330D01*
X1916525Y2055485D01*
X1916334Y2055692D01*
G01X1914959Y2055227D02*
Y2058327D01*
X1914000D01*
X1913694Y2058172D01*
X1913502Y2057965D01*
X1913425Y2057552D01*
X1913502Y2057139D01*
X1913732Y2056880D01*
X1914000Y2056725D01*
X1914959D01*
G01X1914000D02*
X1913425Y2055227D01*
G01X1910325D02*
X1911859D01*
Y2058327D01*
X1910325D01*
G01X1910939Y2056829D02*
X1911859D01*
G01X1909142Y2058327D02*
X1908605Y2055227D01*
X1907992Y2058327D01*
X1907379Y2055227D01*
X1906842Y2058327D01*
G01X1906042Y2054194D02*
X1903742D01*
G01X1901869Y2055227D02*
X1901792Y2055899D01*
X1901677Y2056467D01*
X1901524Y2056984D01*
X1901332Y2057552D01*
X1901025Y2058327D01*
X1902559D01*
G01X1934290Y2148912D02*
X1933983Y2148654D01*
X1933638Y2148499D01*
X1933332D01*
X1933025Y2148654D01*
X1932795Y2148912D01*
X1932680Y2149274D01*
X1932757Y2149636D01*
X1932948Y2149946D01*
X1933293Y2150152D01*
X1933753Y2150256D01*
X1934022Y2150462D01*
X1934137Y2150824D01*
X1934060Y2151186D01*
X1933868Y2151444D01*
X1933600Y2151599D01*
X1933332D01*
X1933063Y2151496D01*
X1932833Y2151237D01*
G01X1929542Y2151341D02*
X1929772Y2151496D01*
X1930040Y2151599D01*
X1930347D01*
X1930692Y2151444D01*
X1930960Y2151186D01*
X1931152Y2150876D01*
X1931305Y2150359D01*
X1931343Y2149894D01*
X1931267Y2149429D01*
X1931152Y2149119D01*
X1930922Y2148809D01*
X1930653Y2148602D01*
X1930385Y2148499D01*
X1930117D01*
X1929848Y2148602D01*
X1929618Y2148757D01*
X1929427Y2148964D01*
G01X1928052Y2148499D02*
Y2151599D01*
X1927093D01*
X1926787Y2151444D01*
X1926595Y2151237D01*
X1926518Y2150824D01*
X1926595Y2150411D01*
X1926825Y2150152D01*
X1927093Y2149997D01*
X1928052D01*
G01X1927093D02*
X1926518Y2148499D01*
G01X1923418D02*
X1924952D01*
Y2151599D01*
X1923418D01*
G01X1924032Y2150101D02*
X1924952D01*
G01X1922235Y2151599D02*
X1921698Y2148499D01*
X1921085Y2151599D01*
X1920472Y2148499D01*
X1919935Y2151599D01*
G01X1919135Y2147466D02*
X1916835D01*
G01X1915690Y2148912D02*
X1915383Y2148654D01*
X1915038Y2148499D01*
X1914732D01*
X1914425Y2148654D01*
X1914195Y2148912D01*
X1914080Y2149274D01*
X1914157Y2149636D01*
X1914348Y2149946D01*
X1914693Y2150152D01*
X1915153Y2150256D01*
X1915422Y2150462D01*
X1915537Y2150824D01*
X1915460Y2151186D01*
X1915268Y2151444D01*
X1915000Y2151599D01*
X1914732D01*
X1914463Y2151496D01*
X1914233Y2151237D01*
G01X1912590Y2148912D02*
X1912283Y2148654D01*
X1911938Y2148499D01*
X1911632D01*
X1911325Y2148654D01*
X1911095Y2148912D01*
X1910980Y2149274D01*
X1911057Y2149636D01*
X1911248Y2149946D01*
X1911593Y2150152D01*
X1912053Y2150256D01*
X1912322Y2150462D01*
X1912437Y2150824D01*
X1912360Y2151186D01*
X1912168Y2151444D01*
X1911900Y2151599D01*
X1911632D01*
X1911363Y2151496D01*
X1911133Y2151237D01*
G01X1909528Y2148499D02*
Y2151599D01*
X1908762D01*
X1908455Y2151444D01*
X1908225Y2151237D01*
X1908033Y2150927D01*
X1907880Y2150566D01*
X1907842Y2150049D01*
X1907880Y2149532D01*
X1908033Y2149171D01*
X1908225Y2148861D01*
X1908455Y2148654D01*
X1908762Y2148499D01*
X1909528D01*
G01X1905585D02*
Y2151599D01*
X1906045Y2150979D01*
G01Y2148499D02*
X1905125D01*
G01X1903328Y2148964D02*
X1903098Y2148706D01*
X1902830Y2148551D01*
X1902485Y2148499D01*
X1902140Y2148602D01*
X1901872Y2148809D01*
X1901680Y2149171D01*
X1901642Y2149584D01*
X1901718Y2149997D01*
X1901910Y2150256D01*
X1902178Y2150462D01*
X1902447Y2150514D01*
X1902715Y2150462D01*
X1903060Y2150256D01*
X1902945Y2151599D01*
X1901910D01*
G01X1900535Y2147466D02*
X1898235D01*
G01X1896285Y2148499D02*
Y2151599D01*
X1896745Y2150979D01*
G01Y2148499D02*
X1895825D01*
G01X1922104Y2161715D02*
X1921912Y2161405D01*
X1921682Y2161198D01*
X1921414Y2161095D01*
X1921107Y2161198D01*
X1920877Y2161405D01*
X1920647Y2161715D01*
X1920570Y2162128D01*
Y2164195D01*
G01X1919004Y2161095D02*
Y2164195D01*
X1918084D01*
X1917777Y2164040D01*
X1917547Y2163678D01*
X1917470Y2163265D01*
X1917547Y2162852D01*
X1917739Y2162542D01*
X1918084Y2162387D01*
X1919004D01*
G01X1914370Y2161095D02*
X1915904D01*
Y2164195D01*
X1914370D01*
G01X1914984Y2162697D02*
X1915904D01*
G01X1912842Y2161095D02*
X1911232Y2164195D01*
G01X1912842D02*
X1911232Y2161095D01*
G01X1909665Y2163678D02*
X1909435Y2163988D01*
X1909167Y2164143D01*
X1908860Y2164195D01*
X1908477Y2164092D01*
X1908209Y2163833D01*
X1908132Y2163523D01*
X1908170Y2163213D01*
X1908324Y2162955D01*
X1909090Y2162438D01*
X1909435Y2162077D01*
X1909665Y2161560D01*
X1909742Y2161095D01*
X1908132D01*
G01X1906987Y2160062D02*
X1904687D01*
G01X1903465Y2161095D02*
Y2164195D01*
X1902009D01*
G01X1902545Y2162697D02*
X1903465D01*
G01X1900787Y2164195D02*
X1900250Y2161095D01*
X1899637Y2164195D01*
X1899024Y2161095D01*
X1898487Y2164195D01*
G01X1896537Y2161095D02*
Y2164195D01*
X1896997Y2163575D01*
G01Y2161095D02*
X1896077D01*
G01X1936027Y2172028D02*
X1935720Y2171770D01*
X1935375Y2171615D01*
X1935069D01*
X1934762Y2171770D01*
X1934532Y2172028D01*
X1934417Y2172390D01*
X1934494Y2172752D01*
X1934685Y2173062D01*
X1935030Y2173268D01*
X1935490Y2173372D01*
X1935759Y2173578D01*
X1935874Y2173940D01*
X1935797Y2174302D01*
X1935605Y2174560D01*
X1935337Y2174715D01*
X1935069D01*
X1934800Y2174612D01*
X1934570Y2174353D01*
G01X1931279Y2174457D02*
X1931509Y2174612D01*
X1931777Y2174715D01*
X1932084D01*
X1932429Y2174560D01*
X1932697Y2174302D01*
X1932889Y2173992D01*
X1933042Y2173475D01*
X1933080Y2173010D01*
X1933004Y2172545D01*
X1932889Y2172235D01*
X1932659Y2171925D01*
X1932390Y2171718D01*
X1932122Y2171615D01*
X1931854D01*
X1931585Y2171718D01*
X1931355Y2171873D01*
X1931164Y2172080D01*
G01X1929789Y2171615D02*
Y2174715D01*
X1928830D01*
X1928524Y2174560D01*
X1928332Y2174353D01*
X1928255Y2173940D01*
X1928332Y2173527D01*
X1928562Y2173268D01*
X1928830Y2173113D01*
X1929789D01*
G01X1928830D02*
X1928255Y2171615D01*
G01X1925155D02*
X1926689D01*
Y2174715D01*
X1925155D01*
G01X1925769Y2173217D02*
X1926689D01*
G01X1923972Y2174715D02*
X1923435Y2171615D01*
X1922822Y2174715D01*
X1922209Y2171615D01*
X1921672Y2174715D01*
G01X1920872Y2170582D02*
X1918572D01*
G01X1917427Y2172028D02*
X1917120Y2171770D01*
X1916775Y2171615D01*
X1916469D01*
X1916162Y2171770D01*
X1915932Y2172028D01*
X1915817Y2172390D01*
X1915894Y2172752D01*
X1916085Y2173062D01*
X1916430Y2173268D01*
X1916890Y2173372D01*
X1917159Y2173578D01*
X1917274Y2173940D01*
X1917197Y2174302D01*
X1917005Y2174560D01*
X1916737Y2174715D01*
X1916469D01*
X1916200Y2174612D01*
X1915970Y2174353D01*
G01X1914327Y2172028D02*
X1914020Y2171770D01*
X1913675Y2171615D01*
X1913369D01*
X1913062Y2171770D01*
X1912832Y2172028D01*
X1912717Y2172390D01*
X1912794Y2172752D01*
X1912985Y2173062D01*
X1913330Y2173268D01*
X1913790Y2173372D01*
X1914059Y2173578D01*
X1914174Y2173940D01*
X1914097Y2174302D01*
X1913905Y2174560D01*
X1913637Y2174715D01*
X1913369D01*
X1913100Y2174612D01*
X1912870Y2174353D01*
G01X1911265Y2171615D02*
Y2174715D01*
X1910499D01*
X1910192Y2174560D01*
X1909962Y2174353D01*
X1909770Y2174043D01*
X1909617Y2173682D01*
X1909579Y2173165D01*
X1909617Y2172648D01*
X1909770Y2172287D01*
X1909962Y2171977D01*
X1910192Y2171770D01*
X1910499Y2171615D01*
X1911265D01*
G01X1907322D02*
Y2174715D01*
X1907782Y2174095D01*
G01Y2171615D02*
X1906862D01*
G01X1904950Y2174198D02*
X1904720Y2174508D01*
X1904452Y2174663D01*
X1904145Y2174715D01*
X1903762Y2174612D01*
X1903494Y2174353D01*
X1903417Y2174043D01*
X1903455Y2173733D01*
X1903609Y2173475D01*
X1904375Y2172958D01*
X1904720Y2172597D01*
X1904950Y2172080D01*
X1905027Y2171615D01*
X1903417D01*
G01X1902272Y2170582D02*
X1899972D01*
G01X1898750Y2174198D02*
X1898520Y2174508D01*
X1898252Y2174663D01*
X1897945Y2174715D01*
X1897562Y2174612D01*
X1897294Y2174353D01*
X1897217Y2174043D01*
X1897255Y2173733D01*
X1897409Y2173475D01*
X1898175Y2172958D01*
X1898520Y2172597D01*
X1898750Y2172080D01*
X1898827Y2171615D01*
X1897217D01*
G01X1906416Y2176874D02*
X1906224Y2176564D01*
X1905994Y2176357D01*
X1905726Y2176254D01*
X1905419Y2176357D01*
X1905189Y2176564D01*
X1904959Y2176874D01*
X1904882Y2177287D01*
Y2179354D01*
G01X1903392Y2176719D02*
X1903162Y2176461D01*
X1902894Y2176306D01*
X1902549Y2176254D01*
X1902204Y2176357D01*
X1901936Y2176564D01*
X1901744Y2176926D01*
X1901706Y2177339D01*
X1901782Y2177752D01*
X1901974Y2178011D01*
X1902242Y2178217D01*
X1902511Y2178269D01*
X1902779Y2178217D01*
X1903124Y2178011D01*
X1903009Y2179354D01*
X1901974D01*
G01X1900177Y2177546D02*
X1899909Y2177907D01*
X1899679Y2178114D01*
X1899372Y2178217D01*
X1899104Y2178114D01*
X1898912Y2177907D01*
X1898759Y2177597D01*
X1898721Y2177236D01*
X1898759Y2176926D01*
X1898912Y2176616D01*
X1899142Y2176357D01*
X1899411Y2176254D01*
X1899717Y2176357D01*
X1899986Y2176667D01*
X1900139Y2177132D01*
X1900177Y2177649D01*
X1900101Y2178321D01*
X1899986Y2178682D01*
X1899794Y2179044D01*
X1899526Y2179302D01*
X1899257Y2179354D01*
X1898989Y2179251D01*
X1898797Y2178992D01*
G01X1897499Y2175221D02*
X1895199D01*
G01X1893249Y2176254D02*
Y2179354D01*
X1893709Y2178734D01*
G01Y2176254D02*
X1892789D01*
G01X1890877Y2178837D02*
X1890647Y2179147D01*
X1890379Y2179302D01*
X1890072Y2179354D01*
X1889689Y2179251D01*
X1889421Y2178992D01*
X1889344Y2178682D01*
X1889382Y2178372D01*
X1889536Y2178114D01*
X1890302Y2177597D01*
X1890647Y2177236D01*
X1890877Y2176719D01*
X1890954Y2176254D01*
X1889344D01*
G01X1892603Y2182374D02*
X1889503D01*
G01Y2180764D02*
X1892603D01*
G01X1891053D02*
Y2182374D01*
G01X1892190Y2179274D02*
X1892448Y2178967D01*
X1892603Y2178622D01*
Y2178316D01*
X1892448Y2178009D01*
X1892190Y2177779D01*
X1891828Y2177664D01*
X1891466Y2177741D01*
X1891156Y2177932D01*
X1890950Y2178277D01*
X1890846Y2178737D01*
X1890640Y2179006D01*
X1890278Y2179121D01*
X1889916Y2179044D01*
X1889658Y2178852D01*
X1889503Y2178584D01*
Y2178316D01*
X1889606Y2178047D01*
X1889865Y2177817D01*
G01X1893636Y2176519D02*
Y2174219D01*
G01X1890950Y2171962D02*
X1890795Y2171809D01*
X1890536Y2171694D01*
X1890175Y2171617D01*
X1889865Y2171694D01*
X1889658Y2171847D01*
X1889503Y2172116D01*
Y2173151D01*
X1892603D01*
Y2171886D01*
X1892396Y2171617D01*
X1892086Y2171464D01*
X1891725Y2171387D01*
X1891363Y2171464D01*
X1891053Y2171694D01*
X1890950Y2171962D01*
Y2173151D01*
G01X1892603Y2169936D02*
X1889503D01*
Y2169016D01*
X1889658Y2168709D01*
X1890020Y2168479D01*
X1890433Y2168402D01*
X1890846Y2168479D01*
X1891156Y2168671D01*
X1891311Y2169016D01*
Y2169936D01*
G01X1891983Y2166912D02*
X1892345Y2166682D01*
X1892551Y2166376D01*
X1892603Y2166031D01*
X1892551Y2165724D01*
X1892293Y2165417D01*
X1891983Y2165226D01*
X1891673Y2165187D01*
X1891311Y2165264D01*
X1891053Y2165532D01*
X1890950Y2165801D01*
Y2166146D01*
G01Y2165801D02*
X1890795Y2165571D01*
X1890536Y2165379D01*
X1890226Y2165302D01*
X1889916Y2165379D01*
X1889658Y2165571D01*
X1889503Y2165916D01*
X1889555Y2166261D01*
X1889761Y2166606D01*
G01X1944299Y2048921D02*
X1943992Y2048663D01*
X1943647Y2048508D01*
X1943341D01*
X1943034Y2048663D01*
X1942804Y2048921D01*
X1942689Y2049283D01*
X1942766Y2049645D01*
X1942957Y2049955D01*
X1943302Y2050161D01*
X1943762Y2050265D01*
X1944031Y2050471D01*
X1944146Y2050833D01*
X1944069Y2051195D01*
X1943877Y2051453D01*
X1943609Y2051608D01*
X1943341D01*
X1943072Y2051505D01*
X1942842Y2051246D01*
G01X1939551Y2051350D02*
X1939781Y2051505D01*
X1940049Y2051608D01*
X1940356D01*
X1940701Y2051453D01*
X1940969Y2051195D01*
X1941161Y2050885D01*
X1941314Y2050368D01*
X1941352Y2049903D01*
X1941276Y2049438D01*
X1941161Y2049128D01*
X1940931Y2048818D01*
X1940662Y2048611D01*
X1940394Y2048508D01*
X1940126D01*
X1939857Y2048611D01*
X1939627Y2048766D01*
X1939436Y2048973D01*
G01X1938061Y2048508D02*
Y2051608D01*
X1937102D01*
X1936796Y2051453D01*
X1936604Y2051246D01*
X1936527Y2050833D01*
X1936604Y2050420D01*
X1936834Y2050161D01*
X1937102Y2050006D01*
X1938061D01*
G01X1937102D02*
X1936527Y2048508D01*
G01X1933427D02*
X1934961D01*
Y2051608D01*
X1933427D01*
G01X1934041Y2050110D02*
X1934961D01*
G01X1932244Y2051608D02*
X1931707Y2048508D01*
X1931094Y2051608D01*
X1930481Y2048508D01*
X1929944Y2051608D01*
G01X1929144Y2047475D02*
X1926844D01*
G01X1925699Y2048921D02*
X1925392Y2048663D01*
X1925047Y2048508D01*
X1924741D01*
X1924434Y2048663D01*
X1924204Y2048921D01*
X1924089Y2049283D01*
X1924166Y2049645D01*
X1924357Y2049955D01*
X1924702Y2050161D01*
X1925162Y2050265D01*
X1925431Y2050471D01*
X1925546Y2050833D01*
X1925469Y2051195D01*
X1925277Y2051453D01*
X1925009Y2051608D01*
X1924741D01*
X1924472Y2051505D01*
X1924242Y2051246D01*
G01X1922599Y2048921D02*
X1922292Y2048663D01*
X1921947Y2048508D01*
X1921641D01*
X1921334Y2048663D01*
X1921104Y2048921D01*
X1920989Y2049283D01*
X1921066Y2049645D01*
X1921257Y2049955D01*
X1921602Y2050161D01*
X1922062Y2050265D01*
X1922331Y2050471D01*
X1922446Y2050833D01*
X1922369Y2051195D01*
X1922177Y2051453D01*
X1921909Y2051608D01*
X1921641D01*
X1921372Y2051505D01*
X1921142Y2051246D01*
G01X1919537Y2048508D02*
Y2051608D01*
X1918771D01*
X1918464Y2051453D01*
X1918234Y2051246D01*
X1918042Y2050936D01*
X1917889Y2050575D01*
X1917851Y2050058D01*
X1917889Y2049541D01*
X1918042Y2049180D01*
X1918234Y2048870D01*
X1918464Y2048663D01*
X1918771Y2048508D01*
X1919537D01*
G01X1915671D02*
X1915594Y2049180D01*
X1915479Y2049748D01*
X1915326Y2050265D01*
X1915134Y2050833D01*
X1914827Y2051608D01*
X1916361D01*
G01X1913644Y2047475D02*
X1911344D01*
G01X1910122Y2051091D02*
X1909892Y2051401D01*
X1909624Y2051556D01*
X1909317Y2051608D01*
X1908934Y2051505D01*
X1908666Y2051246D01*
X1908589Y2050936D01*
X1908627Y2050626D01*
X1908781Y2050368D01*
X1909547Y2049851D01*
X1909892Y2049490D01*
X1910122Y2048973D01*
X1910199Y2048508D01*
X1908589D01*
G01X1940012Y2066449D02*
X1939820Y2066139D01*
X1939590Y2065932D01*
X1939322Y2065829D01*
X1939015Y2065932D01*
X1938785Y2066139D01*
X1938555Y2066449D01*
X1938478Y2066862D01*
Y2068929D01*
G01X1936988Y2066449D02*
X1936758Y2066087D01*
X1936452Y2065881D01*
X1936107Y2065829D01*
X1935800Y2065881D01*
X1935493Y2066139D01*
X1935302Y2066449D01*
X1935263Y2066759D01*
X1935340Y2067121D01*
X1935608Y2067379D01*
X1935877Y2067482D01*
X1936222D01*
G01X1935877D02*
X1935647Y2067637D01*
X1935455Y2067896D01*
X1935378Y2068206D01*
X1935455Y2068516D01*
X1935647Y2068774D01*
X1935992Y2068929D01*
X1936337Y2068877D01*
X1936682Y2068671D01*
G01X1933773Y2067121D02*
X1933505Y2067482D01*
X1933275Y2067689D01*
X1932968Y2067792D01*
X1932700Y2067689D01*
X1932508Y2067482D01*
X1932355Y2067172D01*
X1932317Y2066811D01*
X1932355Y2066501D01*
X1932508Y2066191D01*
X1932738Y2065932D01*
X1933007Y2065829D01*
X1933313Y2065932D01*
X1933582Y2066242D01*
X1933735Y2066707D01*
X1933773Y2067224D01*
X1933697Y2067896D01*
X1933582Y2068257D01*
X1933390Y2068619D01*
X1933122Y2068877D01*
X1932853Y2068929D01*
X1932585Y2068826D01*
X1932393Y2068567D01*
G01X1931095Y2064796D02*
X1928795D01*
G01X1926845Y2065829D02*
X1927152Y2065881D01*
X1927420Y2066087D01*
X1927650Y2066397D01*
X1927803Y2066759D01*
X1927880Y2067172D01*
Y2067586D01*
X1927803Y2067999D01*
X1927650Y2068361D01*
X1927420Y2068671D01*
X1927152Y2068877D01*
X1926845Y2068929D01*
X1926538Y2068877D01*
X1926270Y2068671D01*
X1926040Y2068361D01*
X1925887Y2067999D01*
X1925810Y2067586D01*
Y2067172D01*
X1925887Y2066759D01*
X1926040Y2066397D01*
X1926270Y2066087D01*
X1926538Y2065881D01*
X1926845Y2065829D01*
G01X1923745Y2068929D02*
Y2065829D01*
G01X1924627Y2068929D02*
X1922863D01*
G01X1921450Y2065829D02*
Y2068929D01*
G01X1919840D02*
Y2065829D01*
G01Y2067379D02*
X1921450D01*
G01X1924112Y2066449D02*
X1923920Y2066139D01*
X1923690Y2065932D01*
X1923422Y2065829D01*
X1923115Y2065932D01*
X1922885Y2066139D01*
X1922655Y2066449D01*
X1922578Y2066862D01*
Y2068929D01*
G01X1921088Y2066449D02*
X1920858Y2066087D01*
X1920552Y2065881D01*
X1920207Y2065829D01*
X1919900Y2065881D01*
X1919593Y2066139D01*
X1919402Y2066449D01*
X1919363Y2066759D01*
X1919440Y2067121D01*
X1919708Y2067379D01*
X1919977Y2067482D01*
X1920322D01*
G01X1919977D02*
X1919747Y2067637D01*
X1919555Y2067896D01*
X1919478Y2068206D01*
X1919555Y2068516D01*
X1919747Y2068774D01*
X1920092Y2068929D01*
X1920437Y2068877D01*
X1920782Y2068671D01*
G01X1917222Y2065829D02*
X1917145Y2066501D01*
X1917030Y2067069D01*
X1916877Y2067586D01*
X1916685Y2068154D01*
X1916378Y2068929D01*
X1917912D01*
G01X1915195Y2064796D02*
X1912895D01*
G01X1910945Y2065829D02*
X1911252Y2065881D01*
X1911520Y2066087D01*
X1911750Y2066397D01*
X1911903Y2066759D01*
X1911980Y2067172D01*
Y2067586D01*
X1911903Y2067999D01*
X1911750Y2068361D01*
X1911520Y2068671D01*
X1911252Y2068877D01*
X1910945Y2068929D01*
X1910638Y2068877D01*
X1910370Y2068671D01*
X1910140Y2068361D01*
X1909987Y2067999D01*
X1909910Y2067586D01*
Y2067172D01*
X1909987Y2066759D01*
X1910140Y2066397D01*
X1910370Y2066087D01*
X1910638Y2065881D01*
X1910945Y2065829D01*
G01X1907845Y2068929D02*
Y2065829D01*
G01X1908727Y2068929D02*
X1906963D01*
G01X1905550Y2065829D02*
Y2068929D01*
G01X1903940D02*
Y2065829D01*
G01Y2067379D02*
X1905550D01*
G01X1928756Y2059796D02*
X1928564Y2059486D01*
X1928334Y2059279D01*
X1928066Y2059176D01*
X1927759Y2059279D01*
X1927529Y2059486D01*
X1927299Y2059796D01*
X1927222Y2060209D01*
Y2062276D01*
G01X1925732Y2059796D02*
X1925502Y2059434D01*
X1925196Y2059228D01*
X1924851Y2059176D01*
X1924544Y2059228D01*
X1924237Y2059486D01*
X1924046Y2059796D01*
X1924007Y2060106D01*
X1924084Y2060468D01*
X1924352Y2060726D01*
X1924621Y2060829D01*
X1924966D01*
G01X1924621D02*
X1924391Y2060984D01*
X1924199Y2061243D01*
X1924122Y2061553D01*
X1924199Y2061863D01*
X1924391Y2062121D01*
X1924736Y2062276D01*
X1925081Y2062224D01*
X1925426Y2062018D01*
G01X1921329Y2059176D02*
Y2062276D01*
X1922747Y2060054D01*
X1920831D01*
G01X1919839Y2058143D02*
X1917539D01*
G01X1915589Y2059176D02*
X1915896Y2059228D01*
X1916164Y2059434D01*
X1916394Y2059744D01*
X1916547Y2060106D01*
X1916624Y2060519D01*
Y2060933D01*
X1916547Y2061346D01*
X1916394Y2061708D01*
X1916164Y2062018D01*
X1915896Y2062224D01*
X1915589Y2062276D01*
X1915282Y2062224D01*
X1915014Y2062018D01*
X1914784Y2061708D01*
X1914631Y2061346D01*
X1914554Y2060933D01*
Y2060519D01*
X1914631Y2060106D01*
X1914784Y2059744D01*
X1915014Y2059434D01*
X1915282Y2059228D01*
X1915589Y2059176D01*
G01X1912489Y2062276D02*
Y2059176D01*
G01X1913371Y2062276D02*
X1911607D01*
G01X1910194Y2059176D02*
Y2062276D01*
G01X1908584D02*
Y2059176D01*
G01Y2060726D02*
X1910194D01*
G01X1933612Y2078763D02*
X1933420Y2078453D01*
X1933190Y2078246D01*
X1932922Y2078143D01*
X1932615Y2078246D01*
X1932385Y2078453D01*
X1932155Y2078763D01*
X1932078Y2079176D01*
Y2081243D01*
G01X1929285Y2078143D02*
Y2081243D01*
X1930703Y2079021D01*
X1928787D01*
G01X1927795Y2077110D02*
X1925495D01*
G01X1924273Y2080726D02*
X1924043Y2081036D01*
X1923775Y2081191D01*
X1923468Y2081243D01*
X1923085Y2081140D01*
X1922817Y2080881D01*
X1922740Y2080571D01*
X1922778Y2080261D01*
X1922932Y2080003D01*
X1923698Y2079486D01*
X1924043Y2079125D01*
X1924273Y2078608D01*
X1924350Y2078143D01*
X1922740D01*
G01X1921288Y2078763D02*
X1921058Y2078401D01*
X1920752Y2078195D01*
X1920407Y2078143D01*
X1920100Y2078195D01*
X1919793Y2078453D01*
X1919602Y2078763D01*
X1919563Y2079073D01*
X1919640Y2079435D01*
X1919908Y2079693D01*
X1920177Y2079796D01*
X1920522D01*
G01X1920177D02*
X1919947Y2079951D01*
X1919755Y2080210D01*
X1919678Y2080520D01*
X1919755Y2080830D01*
X1919947Y2081088D01*
X1920292Y2081243D01*
X1920637Y2081191D01*
X1920982Y2080985D01*
G01X1938395Y2074337D02*
X1938088Y2074079D01*
X1937743Y2073924D01*
X1937437D01*
X1937130Y2074079D01*
X1936900Y2074337D01*
X1936785Y2074699D01*
X1936862Y2075061D01*
X1937053Y2075371D01*
X1937398Y2075577D01*
X1937858Y2075681D01*
X1938127Y2075887D01*
X1938242Y2076249D01*
X1938165Y2076611D01*
X1937973Y2076869D01*
X1937705Y2077024D01*
X1937437D01*
X1937168Y2076921D01*
X1936938Y2076662D01*
G01X1933647Y2076766D02*
X1933877Y2076921D01*
X1934145Y2077024D01*
X1934452D01*
X1934797Y2076869D01*
X1935065Y2076611D01*
X1935257Y2076301D01*
X1935410Y2075784D01*
X1935448Y2075319D01*
X1935372Y2074854D01*
X1935257Y2074544D01*
X1935027Y2074234D01*
X1934758Y2074027D01*
X1934490Y2073924D01*
X1934222D01*
X1933953Y2074027D01*
X1933723Y2074182D01*
X1933532Y2074389D01*
G01X1932157Y2073924D02*
Y2077024D01*
X1931198D01*
X1930892Y2076869D01*
X1930700Y2076662D01*
X1930623Y2076249D01*
X1930700Y2075836D01*
X1930930Y2075577D01*
X1931198Y2075422D01*
X1932157D01*
G01X1931198D02*
X1930623Y2073924D01*
G01X1927523D02*
X1929057D01*
Y2077024D01*
X1927523D01*
G01X1928137Y2075526D02*
X1929057D01*
G01X1926340Y2077024D02*
X1925803Y2073924D01*
X1925190Y2077024D01*
X1924577Y2073924D01*
X1924040Y2077024D01*
G01X1923240Y2072891D02*
X1920940D01*
G01X1919642Y2074286D02*
X1919373Y2074027D01*
X1919067Y2073924D01*
X1918760Y2074027D01*
X1918492Y2074337D01*
X1918300Y2074802D01*
X1918223Y2075267D01*
Y2075836D01*
X1918300Y2076301D01*
X1918492Y2076714D01*
X1918722Y2076921D01*
X1918990Y2077024D01*
X1919297Y2076921D01*
X1919527Y2076714D01*
X1919680Y2076404D01*
X1919757Y2075991D01*
X1919680Y2075629D01*
X1919488Y2075267D01*
X1919258Y2075061D01*
X1918990Y2075009D01*
X1918683Y2075112D01*
X1918453Y2075371D01*
X1918223Y2075836D01*
G01X1952065Y2145326D02*
X1951758Y2145068D01*
X1951413Y2144913D01*
X1951107D01*
X1950800Y2145068D01*
X1950570Y2145326D01*
X1950455Y2145688D01*
X1950532Y2146050D01*
X1950723Y2146360D01*
X1951068Y2146566D01*
X1951528Y2146670D01*
X1951797Y2146876D01*
X1951912Y2147238D01*
X1951835Y2147600D01*
X1951643Y2147858D01*
X1951375Y2148013D01*
X1951107D01*
X1950838Y2147910D01*
X1950608Y2147651D01*
G01X1947317Y2147755D02*
X1947547Y2147910D01*
X1947815Y2148013D01*
X1948122D01*
X1948467Y2147858D01*
X1948735Y2147600D01*
X1948927Y2147290D01*
X1949080Y2146773D01*
X1949118Y2146308D01*
X1949042Y2145843D01*
X1948927Y2145533D01*
X1948697Y2145223D01*
X1948428Y2145016D01*
X1948160Y2144913D01*
X1947892D01*
X1947623Y2145016D01*
X1947393Y2145171D01*
X1947202Y2145378D01*
G01X1945827Y2144913D02*
Y2148013D01*
X1944868D01*
X1944562Y2147858D01*
X1944370Y2147651D01*
X1944293Y2147238D01*
X1944370Y2146825D01*
X1944600Y2146566D01*
X1944868Y2146411D01*
X1945827D01*
G01X1944868D02*
X1944293Y2144913D01*
G01X1941193D02*
X1942727D01*
Y2148013D01*
X1941193D01*
G01X1941807Y2146515D02*
X1942727D01*
G01X1940010Y2148013D02*
X1939473Y2144913D01*
X1938860Y2148013D01*
X1938247Y2144913D01*
X1937710Y2148013D01*
G01X1936910Y2143880D02*
X1934610D01*
G01X1933465Y2145326D02*
X1933158Y2145068D01*
X1932813Y2144913D01*
X1932507D01*
X1932200Y2145068D01*
X1931970Y2145326D01*
X1931855Y2145688D01*
X1931932Y2146050D01*
X1932123Y2146360D01*
X1932468Y2146566D01*
X1932928Y2146670D01*
X1933197Y2146876D01*
X1933312Y2147238D01*
X1933235Y2147600D01*
X1933043Y2147858D01*
X1932775Y2148013D01*
X1932507D01*
X1932238Y2147910D01*
X1932008Y2147651D01*
G01X1930365Y2145326D02*
X1930058Y2145068D01*
X1929713Y2144913D01*
X1929407D01*
X1929100Y2145068D01*
X1928870Y2145326D01*
X1928755Y2145688D01*
X1928832Y2146050D01*
X1929023Y2146360D01*
X1929368Y2146566D01*
X1929828Y2146670D01*
X1930097Y2146876D01*
X1930212Y2147238D01*
X1930135Y2147600D01*
X1929943Y2147858D01*
X1929675Y2148013D01*
X1929407D01*
X1929138Y2147910D01*
X1928908Y2147651D01*
G01X1927303Y2144913D02*
Y2148013D01*
X1926537D01*
X1926230Y2147858D01*
X1926000Y2147651D01*
X1925808Y2147341D01*
X1925655Y2146980D01*
X1925617Y2146463D01*
X1925655Y2145946D01*
X1925808Y2145585D01*
X1926000Y2145275D01*
X1926230Y2145068D01*
X1926537Y2144913D01*
X1927303D01*
G01X1924012Y2145275D02*
X1923743Y2145016D01*
X1923437Y2144913D01*
X1923130Y2145016D01*
X1922862Y2145326D01*
X1922670Y2145791D01*
X1922593Y2146256D01*
Y2146825D01*
X1922670Y2147290D01*
X1922862Y2147703D01*
X1923092Y2147910D01*
X1923360Y2148013D01*
X1923667Y2147910D01*
X1923897Y2147703D01*
X1924050Y2147393D01*
X1924127Y2146980D01*
X1924050Y2146618D01*
X1923858Y2146256D01*
X1923628Y2146050D01*
X1923360Y2145998D01*
X1923053Y2146101D01*
X1922823Y2146360D01*
X1922593Y2146825D01*
G01X1921410Y2143880D02*
X1919110D01*
G01X1917888Y2147496D02*
X1917658Y2147806D01*
X1917390Y2147961D01*
X1917083Y2148013D01*
X1916700Y2147910D01*
X1916432Y2147651D01*
X1916355Y2147341D01*
X1916393Y2147031D01*
X1916547Y2146773D01*
X1917313Y2146256D01*
X1917658Y2145895D01*
X1917888Y2145378D01*
X1917965Y2144913D01*
X1916355D01*
G01X1947605Y2151948D02*
X1947298Y2151690D01*
X1946953Y2151535D01*
X1946647D01*
X1946340Y2151690D01*
X1946110Y2151948D01*
X1945995Y2152310D01*
X1946072Y2152672D01*
X1946263Y2152982D01*
X1946608Y2153188D01*
X1947068Y2153292D01*
X1947337Y2153498D01*
X1947452Y2153860D01*
X1947375Y2154222D01*
X1947183Y2154480D01*
X1946915Y2154635D01*
X1946647D01*
X1946378Y2154532D01*
X1946148Y2154273D01*
G01X1942857Y2154377D02*
X1943087Y2154532D01*
X1943355Y2154635D01*
X1943662D01*
X1944007Y2154480D01*
X1944275Y2154222D01*
X1944467Y2153912D01*
X1944620Y2153395D01*
X1944658Y2152930D01*
X1944582Y2152465D01*
X1944467Y2152155D01*
X1944237Y2151845D01*
X1943968Y2151638D01*
X1943700Y2151535D01*
X1943432D01*
X1943163Y2151638D01*
X1942933Y2151793D01*
X1942742Y2152000D01*
G01X1941367Y2151535D02*
Y2154635D01*
X1940408D01*
X1940102Y2154480D01*
X1939910Y2154273D01*
X1939833Y2153860D01*
X1939910Y2153447D01*
X1940140Y2153188D01*
X1940408Y2153033D01*
X1941367D01*
G01X1940408D02*
X1939833Y2151535D01*
G01X1936733D02*
X1938267D01*
Y2154635D01*
X1936733D01*
G01X1937347Y2153137D02*
X1938267D01*
G01X1935550Y2154635D02*
X1935013Y2151535D01*
X1934400Y2154635D01*
X1933787Y2151535D01*
X1933250Y2154635D01*
G01X1932450Y2150502D02*
X1930150D01*
G01X1929005Y2151948D02*
X1928698Y2151690D01*
X1928353Y2151535D01*
X1928047D01*
X1927740Y2151690D01*
X1927510Y2151948D01*
X1927395Y2152310D01*
X1927472Y2152672D01*
X1927663Y2152982D01*
X1928008Y2153188D01*
X1928468Y2153292D01*
X1928737Y2153498D01*
X1928852Y2153860D01*
X1928775Y2154222D01*
X1928583Y2154480D01*
X1928315Y2154635D01*
X1928047D01*
X1927778Y2154532D01*
X1927548Y2154273D01*
G01X1925905Y2151948D02*
X1925598Y2151690D01*
X1925253Y2151535D01*
X1924947D01*
X1924640Y2151690D01*
X1924410Y2151948D01*
X1924295Y2152310D01*
X1924372Y2152672D01*
X1924563Y2152982D01*
X1924908Y2153188D01*
X1925368Y2153292D01*
X1925637Y2153498D01*
X1925752Y2153860D01*
X1925675Y2154222D01*
X1925483Y2154480D01*
X1925215Y2154635D01*
X1924947D01*
X1924678Y2154532D01*
X1924448Y2154273D01*
G01X1922843Y2151535D02*
Y2154635D01*
X1922077D01*
X1921770Y2154480D01*
X1921540Y2154273D01*
X1921348Y2153963D01*
X1921195Y2153602D01*
X1921157Y2153085D01*
X1921195Y2152568D01*
X1921348Y2152207D01*
X1921540Y2151897D01*
X1921770Y2151690D01*
X1922077Y2151535D01*
X1922843D01*
G01X1919743Y2152155D02*
X1919513Y2151793D01*
X1919207Y2151587D01*
X1918862Y2151535D01*
X1918555Y2151587D01*
X1918248Y2151845D01*
X1918057Y2152155D01*
X1918018Y2152465D01*
X1918095Y2152827D01*
X1918363Y2153085D01*
X1918632Y2153188D01*
X1918977D01*
G01X1918632D02*
X1918402Y2153343D01*
X1918210Y2153602D01*
X1918133Y2153912D01*
X1918210Y2154222D01*
X1918402Y2154480D01*
X1918747Y2154635D01*
X1919092Y2154583D01*
X1919437Y2154377D01*
G01X1916950Y2150502D02*
X1914650D01*
G01X1913428Y2154118D02*
X1913198Y2154428D01*
X1912930Y2154583D01*
X1912623Y2154635D01*
X1912240Y2154532D01*
X1911972Y2154273D01*
X1911895Y2153963D01*
X1911933Y2153653D01*
X1912087Y2153395D01*
X1912853Y2152878D01*
X1913198Y2152517D01*
X1913428Y2152000D01*
X1913505Y2151535D01*
X1911895D01*
G01X1944327Y2172028D02*
X1944020Y2171770D01*
X1943675Y2171615D01*
X1943369D01*
X1943062Y2171770D01*
X1942832Y2172028D01*
X1942717Y2172390D01*
X1942794Y2172752D01*
X1942985Y2173062D01*
X1943330Y2173268D01*
X1943790Y2173372D01*
X1944059Y2173578D01*
X1944174Y2173940D01*
X1944097Y2174302D01*
X1943905Y2174560D01*
X1943637Y2174715D01*
X1943369D01*
X1943100Y2174612D01*
X1942870Y2174353D01*
G01X1939579Y2174457D02*
X1939809Y2174612D01*
X1940077Y2174715D01*
X1940384D01*
X1940729Y2174560D01*
X1940997Y2174302D01*
X1941189Y2173992D01*
X1941342Y2173475D01*
X1941380Y2173010D01*
X1941304Y2172545D01*
X1941189Y2172235D01*
X1940959Y2171925D01*
X1940690Y2171718D01*
X1940422Y2171615D01*
X1940154D01*
X1939885Y2171718D01*
X1939655Y2171873D01*
X1939464Y2172080D01*
G01X1938089Y2171615D02*
Y2174715D01*
X1937130D01*
X1936824Y2174560D01*
X1936632Y2174353D01*
X1936555Y2173940D01*
X1936632Y2173527D01*
X1936862Y2173268D01*
X1937130Y2173113D01*
X1938089D01*
G01X1937130D02*
X1936555Y2171615D01*
G01X1933455D02*
X1934989D01*
Y2174715D01*
X1933455D01*
G01X1934069Y2173217D02*
X1934989D01*
G01X1932272Y2174715D02*
X1931735Y2171615D01*
X1931122Y2174715D01*
X1930509Y2171615D01*
X1929972Y2174715D01*
G01X1929172Y2170582D02*
X1926872D01*
G01X1925727Y2172028D02*
X1925420Y2171770D01*
X1925075Y2171615D01*
X1924769D01*
X1924462Y2171770D01*
X1924232Y2172028D01*
X1924117Y2172390D01*
X1924194Y2172752D01*
X1924385Y2173062D01*
X1924730Y2173268D01*
X1925190Y2173372D01*
X1925459Y2173578D01*
X1925574Y2173940D01*
X1925497Y2174302D01*
X1925305Y2174560D01*
X1925037Y2174715D01*
X1924769D01*
X1924500Y2174612D01*
X1924270Y2174353D01*
G01X1922627Y2172028D02*
X1922320Y2171770D01*
X1921975Y2171615D01*
X1921669D01*
X1921362Y2171770D01*
X1921132Y2172028D01*
X1921017Y2172390D01*
X1921094Y2172752D01*
X1921285Y2173062D01*
X1921630Y2173268D01*
X1922090Y2173372D01*
X1922359Y2173578D01*
X1922474Y2173940D01*
X1922397Y2174302D01*
X1922205Y2174560D01*
X1921937Y2174715D01*
X1921669D01*
X1921400Y2174612D01*
X1921170Y2174353D01*
G01X1919565Y2171615D02*
Y2174715D01*
X1918799D01*
X1918492Y2174560D01*
X1918262Y2174353D01*
X1918070Y2174043D01*
X1917917Y2173682D01*
X1917879Y2173165D01*
X1917917Y2172648D01*
X1918070Y2172287D01*
X1918262Y2171977D01*
X1918492Y2171770D01*
X1918799Y2171615D01*
X1919565D01*
G01X1915622D02*
Y2174715D01*
X1916082Y2174095D01*
G01Y2171615D02*
X1915162D01*
G01X1913250Y2174198D02*
X1913020Y2174508D01*
X1912752Y2174663D01*
X1912445Y2174715D01*
X1912062Y2174612D01*
X1911794Y2174353D01*
X1911717Y2174043D01*
X1911755Y2173733D01*
X1911909Y2173475D01*
X1912675Y2172958D01*
X1913020Y2172597D01*
X1913250Y2172080D01*
X1913327Y2171615D01*
X1911717D01*
G01X1910572Y2170582D02*
X1908272D01*
G01X1906322Y2171615D02*
Y2174715D01*
X1906782Y2174095D01*
G01Y2171615D02*
X1905862D01*
G01X1960365Y2145326D02*
X1960058Y2145068D01*
X1959713Y2144913D01*
X1959407D01*
X1959100Y2145068D01*
X1958870Y2145326D01*
X1958755Y2145688D01*
X1958832Y2146050D01*
X1959023Y2146360D01*
X1959368Y2146566D01*
X1959828Y2146670D01*
X1960097Y2146876D01*
X1960212Y2147238D01*
X1960135Y2147600D01*
X1959943Y2147858D01*
X1959675Y2148013D01*
X1959407D01*
X1959138Y2147910D01*
X1958908Y2147651D01*
G01X1955617Y2147755D02*
X1955847Y2147910D01*
X1956115Y2148013D01*
X1956422D01*
X1956767Y2147858D01*
X1957035Y2147600D01*
X1957227Y2147290D01*
X1957380Y2146773D01*
X1957418Y2146308D01*
X1957342Y2145843D01*
X1957227Y2145533D01*
X1956997Y2145223D01*
X1956728Y2145016D01*
X1956460Y2144913D01*
X1956192D01*
X1955923Y2145016D01*
X1955693Y2145171D01*
X1955502Y2145378D01*
G01X1954127Y2144913D02*
Y2148013D01*
X1953168D01*
X1952862Y2147858D01*
X1952670Y2147651D01*
X1952593Y2147238D01*
X1952670Y2146825D01*
X1952900Y2146566D01*
X1953168Y2146411D01*
X1954127D01*
G01X1953168D02*
X1952593Y2144913D01*
G01X1949493D02*
X1951027D01*
Y2148013D01*
X1949493D01*
G01X1950107Y2146515D02*
X1951027D01*
G01X1948310Y2148013D02*
X1947773Y2144913D01*
X1947160Y2148013D01*
X1946547Y2144913D01*
X1946010Y2148013D01*
G01X1945210Y2143880D02*
X1942910D01*
G01X1941765Y2145326D02*
X1941458Y2145068D01*
X1941113Y2144913D01*
X1940807D01*
X1940500Y2145068D01*
X1940270Y2145326D01*
X1940155Y2145688D01*
X1940232Y2146050D01*
X1940423Y2146360D01*
X1940768Y2146566D01*
X1941228Y2146670D01*
X1941497Y2146876D01*
X1941612Y2147238D01*
X1941535Y2147600D01*
X1941343Y2147858D01*
X1941075Y2148013D01*
X1940807D01*
X1940538Y2147910D01*
X1940308Y2147651D01*
G01X1938665Y2145326D02*
X1938358Y2145068D01*
X1938013Y2144913D01*
X1937707D01*
X1937400Y2145068D01*
X1937170Y2145326D01*
X1937055Y2145688D01*
X1937132Y2146050D01*
X1937323Y2146360D01*
X1937668Y2146566D01*
X1938128Y2146670D01*
X1938397Y2146876D01*
X1938512Y2147238D01*
X1938435Y2147600D01*
X1938243Y2147858D01*
X1937975Y2148013D01*
X1937707D01*
X1937438Y2147910D01*
X1937208Y2147651D01*
G01X1935603Y2144913D02*
Y2148013D01*
X1934837D01*
X1934530Y2147858D01*
X1934300Y2147651D01*
X1934108Y2147341D01*
X1933955Y2146980D01*
X1933917Y2146463D01*
X1933955Y2145946D01*
X1934108Y2145585D01*
X1934300Y2145275D01*
X1934530Y2145068D01*
X1934837Y2144913D01*
X1935603D01*
G01X1932312Y2145275D02*
X1932043Y2145016D01*
X1931737Y2144913D01*
X1931430Y2145016D01*
X1931162Y2145326D01*
X1930970Y2145791D01*
X1930893Y2146256D01*
Y2146825D01*
X1930970Y2147290D01*
X1931162Y2147703D01*
X1931392Y2147910D01*
X1931660Y2148013D01*
X1931967Y2147910D01*
X1932197Y2147703D01*
X1932350Y2147393D01*
X1932427Y2146980D01*
X1932350Y2146618D01*
X1932158Y2146256D01*
X1931928Y2146050D01*
X1931660Y2145998D01*
X1931353Y2146101D01*
X1931123Y2146360D01*
X1930893Y2146825D01*
G01X1929710Y2143880D02*
X1927410D01*
G01X1925460Y2144913D02*
Y2148013D01*
X1925920Y2147393D01*
G01Y2144913D02*
X1925000D01*
G01X1955905Y2151948D02*
X1955598Y2151690D01*
X1955253Y2151535D01*
X1954947D01*
X1954640Y2151690D01*
X1954410Y2151948D01*
X1954295Y2152310D01*
X1954372Y2152672D01*
X1954563Y2152982D01*
X1954908Y2153188D01*
X1955368Y2153292D01*
X1955637Y2153498D01*
X1955752Y2153860D01*
X1955675Y2154222D01*
X1955483Y2154480D01*
X1955215Y2154635D01*
X1954947D01*
X1954678Y2154532D01*
X1954448Y2154273D01*
G01X1951157Y2154377D02*
X1951387Y2154532D01*
X1951655Y2154635D01*
X1951962D01*
X1952307Y2154480D01*
X1952575Y2154222D01*
X1952767Y2153912D01*
X1952920Y2153395D01*
X1952958Y2152930D01*
X1952882Y2152465D01*
X1952767Y2152155D01*
X1952537Y2151845D01*
X1952268Y2151638D01*
X1952000Y2151535D01*
X1951732D01*
X1951463Y2151638D01*
X1951233Y2151793D01*
X1951042Y2152000D01*
G01X1949667Y2151535D02*
Y2154635D01*
X1948708D01*
X1948402Y2154480D01*
X1948210Y2154273D01*
X1948133Y2153860D01*
X1948210Y2153447D01*
X1948440Y2153188D01*
X1948708Y2153033D01*
X1949667D01*
G01X1948708D02*
X1948133Y2151535D01*
G01X1945033D02*
X1946567D01*
Y2154635D01*
X1945033D01*
G01X1945647Y2153137D02*
X1946567D01*
G01X1943850Y2154635D02*
X1943313Y2151535D01*
X1942700Y2154635D01*
X1942087Y2151535D01*
X1941550Y2154635D01*
G01X1940750Y2150502D02*
X1938450D01*
G01X1937305Y2151948D02*
X1936998Y2151690D01*
X1936653Y2151535D01*
X1936347D01*
X1936040Y2151690D01*
X1935810Y2151948D01*
X1935695Y2152310D01*
X1935772Y2152672D01*
X1935963Y2152982D01*
X1936308Y2153188D01*
X1936768Y2153292D01*
X1937037Y2153498D01*
X1937152Y2153860D01*
X1937075Y2154222D01*
X1936883Y2154480D01*
X1936615Y2154635D01*
X1936347D01*
X1936078Y2154532D01*
X1935848Y2154273D01*
G01X1934205Y2151948D02*
X1933898Y2151690D01*
X1933553Y2151535D01*
X1933247D01*
X1932940Y2151690D01*
X1932710Y2151948D01*
X1932595Y2152310D01*
X1932672Y2152672D01*
X1932863Y2152982D01*
X1933208Y2153188D01*
X1933668Y2153292D01*
X1933937Y2153498D01*
X1934052Y2153860D01*
X1933975Y2154222D01*
X1933783Y2154480D01*
X1933515Y2154635D01*
X1933247D01*
X1932978Y2154532D01*
X1932748Y2154273D01*
G01X1931143Y2151535D02*
Y2154635D01*
X1930377D01*
X1930070Y2154480D01*
X1929840Y2154273D01*
X1929648Y2153963D01*
X1929495Y2153602D01*
X1929457Y2153085D01*
X1929495Y2152568D01*
X1929648Y2152207D01*
X1929840Y2151897D01*
X1930070Y2151690D01*
X1930377Y2151535D01*
X1931143D01*
G01X1928043Y2152155D02*
X1927813Y2151793D01*
X1927507Y2151587D01*
X1927162Y2151535D01*
X1926855Y2151587D01*
X1926548Y2151845D01*
X1926357Y2152155D01*
X1926318Y2152465D01*
X1926395Y2152827D01*
X1926663Y2153085D01*
X1926932Y2153188D01*
X1927277D01*
G01X1926932D02*
X1926702Y2153343D01*
X1926510Y2153602D01*
X1926433Y2153912D01*
X1926510Y2154222D01*
X1926702Y2154480D01*
X1927047Y2154635D01*
X1927392Y2154583D01*
X1927737Y2154377D01*
G01X1925250Y2150502D02*
X1922950D01*
G01X1921000Y2151535D02*
Y2154635D01*
X1921460Y2154015D01*
G01Y2151535D02*
X1920540D01*
G01X1953752Y2171835D02*
X1953560Y2171525D01*
X1953330Y2171318D01*
X1953062Y2171215D01*
X1952755Y2171318D01*
X1952525Y2171525D01*
X1952295Y2171835D01*
X1952218Y2172248D01*
Y2174315D01*
G01X1950652Y2171215D02*
Y2174315D01*
X1949732D01*
X1949425Y2174160D01*
X1949195Y2173798D01*
X1949118Y2173385D01*
X1949195Y2172972D01*
X1949387Y2172662D01*
X1949732Y2172507D01*
X1950652D01*
G01X1946018Y2171215D02*
X1947552D01*
Y2174315D01*
X1946018D01*
G01X1946632Y2172817D02*
X1947552D01*
G01X1944490Y2171215D02*
X1942880Y2174315D01*
G01X1944490D02*
X1942880Y2171215D01*
G01X1940585D02*
Y2174315D01*
X1941045Y2173695D01*
G01Y2171215D02*
X1940125D01*
G01X1938635Y2170182D02*
X1936335D01*
G01X1935113Y2171215D02*
Y2174315D01*
X1933657D01*
G01X1934193Y2172817D02*
X1935113D01*
G01X1932435Y2174315D02*
X1931898Y2171215D01*
X1931285Y2174315D01*
X1930672Y2171215D01*
X1930135Y2174315D01*
G01X1928185Y2171215D02*
Y2174315D01*
X1928645Y2173695D01*
G01Y2171215D02*
X1927725D01*
G01X1968510Y2165649D02*
X1968203Y2165391D01*
X1967858Y2165236D01*
X1967552D01*
X1967245Y2165391D01*
X1967015Y2165649D01*
X1966900Y2166011D01*
X1966977Y2166373D01*
X1967168Y2166683D01*
X1967513Y2166889D01*
X1967973Y2166993D01*
X1968242Y2167199D01*
X1968357Y2167561D01*
X1968280Y2167923D01*
X1968088Y2168181D01*
X1967820Y2168336D01*
X1967552D01*
X1967283Y2168233D01*
X1967053Y2167974D01*
G01X1963762Y2168078D02*
X1963992Y2168233D01*
X1964260Y2168336D01*
X1964567D01*
X1964912Y2168181D01*
X1965180Y2167923D01*
X1965372Y2167613D01*
X1965525Y2167096D01*
X1965563Y2166631D01*
X1965487Y2166166D01*
X1965372Y2165856D01*
X1965142Y2165546D01*
X1964873Y2165339D01*
X1964605Y2165236D01*
X1964337D01*
X1964068Y2165339D01*
X1963838Y2165494D01*
X1963647Y2165701D01*
G01X1962272Y2165236D02*
Y2168336D01*
X1961313D01*
X1961007Y2168181D01*
X1960815Y2167974D01*
X1960738Y2167561D01*
X1960815Y2167148D01*
X1961045Y2166889D01*
X1961313Y2166734D01*
X1962272D01*
G01X1961313D02*
X1960738Y2165236D01*
G01X1957638D02*
X1959172D01*
Y2168336D01*
X1957638D01*
G01X1958252Y2166838D02*
X1959172D01*
G01X1956455Y2168336D02*
X1955918Y2165236D01*
X1955305Y2168336D01*
X1954692Y2165236D01*
X1954155Y2168336D01*
G01X1953355Y2164203D02*
X1951055D01*
G01X1949910Y2165649D02*
X1949603Y2165391D01*
X1949258Y2165236D01*
X1948952D01*
X1948645Y2165391D01*
X1948415Y2165649D01*
X1948300Y2166011D01*
X1948377Y2166373D01*
X1948568Y2166683D01*
X1948913Y2166889D01*
X1949373Y2166993D01*
X1949642Y2167199D01*
X1949757Y2167561D01*
X1949680Y2167923D01*
X1949488Y2168181D01*
X1949220Y2168336D01*
X1948952D01*
X1948683Y2168233D01*
X1948453Y2167974D01*
G01X1946810Y2165649D02*
X1946503Y2165391D01*
X1946158Y2165236D01*
X1945852D01*
X1945545Y2165391D01*
X1945315Y2165649D01*
X1945200Y2166011D01*
X1945277Y2166373D01*
X1945468Y2166683D01*
X1945813Y2166889D01*
X1946273Y2166993D01*
X1946542Y2167199D01*
X1946657Y2167561D01*
X1946580Y2167923D01*
X1946388Y2168181D01*
X1946120Y2168336D01*
X1945852D01*
X1945583Y2168233D01*
X1945353Y2167974D01*
G01X1943748Y2165236D02*
Y2168336D01*
X1942982D01*
X1942675Y2168181D01*
X1942445Y2167974D01*
X1942253Y2167664D01*
X1942100Y2167303D01*
X1942062Y2166786D01*
X1942100Y2166269D01*
X1942253Y2165908D01*
X1942445Y2165598D01*
X1942675Y2165391D01*
X1942982Y2165236D01*
X1943748D01*
G01X1939805Y2168336D02*
X1940112Y2168233D01*
X1940342Y2167974D01*
X1940495Y2167664D01*
X1940610Y2167251D01*
X1940648Y2166786D01*
X1940610Y2166321D01*
X1940495Y2165908D01*
X1940342Y2165598D01*
X1940112Y2165339D01*
X1939805Y2165236D01*
X1939498Y2165339D01*
X1939268Y2165598D01*
X1939115Y2165908D01*
X1939000Y2166321D01*
X1938962Y2166786D01*
X1939000Y2167251D01*
X1939115Y2167664D01*
X1939268Y2167974D01*
X1939498Y2168233D01*
X1939805Y2168336D01*
G01X1937855Y2164203D02*
X1935555D01*
G01X1933605Y2165236D02*
Y2168336D01*
X1934065Y2167716D01*
G01Y2165236D02*
X1933145D01*
G01X1960210Y2165649D02*
X1959903Y2165391D01*
X1959558Y2165236D01*
X1959252D01*
X1958945Y2165391D01*
X1958715Y2165649D01*
X1958600Y2166011D01*
X1958677Y2166373D01*
X1958868Y2166683D01*
X1959213Y2166889D01*
X1959673Y2166993D01*
X1959942Y2167199D01*
X1960057Y2167561D01*
X1959980Y2167923D01*
X1959788Y2168181D01*
X1959520Y2168336D01*
X1959252D01*
X1958983Y2168233D01*
X1958753Y2167974D01*
G01X1955462Y2168078D02*
X1955692Y2168233D01*
X1955960Y2168336D01*
X1956267D01*
X1956612Y2168181D01*
X1956880Y2167923D01*
X1957072Y2167613D01*
X1957225Y2167096D01*
X1957263Y2166631D01*
X1957187Y2166166D01*
X1957072Y2165856D01*
X1956842Y2165546D01*
X1956573Y2165339D01*
X1956305Y2165236D01*
X1956037D01*
X1955768Y2165339D01*
X1955538Y2165494D01*
X1955347Y2165701D01*
G01X1953972Y2165236D02*
Y2168336D01*
X1953013D01*
X1952707Y2168181D01*
X1952515Y2167974D01*
X1952438Y2167561D01*
X1952515Y2167148D01*
X1952745Y2166889D01*
X1953013Y2166734D01*
X1953972D01*
G01X1953013D02*
X1952438Y2165236D01*
G01X1949338D02*
X1950872D01*
Y2168336D01*
X1949338D01*
G01X1949952Y2166838D02*
X1950872D01*
G01X1948155Y2168336D02*
X1947618Y2165236D01*
X1947005Y2168336D01*
X1946392Y2165236D01*
X1945855Y2168336D01*
G01X1945055Y2164203D02*
X1942755D01*
G01X1941610Y2165649D02*
X1941303Y2165391D01*
X1940958Y2165236D01*
X1940652D01*
X1940345Y2165391D01*
X1940115Y2165649D01*
X1940000Y2166011D01*
X1940077Y2166373D01*
X1940268Y2166683D01*
X1940613Y2166889D01*
X1941073Y2166993D01*
X1941342Y2167199D01*
X1941457Y2167561D01*
X1941380Y2167923D01*
X1941188Y2168181D01*
X1940920Y2168336D01*
X1940652D01*
X1940383Y2168233D01*
X1940153Y2167974D01*
G01X1938510Y2165649D02*
X1938203Y2165391D01*
X1937858Y2165236D01*
X1937552D01*
X1937245Y2165391D01*
X1937015Y2165649D01*
X1936900Y2166011D01*
X1936977Y2166373D01*
X1937168Y2166683D01*
X1937513Y2166889D01*
X1937973Y2166993D01*
X1938242Y2167199D01*
X1938357Y2167561D01*
X1938280Y2167923D01*
X1938088Y2168181D01*
X1937820Y2168336D01*
X1937552D01*
X1937283Y2168233D01*
X1937053Y2167974D01*
G01X1935448Y2165236D02*
Y2168336D01*
X1934682D01*
X1934375Y2168181D01*
X1934145Y2167974D01*
X1933953Y2167664D01*
X1933800Y2167303D01*
X1933762Y2166786D01*
X1933800Y2166269D01*
X1933953Y2165908D01*
X1934145Y2165598D01*
X1934375Y2165391D01*
X1934682Y2165236D01*
X1935448D01*
G01X1931505Y2168336D02*
X1931812Y2168233D01*
X1932042Y2167974D01*
X1932195Y2167664D01*
X1932310Y2167251D01*
X1932348Y2166786D01*
X1932310Y2166321D01*
X1932195Y2165908D01*
X1932042Y2165598D01*
X1931812Y2165339D01*
X1931505Y2165236D01*
X1931198Y2165339D01*
X1930968Y2165598D01*
X1930815Y2165908D01*
X1930700Y2166321D01*
X1930662Y2166786D01*
X1930700Y2167251D01*
X1930815Y2167664D01*
X1930968Y2167974D01*
X1931198Y2168233D01*
X1931505Y2168336D01*
G01X1929555Y2164203D02*
X1927255D01*
G01X1926033Y2167819D02*
X1925803Y2168129D01*
X1925535Y2168284D01*
X1925228Y2168336D01*
X1924845Y2168233D01*
X1924577Y2167974D01*
X1924500Y2167664D01*
X1924538Y2167354D01*
X1924692Y2167096D01*
X1925458Y2166579D01*
X1925803Y2166218D01*
X1926033Y2165701D01*
X1926110Y2165236D01*
X1924500D01*
G01X1970093Y2176144D02*
X1969786Y2175886D01*
X1969441Y2175731D01*
X1969135D01*
X1968828Y2175886D01*
X1968598Y2176144D01*
X1968483Y2176506D01*
X1968560Y2176868D01*
X1968751Y2177178D01*
X1969096Y2177384D01*
X1969556Y2177488D01*
X1969825Y2177694D01*
X1969940Y2178056D01*
X1969863Y2178418D01*
X1969671Y2178676D01*
X1969403Y2178831D01*
X1969135D01*
X1968866Y2178728D01*
X1968636Y2178469D01*
G01X1965345Y2178573D02*
X1965575Y2178728D01*
X1965843Y2178831D01*
X1966150D01*
X1966495Y2178676D01*
X1966763Y2178418D01*
X1966955Y2178108D01*
X1967108Y2177591D01*
X1967146Y2177126D01*
X1967070Y2176661D01*
X1966955Y2176351D01*
X1966725Y2176041D01*
X1966456Y2175834D01*
X1966188Y2175731D01*
X1965920D01*
X1965651Y2175834D01*
X1965421Y2175989D01*
X1965230Y2176196D01*
G01X1963855Y2175731D02*
Y2178831D01*
X1962896D01*
X1962590Y2178676D01*
X1962398Y2178469D01*
X1962321Y2178056D01*
X1962398Y2177643D01*
X1962628Y2177384D01*
X1962896Y2177229D01*
X1963855D01*
G01X1962896D02*
X1962321Y2175731D01*
G01X1959221D02*
X1960755D01*
Y2178831D01*
X1959221D01*
G01X1959835Y2177333D02*
X1960755D01*
G01X1958038Y2178831D02*
X1957501Y2175731D01*
X1956888Y2178831D01*
X1956275Y2175731D01*
X1955738Y2178831D01*
G01X1954938Y2174698D02*
X1952638D01*
G01X1951493Y2176144D02*
X1951186Y2175886D01*
X1950841Y2175731D01*
X1950535D01*
X1950228Y2175886D01*
X1949998Y2176144D01*
X1949883Y2176506D01*
X1949960Y2176868D01*
X1950151Y2177178D01*
X1950496Y2177384D01*
X1950956Y2177488D01*
X1951225Y2177694D01*
X1951340Y2178056D01*
X1951263Y2178418D01*
X1951071Y2178676D01*
X1950803Y2178831D01*
X1950535D01*
X1950266Y2178728D01*
X1950036Y2178469D01*
G01X1948393Y2176144D02*
X1948086Y2175886D01*
X1947741Y2175731D01*
X1947435D01*
X1947128Y2175886D01*
X1946898Y2176144D01*
X1946783Y2176506D01*
X1946860Y2176868D01*
X1947051Y2177178D01*
X1947396Y2177384D01*
X1947856Y2177488D01*
X1948125Y2177694D01*
X1948240Y2178056D01*
X1948163Y2178418D01*
X1947971Y2178676D01*
X1947703Y2178831D01*
X1947435D01*
X1947166Y2178728D01*
X1946936Y2178469D01*
G01X1945331Y2175731D02*
Y2178831D01*
X1944565D01*
X1944258Y2178676D01*
X1944028Y2178469D01*
X1943836Y2178159D01*
X1943683Y2177798D01*
X1943645Y2177281D01*
X1943683Y2176764D01*
X1943836Y2176403D01*
X1944028Y2176093D01*
X1944258Y2175886D01*
X1944565Y2175731D01*
X1945331D01*
G01X1942116Y2177023D02*
X1941848Y2177384D01*
X1941618Y2177591D01*
X1941311Y2177694D01*
X1941043Y2177591D01*
X1940851Y2177384D01*
X1940698Y2177074D01*
X1940660Y2176713D01*
X1940698Y2176403D01*
X1940851Y2176093D01*
X1941081Y2175834D01*
X1941350Y2175731D01*
X1941656Y2175834D01*
X1941925Y2176144D01*
X1942078Y2176609D01*
X1942116Y2177126D01*
X1942040Y2177798D01*
X1941925Y2178159D01*
X1941733Y2178521D01*
X1941465Y2178779D01*
X1941196Y2178831D01*
X1940928Y2178728D01*
X1940736Y2178469D01*
G01X1939438Y2174698D02*
X1937138D01*
G01X1935188Y2175731D02*
Y2178831D01*
X1935648Y2178211D01*
G01Y2175731D02*
X1934728D01*
G01X1961793Y2176144D02*
X1961486Y2175886D01*
X1961141Y2175731D01*
X1960835D01*
X1960528Y2175886D01*
X1960298Y2176144D01*
X1960183Y2176506D01*
X1960260Y2176868D01*
X1960451Y2177178D01*
X1960796Y2177384D01*
X1961256Y2177488D01*
X1961525Y2177694D01*
X1961640Y2178056D01*
X1961563Y2178418D01*
X1961371Y2178676D01*
X1961103Y2178831D01*
X1960835D01*
X1960566Y2178728D01*
X1960336Y2178469D01*
G01X1957045Y2178573D02*
X1957275Y2178728D01*
X1957543Y2178831D01*
X1957850D01*
X1958195Y2178676D01*
X1958463Y2178418D01*
X1958655Y2178108D01*
X1958808Y2177591D01*
X1958846Y2177126D01*
X1958770Y2176661D01*
X1958655Y2176351D01*
X1958425Y2176041D01*
X1958156Y2175834D01*
X1957888Y2175731D01*
X1957620D01*
X1957351Y2175834D01*
X1957121Y2175989D01*
X1956930Y2176196D01*
G01X1955555Y2175731D02*
Y2178831D01*
X1954596D01*
X1954290Y2178676D01*
X1954098Y2178469D01*
X1954021Y2178056D01*
X1954098Y2177643D01*
X1954328Y2177384D01*
X1954596Y2177229D01*
X1955555D01*
G01X1954596D02*
X1954021Y2175731D01*
G01X1950921D02*
X1952455D01*
Y2178831D01*
X1950921D01*
G01X1951535Y2177333D02*
X1952455D01*
G01X1949738Y2178831D02*
X1949201Y2175731D01*
X1948588Y2178831D01*
X1947975Y2175731D01*
X1947438Y2178831D01*
G01X1946638Y2174698D02*
X1944338D01*
G01X1943193Y2176144D02*
X1942886Y2175886D01*
X1942541Y2175731D01*
X1942235D01*
X1941928Y2175886D01*
X1941698Y2176144D01*
X1941583Y2176506D01*
X1941660Y2176868D01*
X1941851Y2177178D01*
X1942196Y2177384D01*
X1942656Y2177488D01*
X1942925Y2177694D01*
X1943040Y2178056D01*
X1942963Y2178418D01*
X1942771Y2178676D01*
X1942503Y2178831D01*
X1942235D01*
X1941966Y2178728D01*
X1941736Y2178469D01*
G01X1940093Y2176144D02*
X1939786Y2175886D01*
X1939441Y2175731D01*
X1939135D01*
X1938828Y2175886D01*
X1938598Y2176144D01*
X1938483Y2176506D01*
X1938560Y2176868D01*
X1938751Y2177178D01*
X1939096Y2177384D01*
X1939556Y2177488D01*
X1939825Y2177694D01*
X1939940Y2178056D01*
X1939863Y2178418D01*
X1939671Y2178676D01*
X1939403Y2178831D01*
X1939135D01*
X1938866Y2178728D01*
X1938636Y2178469D01*
G01X1937031Y2175731D02*
Y2178831D01*
X1936265D01*
X1935958Y2178676D01*
X1935728Y2178469D01*
X1935536Y2178159D01*
X1935383Y2177798D01*
X1935345Y2177281D01*
X1935383Y2176764D01*
X1935536Y2176403D01*
X1935728Y2176093D01*
X1935958Y2175886D01*
X1936265Y2175731D01*
X1937031D01*
G01X1933816Y2177023D02*
X1933548Y2177384D01*
X1933318Y2177591D01*
X1933011Y2177694D01*
X1932743Y2177591D01*
X1932551Y2177384D01*
X1932398Y2177074D01*
X1932360Y2176713D01*
X1932398Y2176403D01*
X1932551Y2176093D01*
X1932781Y2175834D01*
X1933050Y2175731D01*
X1933356Y2175834D01*
X1933625Y2176144D01*
X1933778Y2176609D01*
X1933816Y2177126D01*
X1933740Y2177798D01*
X1933625Y2178159D01*
X1933433Y2178521D01*
X1933165Y2178779D01*
X1932896Y2178831D01*
X1932628Y2178728D01*
X1932436Y2178469D01*
G01X1931138Y2174698D02*
X1928838D01*
G01X1927616Y2178314D02*
X1927386Y2178624D01*
X1927118Y2178779D01*
X1926811Y2178831D01*
X1926428Y2178728D01*
X1926160Y2178469D01*
X1926083Y2178159D01*
X1926121Y2177849D01*
X1926275Y2177591D01*
X1927041Y2177074D01*
X1927386Y2176713D01*
X1927616Y2176196D01*
X1927693Y2175731D01*
X1926083D01*
G01X1958012Y2149622D02*
X1957820Y2149312D01*
X1957590Y2149105D01*
X1957322Y2149002D01*
X1957015Y2149105D01*
X1956785Y2149312D01*
X1956555Y2149622D01*
X1956478Y2150035D01*
Y2152102D01*
G01X1954988Y2149622D02*
X1954758Y2149260D01*
X1954452Y2149054D01*
X1954107Y2149002D01*
X1953800Y2149054D01*
X1953493Y2149312D01*
X1953302Y2149622D01*
X1953263Y2149932D01*
X1953340Y2150294D01*
X1953608Y2150552D01*
X1953877Y2150655D01*
X1954222D01*
G01X1953877D02*
X1953647Y2150810D01*
X1953455Y2151069D01*
X1953378Y2151379D01*
X1953455Y2151689D01*
X1953647Y2151947D01*
X1953992Y2152102D01*
X1954337Y2152050D01*
X1954682Y2151844D01*
G01X1951697Y2149364D02*
X1951428Y2149105D01*
X1951122Y2149002D01*
X1950815Y2149105D01*
X1950547Y2149415D01*
X1950355Y2149880D01*
X1950278Y2150345D01*
Y2150914D01*
X1950355Y2151379D01*
X1950547Y2151792D01*
X1950777Y2151999D01*
X1951045Y2152102D01*
X1951352Y2151999D01*
X1951582Y2151792D01*
X1951735Y2151482D01*
X1951812Y2151069D01*
X1951735Y2150707D01*
X1951543Y2150345D01*
X1951313Y2150139D01*
X1951045Y2150087D01*
X1950738Y2150190D01*
X1950508Y2150449D01*
X1950278Y2150914D01*
G01X1949095Y2147969D02*
X1946795D01*
G01X1944845Y2149002D02*
X1945152Y2149054D01*
X1945420Y2149260D01*
X1945650Y2149570D01*
X1945803Y2149932D01*
X1945880Y2150345D01*
Y2150759D01*
X1945803Y2151172D01*
X1945650Y2151534D01*
X1945420Y2151844D01*
X1945152Y2152050D01*
X1944845Y2152102D01*
X1944538Y2152050D01*
X1944270Y2151844D01*
X1944040Y2151534D01*
X1943887Y2151172D01*
X1943810Y2150759D01*
Y2150345D01*
X1943887Y2149932D01*
X1944040Y2149570D01*
X1944270Y2149260D01*
X1944538Y2149054D01*
X1944845Y2149002D01*
G01X1941745Y2152102D02*
Y2149002D01*
G01X1942627Y2152102D02*
X1940863D01*
G01X1939450Y2149002D02*
Y2152102D01*
G01X1937840D02*
Y2149002D01*
G01Y2150552D02*
X1939450D01*
G01X1968932Y2157307D02*
X1968625Y2157049D01*
X1968280Y2156894D01*
X1967974D01*
X1967667Y2157049D01*
X1967437Y2157307D01*
X1967322Y2157669D01*
X1967399Y2158031D01*
X1967590Y2158341D01*
X1967935Y2158547D01*
X1968395Y2158651D01*
X1968664Y2158857D01*
X1968779Y2159219D01*
X1968702Y2159581D01*
X1968510Y2159839D01*
X1968242Y2159994D01*
X1967974D01*
X1967705Y2159891D01*
X1967475Y2159632D01*
G01X1964184Y2159736D02*
X1964414Y2159891D01*
X1964682Y2159994D01*
X1964989D01*
X1965334Y2159839D01*
X1965602Y2159581D01*
X1965794Y2159271D01*
X1965947Y2158754D01*
X1965985Y2158289D01*
X1965909Y2157824D01*
X1965794Y2157514D01*
X1965564Y2157204D01*
X1965295Y2156997D01*
X1965027Y2156894D01*
X1964759D01*
X1964490Y2156997D01*
X1964260Y2157152D01*
X1964069Y2157359D01*
G01X1962694Y2156894D02*
Y2159994D01*
X1961735D01*
X1961429Y2159839D01*
X1961237Y2159632D01*
X1961160Y2159219D01*
X1961237Y2158806D01*
X1961467Y2158547D01*
X1961735Y2158392D01*
X1962694D01*
G01X1961735D02*
X1961160Y2156894D01*
G01X1958060D02*
X1959594D01*
Y2159994D01*
X1958060D01*
G01X1958674Y2158496D02*
X1959594D01*
G01X1956877Y2159994D02*
X1956340Y2156894D01*
X1955727Y2159994D01*
X1955114Y2156894D01*
X1954577Y2159994D01*
G01X1953777Y2155861D02*
X1951477D01*
G01X1949527Y2156894D02*
Y2159994D01*
X1949987Y2159374D01*
G01Y2156894D02*
X1949067D01*
G01X1959232Y2157307D02*
X1958925Y2157049D01*
X1958580Y2156894D01*
X1958274D01*
X1957967Y2157049D01*
X1957737Y2157307D01*
X1957622Y2157669D01*
X1957699Y2158031D01*
X1957890Y2158341D01*
X1958235Y2158547D01*
X1958695Y2158651D01*
X1958964Y2158857D01*
X1959079Y2159219D01*
X1959002Y2159581D01*
X1958810Y2159839D01*
X1958542Y2159994D01*
X1958274D01*
X1958005Y2159891D01*
X1957775Y2159632D01*
G01X1954484Y2159736D02*
X1954714Y2159891D01*
X1954982Y2159994D01*
X1955289D01*
X1955634Y2159839D01*
X1955902Y2159581D01*
X1956094Y2159271D01*
X1956247Y2158754D01*
X1956285Y2158289D01*
X1956209Y2157824D01*
X1956094Y2157514D01*
X1955864Y2157204D01*
X1955595Y2156997D01*
X1955327Y2156894D01*
X1955059D01*
X1954790Y2156997D01*
X1954560Y2157152D01*
X1954369Y2157359D01*
G01X1952994Y2156894D02*
Y2159994D01*
X1952035D01*
X1951729Y2159839D01*
X1951537Y2159632D01*
X1951460Y2159219D01*
X1951537Y2158806D01*
X1951767Y2158547D01*
X1952035Y2158392D01*
X1952994D01*
G01X1952035D02*
X1951460Y2156894D01*
G01X1948360D02*
X1949894D01*
Y2159994D01*
X1948360D01*
G01X1948974Y2158496D02*
X1949894D01*
G01X1947177Y2159994D02*
X1946640Y2156894D01*
X1946027Y2159994D01*
X1945414Y2156894D01*
X1944877Y2159994D01*
G01X1944077Y2155861D02*
X1941777D01*
G01X1940555Y2159477D02*
X1940325Y2159787D01*
X1940057Y2159942D01*
X1939750Y2159994D01*
X1939367Y2159891D01*
X1939099Y2159632D01*
X1939022Y2159322D01*
X1939060Y2159012D01*
X1939214Y2158754D01*
X1939980Y2158237D01*
X1940325Y2157876D01*
X1940555Y2157359D01*
X1940632Y2156894D01*
X1939022D01*
G01X1959029Y2167212D02*
X1958837Y2166902D01*
X1958607Y2166695D01*
X1958339Y2166592D01*
X1958032Y2166695D01*
X1957802Y2166902D01*
X1957572Y2167212D01*
X1957495Y2167625D01*
Y2169692D01*
G01X1956005Y2167212D02*
X1955775Y2166850D01*
X1955469Y2166644D01*
X1955124Y2166592D01*
X1954817Y2166644D01*
X1954510Y2166902D01*
X1954319Y2167212D01*
X1954280Y2167522D01*
X1954357Y2167884D01*
X1954625Y2168142D01*
X1954894Y2168245D01*
X1955239D01*
G01X1954894D02*
X1954664Y2168400D01*
X1954472Y2168659D01*
X1954395Y2168969D01*
X1954472Y2169279D01*
X1954664Y2169537D01*
X1955009Y2169692D01*
X1955354Y2169640D01*
X1955699Y2169434D01*
G01X1952062Y2166592D02*
Y2169692D01*
X1952522Y2169072D01*
G01Y2166592D02*
X1951602D01*
G01X1950112Y2165559D02*
X1947812D01*
G01X1945862Y2166592D02*
X1946169Y2166644D01*
X1946437Y2166850D01*
X1946667Y2167160D01*
X1946820Y2167522D01*
X1946897Y2167935D01*
Y2168349D01*
X1946820Y2168762D01*
X1946667Y2169124D01*
X1946437Y2169434D01*
X1946169Y2169640D01*
X1945862Y2169692D01*
X1945555Y2169640D01*
X1945287Y2169434D01*
X1945057Y2169124D01*
X1944904Y2168762D01*
X1944827Y2168349D01*
Y2167935D01*
X1944904Y2167522D01*
X1945057Y2167160D01*
X1945287Y2166850D01*
X1945555Y2166644D01*
X1945862Y2166592D01*
G01X1942762Y2169692D02*
Y2166592D01*
G01X1943644Y2169692D02*
X1941880D01*
G01X1940467Y2166592D02*
Y2169692D01*
G01X1938857D02*
Y2166592D01*
G01Y2168142D02*
X1940467D01*
G01X1982283Y2145080D02*
X1981976Y2144822D01*
X1981631Y2144667D01*
X1981325D01*
X1981018Y2144822D01*
X1980788Y2145080D01*
X1980673Y2145442D01*
X1980750Y2145804D01*
X1980941Y2146114D01*
X1981286Y2146320D01*
X1981746Y2146424D01*
X1982015Y2146630D01*
X1982130Y2146992D01*
X1982053Y2147354D01*
X1981861Y2147612D01*
X1981593Y2147767D01*
X1981325D01*
X1981056Y2147664D01*
X1980826Y2147405D01*
G01X1977535Y2147509D02*
X1977765Y2147664D01*
X1978033Y2147767D01*
X1978340D01*
X1978685Y2147612D01*
X1978953Y2147354D01*
X1979145Y2147044D01*
X1979298Y2146527D01*
X1979336Y2146062D01*
X1979260Y2145597D01*
X1979145Y2145287D01*
X1978915Y2144977D01*
X1978646Y2144770D01*
X1978378Y2144667D01*
X1978110D01*
X1977841Y2144770D01*
X1977611Y2144925D01*
X1977420Y2145132D01*
G01X1976045Y2144667D02*
Y2147767D01*
X1975086D01*
X1974780Y2147612D01*
X1974588Y2147405D01*
X1974511Y2146992D01*
X1974588Y2146579D01*
X1974818Y2146320D01*
X1975086Y2146165D01*
X1976045D01*
G01X1975086D02*
X1974511Y2144667D01*
G01X1971411D02*
X1972945D01*
Y2147767D01*
X1971411D01*
G01X1972025Y2146269D02*
X1972945D01*
G01X1970228Y2147767D02*
X1969691Y2144667D01*
X1969078Y2147767D01*
X1968465Y2144667D01*
X1967928Y2147767D01*
G01X1967128Y2143634D02*
X1964828D01*
G01X1963606Y2145959D02*
X1963338Y2146320D01*
X1963108Y2146527D01*
X1962801Y2146630D01*
X1962533Y2146527D01*
X1962341Y2146320D01*
X1962188Y2146010D01*
X1962150Y2145649D01*
X1962188Y2145339D01*
X1962341Y2145029D01*
X1962571Y2144770D01*
X1962840Y2144667D01*
X1963146Y2144770D01*
X1963415Y2145080D01*
X1963568Y2145545D01*
X1963606Y2146062D01*
X1963530Y2146734D01*
X1963415Y2147095D01*
X1963223Y2147457D01*
X1962955Y2147715D01*
X1962686Y2147767D01*
X1962418Y2147664D01*
X1962226Y2147405D01*
G01X1973912Y2149622D02*
X1973720Y2149312D01*
X1973490Y2149105D01*
X1973222Y2149002D01*
X1972915Y2149105D01*
X1972685Y2149312D01*
X1972455Y2149622D01*
X1972378Y2150035D01*
Y2152102D01*
G01X1970888Y2149622D02*
X1970658Y2149260D01*
X1970352Y2149054D01*
X1970007Y2149002D01*
X1969700Y2149054D01*
X1969393Y2149312D01*
X1969202Y2149622D01*
X1969163Y2149932D01*
X1969240Y2150294D01*
X1969508Y2150552D01*
X1969777Y2150655D01*
X1970122D01*
G01X1969777D02*
X1969547Y2150810D01*
X1969355Y2151069D01*
X1969278Y2151379D01*
X1969355Y2151689D01*
X1969547Y2151947D01*
X1969892Y2152102D01*
X1970237Y2152050D01*
X1970582Y2151844D01*
G01X1966945Y2149002D02*
X1966677Y2149054D01*
X1966370Y2149209D01*
X1966178Y2149467D01*
X1966102Y2149829D01*
X1966178Y2150190D01*
X1966408Y2150500D01*
X1966753Y2150655D01*
X1967137D01*
X1967367Y2150759D01*
X1967558Y2151017D01*
X1967635Y2151379D01*
X1967520Y2151740D01*
X1967252Y2151999D01*
X1966945Y2152102D01*
X1966638Y2151999D01*
X1966370Y2151740D01*
X1966255Y2151379D01*
X1966332Y2151017D01*
X1966523Y2150759D01*
X1966753Y2150655D01*
X1967137D01*
X1967482Y2150500D01*
X1967712Y2150190D01*
X1967788Y2149829D01*
X1967712Y2149467D01*
X1967520Y2149209D01*
X1967213Y2149054D01*
X1966945Y2149002D01*
G01X1964995Y2147969D02*
X1962695D01*
G01X1960745Y2149002D02*
X1961052Y2149054D01*
X1961320Y2149260D01*
X1961550Y2149570D01*
X1961703Y2149932D01*
X1961780Y2150345D01*
Y2150759D01*
X1961703Y2151172D01*
X1961550Y2151534D01*
X1961320Y2151844D01*
X1961052Y2152050D01*
X1960745Y2152102D01*
X1960438Y2152050D01*
X1960170Y2151844D01*
X1959940Y2151534D01*
X1959787Y2151172D01*
X1959710Y2150759D01*
Y2150345D01*
X1959787Y2149932D01*
X1959940Y2149570D01*
X1960170Y2149260D01*
X1960438Y2149054D01*
X1960745Y2149002D01*
G01X1957645Y2152102D02*
Y2149002D01*
G01X1958527Y2152102D02*
X1956763D01*
G01X1955350Y2149002D02*
Y2152102D01*
G01X1953740D02*
Y2149002D01*
G01Y2150552D02*
X1955350D01*
G01X1982283Y2154780D02*
X1981976Y2154522D01*
X1981631Y2154367D01*
X1981325D01*
X1981018Y2154522D01*
X1980788Y2154780D01*
X1980673Y2155142D01*
X1980750Y2155504D01*
X1980941Y2155814D01*
X1981286Y2156020D01*
X1981746Y2156124D01*
X1982015Y2156330D01*
X1982130Y2156692D01*
X1982053Y2157054D01*
X1981861Y2157312D01*
X1981593Y2157467D01*
X1981325D01*
X1981056Y2157364D01*
X1980826Y2157105D01*
G01X1977535Y2157209D02*
X1977765Y2157364D01*
X1978033Y2157467D01*
X1978340D01*
X1978685Y2157312D01*
X1978953Y2157054D01*
X1979145Y2156744D01*
X1979298Y2156227D01*
X1979336Y2155762D01*
X1979260Y2155297D01*
X1979145Y2154987D01*
X1978915Y2154677D01*
X1978646Y2154470D01*
X1978378Y2154367D01*
X1978110D01*
X1977841Y2154470D01*
X1977611Y2154625D01*
X1977420Y2154832D01*
G01X1976045Y2154367D02*
Y2157467D01*
X1975086D01*
X1974780Y2157312D01*
X1974588Y2157105D01*
X1974511Y2156692D01*
X1974588Y2156279D01*
X1974818Y2156020D01*
X1975086Y2155865D01*
X1976045D01*
G01X1975086D02*
X1974511Y2154367D01*
G01X1971411D02*
X1972945D01*
Y2157467D01*
X1971411D01*
G01X1972025Y2155969D02*
X1972945D01*
G01X1970228Y2157467D02*
X1969691Y2154367D01*
X1969078Y2157467D01*
X1968465Y2154367D01*
X1967928Y2157467D01*
G01X1967128Y2153334D02*
X1964828D01*
G01X1962878Y2157467D02*
X1963185Y2157364D01*
X1963415Y2157105D01*
X1963568Y2156795D01*
X1963683Y2156382D01*
X1963721Y2155917D01*
X1963683Y2155452D01*
X1963568Y2155039D01*
X1963415Y2154729D01*
X1963185Y2154470D01*
X1962878Y2154367D01*
X1962571Y2154470D01*
X1962341Y2154729D01*
X1962188Y2155039D01*
X1962073Y2155452D01*
X1962035Y2155917D01*
X1962073Y2156382D01*
X1962188Y2156795D01*
X1962341Y2157105D01*
X1962571Y2157364D01*
X1962878Y2157467D01*
G01X1991983Y2145080D02*
X1991676Y2144822D01*
X1991331Y2144667D01*
X1991025D01*
X1990718Y2144822D01*
X1990488Y2145080D01*
X1990373Y2145442D01*
X1990450Y2145804D01*
X1990641Y2146114D01*
X1990986Y2146320D01*
X1991446Y2146424D01*
X1991715Y2146630D01*
X1991830Y2146992D01*
X1991753Y2147354D01*
X1991561Y2147612D01*
X1991293Y2147767D01*
X1991025D01*
X1990756Y2147664D01*
X1990526Y2147405D01*
G01X1987235Y2147509D02*
X1987465Y2147664D01*
X1987733Y2147767D01*
X1988040D01*
X1988385Y2147612D01*
X1988653Y2147354D01*
X1988845Y2147044D01*
X1988998Y2146527D01*
X1989036Y2146062D01*
X1988960Y2145597D01*
X1988845Y2145287D01*
X1988615Y2144977D01*
X1988346Y2144770D01*
X1988078Y2144667D01*
X1987810D01*
X1987541Y2144770D01*
X1987311Y2144925D01*
X1987120Y2145132D01*
G01X1985745Y2144667D02*
Y2147767D01*
X1984786D01*
X1984480Y2147612D01*
X1984288Y2147405D01*
X1984211Y2146992D01*
X1984288Y2146579D01*
X1984518Y2146320D01*
X1984786Y2146165D01*
X1985745D01*
G01X1984786D02*
X1984211Y2144667D01*
G01X1981111D02*
X1982645D01*
Y2147767D01*
X1981111D01*
G01X1981725Y2146269D02*
X1982645D01*
G01X1979928Y2147767D02*
X1979391Y2144667D01*
X1978778Y2147767D01*
X1978165Y2144667D01*
X1977628Y2147767D01*
G01X1976828Y2143634D02*
X1974528D01*
G01X1973421Y2145132D02*
X1973191Y2144874D01*
X1972923Y2144719D01*
X1972578Y2144667D01*
X1972233Y2144770D01*
X1971965Y2144977D01*
X1971773Y2145339D01*
X1971735Y2145752D01*
X1971811Y2146165D01*
X1972003Y2146424D01*
X1972271Y2146630D01*
X1972540Y2146682D01*
X1972808Y2146630D01*
X1973153Y2146424D01*
X1973038Y2147767D01*
X1972003D01*
G01X1995083Y2154367D02*
Y2157467D01*
G01X1993473D02*
Y2154367D01*
G01Y2155917D02*
X1995083D01*
G01X1992136Y2154367D02*
X1991178Y2157467D01*
X1990220Y2154367D01*
G01X1990565Y2155452D02*
X1991791D01*
G01X1988960Y2154367D02*
Y2157467D01*
X1987196Y2154367D01*
Y2157467D01*
G01X1985821Y2154367D02*
Y2157467D01*
X1985055D01*
X1984748Y2157312D01*
X1984518Y2157105D01*
X1984326Y2156795D01*
X1984173Y2156434D01*
X1984135Y2155917D01*
X1984173Y2155400D01*
X1984326Y2155039D01*
X1984518Y2154729D01*
X1984748Y2154522D01*
X1985055Y2154367D01*
X1985821D01*
G01X1982645Y2157467D02*
Y2154367D01*
X1981111D01*
G01X1978011D02*
X1979545D01*
Y2157467D01*
X1978011D01*
G01X1978625Y2155969D02*
X1979545D01*
G01X1976828Y2153334D02*
X1974528D01*
G01X1972578Y2154367D02*
Y2157467D01*
X1973038Y2156847D01*
G01Y2154367D02*
X1972118D01*
M02*
